# Altium SchDoc records: 03-POWER.SchDoc
|HEADER=Protel for Windows - Schematic Capture Binary File Version 5.0|Weight=4711|MinorVersion=6
|RECORD=31|FontIdCount=8|Size1=10|FontName1=Times New Roman|Size2=10|Rotation2=90|FontName2=Times New Roman|Size3=8|FontName3=Arial|Size4=10|FontName4=Arial|Size5=12|Underline5=T|FontName5=Arial|Size6=11|FontName6=Arial|Size7=10|Underline7=T|FontName7=Times New Roman|Size8=12|FontName8=Arial|UseMBCS=T|IsBOC=T|HotSpotGridOn=T|HotSpotGridSize=2|SheetStyle=12|SystemFont=4|BorderOn=T|SheetNumberSpaceSize=12|AreaColor=16317695|SnapGridOn=T|SnapGridSize=5|VisibleGridOn=T|VisibleGridSize=10|CustomX=2338|CustomX_Frac=58268|CustomY=1653|CustomY_Frac=54331|CustomXZones=8|CustomYZones=6|CustomMarginWidth=19|CustomMarginWidth_Frac=80000|ShowTemplateGraphics=T|TemplateFileName=C:\Users\<user>\Documents\Altium\AD20\Templates\Timecard.SchDot|Display_Unit=0
|RECORD=39|IsNotAccesible=T|OwnerPartId=-1|FileName=C:\Users\<user>\Documents\Altium\AD20\Templates\Timecard.SchDot
|RECORD=4|OwnerIndex=1|OwnerPartId=-1|Location.X=1594|Location.Y=39|Color=8388608|FontID=5|Text=timingcard.com|URL=http://timingcard.com
|RECORD=6|OwnerIndex=1|IndexInSheet=1|OwnerPartId=-1|LocationCount=2|X1=1680|Y1=35|X2=1576|Y2=35
|RECORD=4|OwnerIndex=1|IndexInSheet=2|OwnerPartId=-1|Location.X=1615|Location.Y=27|Justification=4|Color=16711680|FontID=6|Text==SheetNumber
|RECORD=4|OwnerIndex=1|IndexInSheet=3|OwnerPartId=-1|Location.X=1581|Location.X_Frac=42446|Location.Y=29|Location.Y_Frac=96838|Justification=3|FontID=3|Text=SHEET
|RECORD=4|OwnerIndex=1|IndexInSheet=4|OwnerPartId=-1|Location.X=1639|Location.X_Frac=42446|Location.Y=29|Location.Y_Frac=96838|Justification=3|FontID=3|Text=OF
|RECORD=6|OwnerIndex=1|IndexInSheet=5|OwnerPartId=-1|LineWidth=1|LocationCount=2|X1=1679|X1_Frac=42446|Y1=117|Y1_Frac=96838|X2=1576|Y2=118
|RECORD=4|OwnerIndex=1|IndexInSheet=6|OwnerPartId=-1|Location.X=1659|Location.Y=27|Justification=4|Color=16711680|FontID=6|Text==SheetTotal
|RECORD=30|OwnerIndex=1|IndexInSheet=7|OwnerPartId=-1|Location.X=1578|Location.Y=65|Corner.X=1673|Corner.X_Frac=88801|Corner.Y=115|KeepAspect=T|FileName=C:\Users\<user>\Desktop\Timecard Logo\TIMECARD.jpg
|RECORD=6|OwnerIndex=1|IndexInSheet=8|OwnerPartId=-1|LineWidth=1|LocationCount=2|X1=1576|X1_Frac=3162|Y1=117|Y1_Frac=42446|X2=1576|Y2=21
|RECORD=6|OwnerIndex=1|IndexInSheet=9|OwnerPartId=-1|LocationCount=2|X1=1680|Y1=51|X2=1576|Y2=51
|RECORD=4|OwnerIndex=1|IndexInSheet=10|OwnerPartId=-1|Location.X=1581|Location.X_Frac=42446|Location.Y=56|Location.Y_Frac=96838|Justification=3|FontID=3|Text=REV
|RECORD=4|OwnerIndex=1|IndexInSheet=11|OwnerPartId=-1|Location.X=1619|Location.Y=57|Justification=3|FontID=3|Text=DATE
|RECORD=6|OwnerIndex=1|IndexInSheet=12|OwnerPartId=-1|LocationCount=2|X1=1680|Y1=65|X2=1576|Y2=65
|RECORD=4|OwnerIndex=1|IndexInSheet=13|OwnerPartId=-1|Location.X=1605|Location.Y=58|Justification=4|Color=16711680|FontID=6|Text==ProjectRevision
|RECORD=4|OwnerIndex=1|IndexInSheet=14|OwnerPartId=-1|Location.X=1659|Location.Y=58|Justification=4|Color=16711680|FontID=6|Text==ProjectDate
|RECORD=41|IndexInSheet=1|OwnerPartId=-1|Location.X=21474|Location.X_Frac=83647|Location.Y=21464|Location.Y_Frac=83647|Color=8388608|FontID=1|IsHidden=T|Text=01910|Name=Customer
|RECORD=41|IndexInSheet=2|OwnerPartId=-1|Location.X=1000|Location.Y=10|Color=8388608|FontID=1|IsHidden=T|Text=*|Name=DocStatus
|RECORD=17|IndexInSheet=3|OwnerPartId=-1|ShowNetName=T|Location.X=602|Location.Y=937|Orientation=1|Color=128|FontID=1|Text=+12V
|RECORD=17|IndexInSheet=4|OwnerPartId=-1|Style=4|ShowNetName=T|Location.X=600|Location.Y=805|Orientation=3|Color=128|FontID=1|Text=GND
|RECORD=17|IndexInSheet=5|OwnerPartId=-1|ShowNetName=T|Location.X=1425|Location.Y=430|Orientation=1|Color=128|FontID=1|Text=+3.3V
|RECORD=17|IndexInSheet=6|OwnerPartId=-1|Style=4|ShowNetName=T|Location.X=1425|Location.Y=250|Orientation=3|Color=128|FontID=1|Text=GND
|RECORD=1|LibReference=CAP_0805_10UF_25V|ComponentDescription=CAP, CER, 10.UF, 25V, 10%, X5R, 0805|PartCount=2|DisplayModeCount=1|IndexInSheet=7|OwnerPartId=-1|Location.X=532|Location.Y=827|CurrentPartId=1|LibraryPath=*|SourceLibraryName=Capacitors.IntLib|TargetFileName=*|AreaColor=11599871|Color=128|PartIDLocked=F|DesignItemId=CAP_0805_10UF_25V|AllPinCount=2
|RECORD=41|OwnerIndex=23|OwnerPartId=-1|Location.X=532|Location.Y=827|Color=8388608|FontID=8|IsHidden=T|Text=TAIYO YUDEN|Name=MFG NAME
|RECORD=41|OwnerIndex=23|IndexInSheet=1|OwnerPartId=-1|Location.X=532|Location.Y=827|Color=8388608|FontID=8|IsHidden=T|Text=TMK212BBJ106KG-T|Name=MFG PART NUM
|RECORD=41|OwnerIndex=23|IndexInSheet=2|OwnerPartId=-1|Location.X=532|Location.Y=827|Color=8388608|FontID=8|IsHidden=T|Text=10/23/2013|Name=MODIFY DATE
|RECORD=41|OwnerIndex=23|IndexInSheet=3|OwnerPartId=-1|Location.X=532|Location.Y=827|Color=8388608|FontID=8|IsHidden=T|Text=CAP, CER|Name=CATEGORY
|RECORD=41|OwnerIndex=23|IndexInSheet=4|OwnerPartId=-1|Location.X=530|Location.Y=839|Location.Y_Frac=50000|Color=8388608|FontID=8|IsHidden=T|Text=4/11/2006 3:37:28 PM|Name=Date
|RECORD=41|OwnerIndex=23|IndexInSheet=5|OwnerPartId=-1|Location.X=538|Location.Y=901|Location.Y_Frac=48252|Color=8388608|FontID=8|IsHidden=T|Text=*|Name=SHEETPART
|RECORD=41|OwnerIndex=23|IndexInSheet=6|OwnerPartId=-1|Location.X=538|Location.Y=901|Location.Y_Frac=48252|Color=8388608|FontID=8|IsHidden=T|Text=10%|Name=P1
|RECORD=41|OwnerIndex=23|IndexInSheet=7|OwnerPartId=-1|Location.X=538|Location.Y=901|Location.Y_Frac=48252|Color=8388608|FontID=8|IsHidden=T|Text=85C|Name=MAXTEMP
|RECORD=41|OwnerIndex=23|IndexInSheet=8|OwnerPartId=-1|Location.X=538|Location.Y=901|Location.Y_Frac=48252|Color=8388608|FontID=8|IsHidden=T|Text=-55C|Name=MINTEMP
|RECORD=41|OwnerIndex=23|IndexInSheet=9|OwnerPartId=-1|Location.X=538|Location.Y=901|Location.Y_Frac=48252|Color=8388608|FontID=8|IsHidden=T|Name=OTHER
|RECORD=41|OwnerIndex=23|IndexInSheet=10|OwnerPartId=-1|Location.X=538|Location.Y=901|Location.Y_Frac=48252|Color=8388608|FontID=8|IsHidden=T|Text=25V|Name=P2
|RECORD=41|OwnerIndex=23|IndexInSheet=11|OwnerPartId=-1|Location.X=538|Location.Y=901|Location.Y_Frac=48252|Color=8388608|FontID=8|IsHidden=T|Text=X5R|Name=P3
|RECORD=41|OwnerIndex=23|IndexInSheet=12|OwnerPartId=-1|Location.X=538|Location.Y=901|Location.Y_Frac=48252|Color=8388608|FontID=8|IsHidden=T|Text=0805|Name=Size
|RECORD=41|OwnerIndex=23|IndexInSheet=13|OwnerPartId=-1|Location.X=538|Location.Y=901|Location.Y_Frac=48252|Color=8388608|FontID=8|IsHidden=T|Name=SUB
|RECORD=41|OwnerIndex=23|IndexInSheet=14|OwnerPartId=-1|Location.X=538|Location.Y=901|Location.Y_Frac=48252|Color=8388608|FontID=1|IsHidden=T|Text=CAP, CER, 10.UF, 10V, 10%, X5R, 0805|Name=DESC
|RECORD=41|OwnerIndex=23|IndexInSheet=15|OwnerPartId=-1|Location.X=538|Location.Y=900|Location.Y_Frac=98252|Color=8388608|FontID=1|IsHidden=T|Text=MOUSER|Name=Supplier 1|ReadOnlyState=1
|RECORD=41|OwnerIndex=23|IndexInSheet=16|OwnerPartId=-1|Location.X=538|Location.Y=900|Location.Y_Frac=98252|Color=8388608|FontID=1|IsHidden=T|Text=963-TMK212BBJ106KG-T|Name=Supplier Part Number 1|ReadOnlyState=1
|RECORD=41|OwnerIndex=23|IndexInSheet=17|OwnerPartId=-1|Location.X=562|Location.Y=857|Color=8388608|FontID=8|Text=10uF|Name=VALUE
|RECORD=2|OwnerIndex=23|OwnerPartId=1|FormalType=1|Electrical=4|PinConglomerate=35|PinLength=10|Location.X=552|Location.Y=857|Name=2|Designator=2|SwapIdPin=2|SwapIDPart=1|PinPropagationDelay=0.000000E+000
|RECORD=2|OwnerIndex=23|OwnerPartId=1|FormalType=1|Electrical=4|PinConglomerate=33|PinLength=10|Location.X=552|Location.Y=867|Name=1|Designator=1|SwapIdPin=1|SwapIDPart=1|PinPropagationDelay=0.000000E+000
|RECORD=13|OwnerIndex=23|IsNotAccesible=T|IndexInSheet=20|OwnerPartId=1|Location.X=552|Location.Y=859|Location.Y_Frac=50000|Corner.X=552|Corner.Y=857|LineWidth=1|Color=16711680
|RECORD=13|OwnerIndex=23|IsNotAccesible=T|IndexInSheet=21|OwnerPartId=1|Location.X=552|Location.Y=867|Corner.X=552|Corner.Y=864|Corner.Y_Frac=50000|LineWidth=1|Color=16711680
|RECORD=13|OwnerIndex=23|IsNotAccesible=T|IndexInSheet=22|OwnerPartId=1|Location.X=557|Location.Y=859|Location.Y_Frac=50000|Corner.X=547|Corner.Y=859|Corner.Y_Frac=50000|LineWidth=1|Color=16711680
|RECORD=13|OwnerIndex=23|IsNotAccesible=T|IndexInSheet=23|OwnerPartId=1|Location.X=557|Location.Y=864|Location.Y_Frac=50000|Corner.X=547|Corner.Y=864|Corner.Y_Frac=50000|LineWidth=1|Color=16711680
|RECORD=41|OwnerIndex=23|IndexInSheet=24|OwnerPartId=-1|Location.X=538|Location.Y=900|Location.Y_Frac=98951|Color=8388608|FontID=1|IsHidden=T|Text=<VALENTIUM>|Name=VALENTIUM PART NUM
|RECORD=34|OwnerIndex=23|IndexInSheet=-1|OwnerPartId=-1|Location.X=562|Location.Y=867|Color=8388608|FontID=1|Text=C1|Name=Designator|ReadOnlyState=1
|RECORD=41|OwnerIndex=23|IndexInSheet=-1|OwnerPartId=-1|Location.X=559|Location.X_Frac=50000|Location.Y=822|Color=8388608|FontID=1|IsHidden=T|Text=CAP_0805_10UF_25V|Name=Comment
|RECORD=44|OwnerIndex=23
|RECORD=45|OwnerIndex=53|IndexInSheet=-1|Description=Chip Capacitor, 0805, 2-Leads, Body 2.00x1.25mm, IPC Medium Density|UseComponentLibrary=T|ModelName=CAPC2012X14N|ModelType=PCBLIB|DatafileCount=1|ModelDatafileEntity0=CAPC2012X14N|ModelDatafileKind0=PCBLib|IsCurrent=T|DatalinksLocked=T|DatabaseDatalinksLocked=T|IntegratedModel=T|DatabaseModel=T
|RECORD=46|OwnerIndex=54
|RECORD=48|OwnerIndex=54
|RECORD=1|LibReference=FUSE_0603_2.00A|ComponentDescription=FUSE SLOW 5.00A 32V M 0603|PartCount=2|DisplayModeCount=1|IndexInSheet=8|OwnerPartId=-1|Location.X=320|Location.Y=915|CurrentPartId=1|LibraryPath=*|SourceLibraryName=Passives.IntLib|TargetFileName=*|AreaColor=11599871|Color=128|PartIDLocked=F|DesignItemId=FUSE_0603_2.00A|AllPinCount=2
|RECORD=41|OwnerIndex=57|OwnerPartId=-1|Location.X=320|Location.Y=880|Color=8388608|FontID=8|Text=SF-0603S500-2|Name=MFG PART NUM
|RECORD=41|OwnerIndex=57|IndexInSheet=1|OwnerPartId=-1|Location.X=320|Location.Y=915|Color=8388608|FontID=8|IsHidden=T|Text=9/4/2013|Name=MODIFY DATE
|RECORD=41|OwnerIndex=57|IndexInSheet=2|OwnerPartId=-1|Location.X=320|Location.Y=915|Color=8388608|FontID=8|IsHidden=T|Text=BOURNS|Name=MFG NAME
|RECORD=41|OwnerIndex=57|IndexInSheet=3|OwnerPartId=-1|Location.X=320|Location.Y=915|Color=8388608|FontID=8|IsHidden=T|Text=FUSE|Name=CATEGORY
|RECORD=41|OwnerIndex=57|IndexInSheet=4|OwnerPartId=-1|Location.X=318|Location.Y=932|Color=8388608|FontID=8|IsHidden=T|Text=20 OCT 15|Name=DATE
|RECORD=41|OwnerIndex=57|IndexInSheet=5|OwnerPartId=-1|Location.X=318|Location.Y=932|Color=8388608|FontID=8|IsHidden=T|Text=105C|Name=MAXTEMP
|RECORD=41|OwnerIndex=57|IndexInSheet=6|OwnerPartId=-1|Location.X=318|Location.Y=932|Color=8388608|FontID=8|IsHidden=T|Text=-40C|Name=MINTEMP
|RECORD=41|OwnerIndex=57|IndexInSheet=7|OwnerPartId=-1|Location.X=318|Location.Y=932|Color=8388608|FontID=8|IsHidden=T|Text=UL E141069|Name=OTHER
|RECORD=41|OwnerIndex=57|IndexInSheet=8|OwnerPartId=-1|Location.X=318|Location.Y=932|Color=8388608|FontID=8|IsHidden=T|Text=SLOW BLO|Name=P1
|RECORD=41|OwnerIndex=57|IndexInSheet=9|OwnerPartId=-1|Location.X=318|Location.Y=932|Color=8388608|FontID=8|IsHidden=T|Text=32V|Name=P2
|RECORD=41|OwnerIndex=57|IndexInSheet=10|OwnerPartId=-1|Location.X=318|Location.Y=932|Color=8388608|FontID=8|IsHidden=T|Text=M|Name=P3
|RECORD=41|OwnerIndex=57|IndexInSheet=11|OwnerPartId=-1|Location.X=318|Location.Y=932|Color=8388608|FontID=8|IsHidden=T|Text=0603|Name=SIZE
|RECORD=41|OwnerIndex=57|IndexInSheet=12|OwnerPartId=-1|Location.X=318|Location.Y=932|Color=8388608|FontID=8|IsHidden=T|Name=SUB
|RECORD=41|OwnerIndex=57|IndexInSheet=13|OwnerPartId=-1|Location.X=318|Location.Y=888|Color=8388608|FontID=1|IsHidden=T|Text=*|Name=SHEETPART
|RECORD=41|OwnerIndex=57|IndexInSheet=14|OwnerPartId=-1|Location.X=318|Location.Y=936|Color=8388608|FontID=1|IsHidden=T|Text=FUSE SLOW 1.25A 32V M 0603|Name=DESC
|RECORD=41|OwnerIndex=57|IndexInSheet=15|OwnerPartId=-1|Location.X=318|Location.Y=936|Color=8388608|FontID=1|IsHidden=T|Text=<VALENTIUM>|Name=VALENTIUM PART NUM
|RECORD=2|OwnerIndex=57|OwnerPartId=1|FormalType=1|Electrical=4|PinConglomerate=34|PinLength=20|Location.X=340|Location.Y=915|Name=1|Designator=1|SwapIdPin=1|SwapIDPart=1|PinPropagationDelay=0.000000E+000
|RECORD=2|OwnerIndex=57|OwnerPartId=1|FormalType=1|Electrical=4|PinConglomerate=32|PinLength=20|Location.X=360|Location.Y=915|Name=2|Designator=2|SwapIdPin=2|SwapIDPart=1|PinPropagationDelay=0.000000E+000
|RECORD=12|OwnerIndex=57|IsNotAccesible=T|IndexInSheet=18|OwnerPartId=1|Location.X=355|Location.Y=915|Radius=5|LineWidth=1|StartAngle=180.000|Color=16711680
|RECORD=12|OwnerIndex=57|IsNotAccesible=T|IndexInSheet=19|OwnerPartId=1|Location.X=345|Location.Y=915|Radius=5|LineWidth=1|EndAngle=180.000|Color=16711680
|RECORD=41|OwnerIndex=57|IndexInSheet=20|OwnerPartId=-1|Location.X=338|Location.Y=893|Color=8388608|FontID=8|Text=5.00A|Name=VALUE
|RECORD=8|OwnerIndex=57|IsNotAccesible=T|IndexInSheet=21|OwnerPartId=1|Location.X=340|Location.Y=915|Radius=2|SecondaryRadius=2|LineWidth=1|Color=16711680|AreaColor=16777215|IsSolid=T
|RECORD=8|OwnerIndex=57|IsNotAccesible=T|IndexInSheet=22|OwnerPartId=1|Location.X=360|Location.Y=915|Radius=2|SecondaryRadius=2|LineWidth=1|Color=16711680|AreaColor=16777215|IsSolid=T
|RECORD=41|OwnerIndex=57|IndexInSheet=23|OwnerPartId=-1|Location.X=318|Location.Y=930|Color=8388608|FontID=1|IsHidden=T|Text=Digi-Key|Name=Supplier 1|ReadOnlyState=3
|RECORD=41|OwnerIndex=57|IndexInSheet=24|OwnerPartId=-1|Location.X=318|Location.Y=930|Color=8388608|FontID=1|Text=SF-0603S500-2CT-ND|Name=Supplier Part Number 1|ReadOnlyState=3
|RECORD=34|OwnerIndex=57|IndexInSheet=-1|OwnerPartId=-1|Location.X=338|Location.Y=920|Color=8388608|FontID=1|Text=F1|Name=Designator|ReadOnlyState=1
|RECORD=41|OwnerIndex=57|IndexInSheet=-1|OwnerPartId=-1|Location.X=360|Location.Y=892|Location.Y_Frac=10000|Color=8388608|FontID=1|IsHidden=T|Text=FUSE_0603_5.00A|Name=Comment
|RECORD=44|OwnerIndex=57
|RECORD=45|OwnerIndex=87|IndexInSheet=-1|Description=Chip Fuse, 0603, 2-Leads, Body 1.60x0.81mm, IPC Medium Density|UseComponentLibrary=T|ModelName=FUSM1608X60N|ModelType=PCBLIB|DatafileCount=1|ModelDatafileEntity0=FUSM1608X60N|ModelDatafileKind0=PCBLib|IsCurrent=T|DatalinksLocked=T|DatabaseDatalinksLocked=T|IntegratedModel=T|DatabaseModel=T
|RECORD=46|OwnerIndex=88
|RECORD=48|OwnerIndex=88
|RECORD=1|LibReference=CAP|ComponentDescription=C0603X104K5RACAUTO|PartCount=2|DisplayModeCount=2|IndexInSheet=9|OwnerPartId=-1|Location.X=592|Location.Y=857|Orientation=1|CurrentPartId=1|SourceLibraryName=Altium Content Vault|TargetFileName=*|AreaColor=11599871|Color=128|PartIDLocked=F|DesignItemId=CMP-2006-00003-1|AllPinCount=2
|RECORD=2|OwnerIndex=91|OwnerPartId=1|OwnerPartDisplayMode=1|FormalType=1|Electrical=4|PinConglomerate=35|PinLength=10|Location.X=602|Location.Y=857|Name=1|Designator=1|PinPropagationDelay=0.000000E+000
|RECORD=2|OwnerIndex=91|OwnerPartId=1|OwnerPartDisplayMode=1|FormalType=1|Electrical=4|PinConglomerate=33|PinLength=10|Location.X=602|Location.Y=867|Name=2|Designator=2|PinPropagationDelay=0.000000E+000
|RECORD=13|OwnerIndex=91|IsNotAccesible=T|IndexInSheet=2|OwnerPartId=1|OwnerPartDisplayMode=1|Location.X=610|Location.Y=857|Corner.X=594|Corner.Y=857|LineWidth=1|Color=16711680
|RECORD=13|OwnerIndex=91|IsNotAccesible=T|IndexInSheet=3|OwnerPartId=1|OwnerPartDisplayMode=1|Location.X=602|Location.Y=861|Corner.X=602|Corner.Y=867|LineWidth=1|Color=16711680
|RECORD=12|OwnerIndex=91|IsNotAccesible=T|IndexInSheet=4|OwnerPartId=1|OwnerPartDisplayMode=1|Location.X=602|Location.Y=877|Radius=16|LineWidth=1|StartAngle=241.000|EndAngle=270.000|Color=16711680
|RECORD=12|OwnerIndex=91|IsNotAccesible=T|IndexInSheet=5|OwnerPartId=1|OwnerPartDisplayMode=1|Location.X=602|Location.Y=877|Radius=16|LineWidth=1|StartAngle=270.000|EndAngle=299.000|Color=16711680
|RECORD=2|OwnerIndex=91|OwnerPartId=1|FormalType=1|Electrical=4|PinConglomerate=35|PinLength=10|Location.X=602|Location.Y=857|Name=1|Designator=1|PinPropagationDelay=0.000000E+000
|RECORD=2|OwnerIndex=91|OwnerPartId=1|FormalType=1|Electrical=4|PinConglomerate=33|PinLength=10|Location.X=602|Location.Y=867|Name=2|Designator=2|PinPropagationDelay=0.000000E+000
|RECORD=13|OwnerIndex=91|IsNotAccesible=T|IndexInSheet=8|OwnerPartId=1|Location.X=594|Location.Y=864|Corner.X=610|Corner.Y=864|LineWidth=1|Color=16711680
|RECORD=13|OwnerIndex=91|IsNotAccesible=T|IndexInSheet=9|OwnerPartId=1|Location.X=610|Location.Y=860|Corner.X=594|Corner.Y=860|LineWidth=1|Color=16711680
|RECORD=6|OwnerIndex=91|IsNotAccesible=T|IndexInSheet=10|OwnerPartId=1|LineWidth=1|Color=16711680|LocationCount=2|X1=602|Y1=857|X2=602|Y2=860
|RECORD=6|OwnerIndex=91|IsNotAccesible=T|IndexInSheet=11|OwnerPartId=1|LineWidth=1|Color=16711680|LocationCount=2|X1=602|Y1=867|X2=602|Y2=864
|RECORD=41|OwnerIndex=91|IndexInSheet=12|OwnerPartId=-1|Location.X=593|Location.Y=879|Color=8388608|FontID=1|IsHidden=T|Text=Kemet|Name=Manufacturer
|RECORD=41|OwnerIndex=91|IndexInSheet=13|OwnerPartId=-1|Location.X=593|Location.Y=879|Color=8388608|FontID=1|IsHidden=T|Text=C0603X104K5RACAUTO|Name=Part Number
|RECORD=34|OwnerIndex=91|IndexInSheet=-1|OwnerPartId=-1|Location.X=611|Location.Y=858|Color=8388608|FontID=1|Text=C2|Name=Designator|ReadOnlyState=1
|RECORD=41|OwnerIndex=91|IndexInSheet=-1|OwnerPartId=-1|Location.X=611|Location.Y=848|Color=8388608|FontID=1|Text=0.1uF|Name=Comment
|RECORD=44|OwnerIndex=91
|RECORD=45|OwnerIndex=112|IndexInSheet=-1|Description=Chip Capacitor, 2-Leads, Body 1.60x0.80mm, IPC Low Density|UseComponentLibrary=T|ModelName=CAPC1608X87X45ML20T05|ModelType=PCBLIB|DatafileCount=1|ModelDatafileEntity0=CAPC1608X87X45ML20T05|ModelDatafileKind0=PCBLib|IsCurrent=T|DatalinksLocked=T|DatabaseDatalinksLocked=T
|RECORD=46|OwnerIndex=113
|RECORD=48|OwnerIndex=113
|RECORD=41|OwnerIndex=115|IndexInSheet=-1|OwnerPartId=-1|Color=8388608|FontID=1|Text=2D|Name=Available Preview Images
|RECORD=45|OwnerIndex=112|IndexInSheet=-1|Description=Chip Capacitor, 2-Leads, Body 1.60x0.80mm, IPC High Density|UseComponentLibrary=T|ModelName=CAPC1608X87X45LL20T05|ModelType=PCBLIB|DatafileCount=1|ModelDatafileEntity0=CAPC1608X87X45LL20T05|ModelDatafileKind0=PCBLib|DatalinksLocked=T|DatabaseDatalinksLocked=T
|RECORD=46|OwnerIndex=117
|RECORD=48|OwnerIndex=117
|RECORD=41|OwnerIndex=119|IndexInSheet=-1|OwnerPartId=-1|Color=8388608|FontID=1|Text=2D|Name=Available Preview Images
|RECORD=45|OwnerIndex=112|IndexInSheet=-1|Description=Chip Capacitor, 2-Leads, Body 1.60x0.80mm, IPC Medium Density|UseComponentLibrary=T|ModelName=CAPC1608X87X45NL20T05|ModelType=PCBLIB|DatafileCount=1|ModelDatafileEntity0=CAPC1608X87X45NL20T05|ModelDatafileKind0=PCBLib|DatalinksLocked=T|DatabaseDatalinksLocked=T
|RECORD=46|OwnerIndex=121
|RECORD=48|OwnerIndex=121
|RECORD=41|OwnerIndex=123|IndexInSheet=-1|OwnerPartId=-1|Color=8388608|FontID=1|Text=2D|Name=Available Preview Images
|RECORD=41|IndexInSheet=10|OwnerPartId=-1|Color=8388608|FontID=1|IsHidden=T|Name=ConfigurationParameters|ReadOnlyState=1
|RECORD=41|IndexInSheet=11|OwnerPartId=-1|Color=8388608|FontID=1|IsHidden=T|Name=ConfiguratorName|ReadOnlyState=1
|RECORD=41|IndexInSheet=12|OwnerPartId=-1|Color=8388608|FontID=1|IsHidden=T|Name=VersionControl_RevNumber|ReadOnlyState=1
|RECORD=41|IndexInSheet=13|OwnerPartId=-1|Color=8388608|FontID=1|IsHidden=T|Name=IsUserConfigurable|ReadOnlyState=1
|RECORD=41|IndexInSheet=14|OwnerPartId=-1|Color=8388608|FontID=1|IsHidden=T|Name=VersionControl_ProjFolderRevNumber|ReadOnlyState=1
|RECORD=41|IndexInSheet=15|OwnerPartId=-1|Color=8388608|FontID=1|IsHidden=T|Text=|Name=SPICEModelCache|ReadOnlyState=1
|RECORD=41|IndexInSheet=16|OwnerPartId=-1|Color=8388608|FontID=1|IsHidden=T|Text=*|Name=CurrentTime|ReadOnlyState=1
|RECORD=41|IndexInSheet=17|OwnerPartId=-1|Color=8388608|FontID=1|IsHidden=T|Text=*|Name=CurrentDate|ReadOnlyState=1
|RECORD=41|IndexInSheet=18|OwnerPartId=-1|Color=8388608|FontID=1|IsHidden=T|Text=*|Name=Time|ReadOnlyState=1
|RECORD=41|IndexInSheet=19|OwnerPartId=-1|Color=8388608|FontID=1|IsHidden=T|Text=*|Name=Date|ReadOnlyState=1
|RECORD=41|IndexInSheet=20|OwnerPartId=-1|Color=8388608|FontID=1|IsHidden=T|Text=*|Name=DocumentFullPathAndName|ReadOnlyState=1
|RECORD=41|IndexInSheet=21|OwnerPartId=-1|Color=8388608|FontID=1|IsHidden=T|Text=*|Name=DocumentName|ReadOnlyState=1
|RECORD=41|IndexInSheet=22|OwnerPartId=-1|Color=8388608|FontID=1|IsHidden=T|Text=*|Name=ModifiedDate|ReadOnlyState=1
|RECORD=41|IndexInSheet=23|OwnerPartId=-1|Color=8388608|FontID=1|IsHidden=T|Text=*|Name=ApprovedBy|ReadOnlyState=1
|RECORD=41|IndexInSheet=24|OwnerPartId=-1|Color=8388608|FontID=1|IsHidden=T|Text=*|Name=CheckedBy|ReadOnlyState=1
|RECORD=41|IndexInSheet=25|OwnerPartId=-1|Color=8388608|FontID=1|IsHidden=T|Text=*|Name=Author|ReadOnlyState=1
|RECORD=41|IndexInSheet=26|OwnerPartId=-1|Color=8388608|FontID=1|IsHidden=T|Text=*|Name=CompanyName|ReadOnlyState=1
|RECORD=41|IndexInSheet=27|OwnerPartId=-1|Color=8388608|FontID=1|IsHidden=T|Text=*|Name=DrawnBy|ReadOnlyState=1
|RECORD=41|IndexInSheet=28|OwnerPartId=-1|Color=8388608|FontID=1|IsHidden=T|Text=*|Name=Engineer|ReadOnlyState=1
|RECORD=41|IndexInSheet=29|OwnerPartId=-1|Color=8388608|FontID=1|IsHidden=T|Text=*|Name=Organization|ReadOnlyState=1
|RECORD=41|IndexInSheet=30|OwnerPartId=-1|Color=8388608|FontID=1|IsHidden=T|Text=*|Name=Address1|ReadOnlyState=1
|RECORD=41|IndexInSheet=31|OwnerPartId=-1|Color=8388608|FontID=1|IsHidden=T|Text=*|Name=Address2|ReadOnlyState=1
|RECORD=41|IndexInSheet=32|OwnerPartId=-1|Color=8388608|FontID=1|IsHidden=T|Text=*|Name=Address3|ReadOnlyState=1
|RECORD=41|IndexInSheet=33|OwnerPartId=-1|Color=8388608|FontID=1|IsHidden=T|Text=*|Name=Address4|ReadOnlyState=1
|RECORD=41|IndexInSheet=34|OwnerPartId=-1|Color=8388608|FontID=1|IsHidden=T|Text=*|Name=Title|ReadOnlyState=1
|RECORD=41|IndexInSheet=35|OwnerPartId=-1|Color=8388608|FontID=1|IsHidden=T|Text=*|Name=DocumentNumber|ReadOnlyState=1
|RECORD=41|IndexInSheet=36|OwnerPartId=-1|Color=8388608|FontID=1|IsHidden=T|Text=*|Name=Revision|ReadOnlyState=1
|RECORD=41|IndexInSheet=37|OwnerPartId=-1|Color=8388608|FontID=1|IsHidden=T|Text=*|Name=SheetNumber|ReadOnlyState=1
|RECORD=41|IndexInSheet=38|OwnerPartId=-1|Color=8388608|FontID=1|IsHidden=T|Text=*|Name=SheetTotal|ReadOnlyState=1
|RECORD=41|IndexInSheet=39|OwnerPartId=-1|Color=8388608|FontID=1|IsHidden=T|Text=*|Name=Rule|ReadOnlyState=1
|RECORD=41|IndexInSheet=40|OwnerPartId=-1|Color=8388608|FontID=1|IsHidden=T|Text=*|Name=ImagePath|ReadOnlyState=1
|RECORD=41|IndexInSheet=41|OwnerPartId=-1|Color=8388608|FontID=1|IsHidden=T|Text=*|Name=ProjectName|ReadOnlyState=1
|RECORD=41|IndexInSheet=42|OwnerPartId=-1|Color=8388608|FontID=1|IsHidden=T|Text=*|Name=Application_BuildNumber|ReadOnlyState=1
|RECORD=17|IndexInSheet=43|OwnerPartId=-1|Style=4|ShowNetName=T|Location.X=170|Location.Y=900|Orientation=3|Color=128|FontID=1|Text=GND
|RECORD=17|IndexInSheet=44|OwnerPartId=-1|ShowNetName=T|Location.X=82|Location.Y=839|Orientation=1|Color=128|FontID=1|Text=+12V_PCIE
|RECORD=1|LibReference=1d6ec82d83fb6aee721767c19dac4b9|ComponentDescription=DIODE SCHOTTKY 60V 5A SMC|PartCount=2|DisplayModeCount=1|IndexInSheet=45|OwnerPartId=-1|Location.X=220|Location.Y=1000|CurrentPartId=1|LibraryPath=*|SourceLibraryName=Altium Content Vault|TargetFileName=*|AreaColor=11599871|Color=128|PartIDLocked=T|DesignItemId=CMP-12187-000009-2|AllPinCount=2
|RECORD=2|OwnerIndex=160|OwnerPartId=1|Electrical=4|PinConglomerate=50|PinLength=20|Location.X=240|Location.Y=1000|Name=A|Designator=2|PinPropagationDelay=0.000000E+000
|RECORD=2|OwnerIndex=160|OwnerPartId=1|Electrical=4|PinConglomerate=48|PinLength=20|Location.X=260|Location.Y=1000|Name=C|Designator=1|PinPropagationDelay=0.000000E+000
|RECORD=13|OwnerIndex=160|IsNotAccesible=T|IndexInSheet=2|OwnerPartId=1|Location.X=240|Location.Y=1010|Corner.X=240|Corner.Y=990|LineWidth=1|Color=16711680
|RECORD=13|OwnerIndex=160|IsNotAccesible=T|IndexInSheet=3|OwnerPartId=1|Location.X=260|Location.Y=1010|Corner.X=260|Corner.Y=990|LineWidth=1|Color=16711680
|RECORD=13|OwnerIndex=160|IsNotAccesible=T|IndexInSheet=4|OwnerPartId=1|Location.X=240|Location.Y=1010|Corner.X=260|Corner.Y=1000|LineWidth=1|Color=16711680
|RECORD=13|OwnerIndex=160|IsNotAccesible=T|IndexInSheet=5|OwnerPartId=1|Location.X=240|Location.Y=990|Corner.X=260|Corner.Y=1000|LineWidth=1|Color=16711680
|RECORD=13|OwnerIndex=160|IsNotAccesible=T|IndexInSheet=6|OwnerPartId=1|Location.X=260|Location.Y=1010|Corner.X=257|Corner.Y=1010|LineWidth=1|Color=16711680
|RECORD=13|OwnerIndex=160|IsNotAccesible=T|IndexInSheet=7|OwnerPartId=1|Location.X=263|Location.Y=990|Corner.X=263|Corner.Y=993|LineWidth=1|Color=16711680
|RECORD=13|OwnerIndex=160|IsNotAccesible=T|IndexInSheet=8|OwnerPartId=1|Location.X=257|Location.Y=1010|Corner.X=257|Corner.Y=1007|LineWidth=1|Color=16711680
|RECORD=13|OwnerIndex=160|IsNotAccesible=T|IndexInSheet=9|OwnerPartId=1|Location.X=260|Location.Y=990|Corner.X=263|Corner.Y=990|LineWidth=1|Color=16711680
|RECORD=13|OwnerIndex=160|IsNotAccesible=T|IndexInSheet=10|OwnerPartId=1|Location.X=240|Location.Y=1000|Corner.X=237|Corner.Y=1000|LineWidth=1|Color=16711680
|RECORD=13|OwnerIndex=160|IsNotAccesible=T|IndexInSheet=11|OwnerPartId=1|Location.X=260|Location.Y=1000|Corner.X=263|Corner.Y=1000|LineWidth=1|Color=16711680
|RECORD=41|OwnerIndex=160|IndexInSheet=12|OwnerPartId=-1|Location.X=218|Location.Y=1011|Color=8388608|FontID=1|IsHidden=T|Text=No|Name=Radiation Hardening
|RECORD=41|OwnerIndex=160|IndexInSheet=13|OwnerPartId=-1|Location.X=218|Location.Y=1011|Color=8388608|FontID=1|IsHidden=T|Text=150A|Name=Max Forward Surge Current (Ifsm)
|RECORD=41|OwnerIndex=160|IndexInSheet=14|OwnerPartId=-1|Location.X=218|Location.Y=1011|Color=8388608|FontID=1|IsHidden=T|Text=2500|Name=Package Quantity
|RECORD=41|OwnerIndex=160|IndexInSheet=15|OwnerPartId=-1|Location.X=218|Location.Y=1011|Color=8388608|FontID=1|IsHidden=T|Text=No SVHC|Name=REACH SVHC
|RECORD=41|OwnerIndex=160|IndexInSheet=16|OwnerPartId=-1|Location.X=218|Location.Y=1011|Color=8388608|FontID=1|IsHidden=T|Text=60V|Name=Max Reverse Voltage (DC)
|RECORD=41|OwnerIndex=160|IndexInSheet=17|OwnerPartId=-1|Location.X=218|Location.Y=1011|Color=8388608|FontID=1|IsHidden=T|Text=2|Name=Number of Pins
|RECORD=41|OwnerIndex=160|IndexInSheet=18|OwnerPartId=-1|Location.X=218|Location.Y=1011|Color=8388608|FontID=1|IsHidden=T|Text=Surface Mount|Name=Mount
|RECORD=41|OwnerIndex=160|IndexInSheet=19|OwnerPartId=-1|Location.X=218|Location.Y=1011|Color=8388608|FontID=1|IsHidden=T|Text=2.45mm|Name=Height
|RECORD=41|OwnerIndex=160|IndexInSheet=20|OwnerPartId=-1|Location.X=218|Location.Y=1011|Color=8388608|FontID=1|IsHidden=T|Text=5A|Name=Forward Current
|RECORD=41|OwnerIndex=160|IndexInSheet=21|OwnerPartId=-1|Location.X=218|Location.Y=1011|Color=8388608|FontID=1|IsHidden=T|Text=Tape and Reel|Name=Packaging
|RECORD=41|OwnerIndex=160|IndexInSheet=22|OwnerPartId=-1|Location.X=218|Location.Y=1011|Color=8388608|FontID=1|IsHidden=T|Text=6.25mm|Name=Width
|RECORD=41|OwnerIndex=160|IndexInSheet=23|OwnerPartId=-1|Location.X=218|Location.Y=1011|Color=8388608|FontID=1|IsHidden=T|Text=-|Name=Series
|RECORD=41|OwnerIndex=160|IndexInSheet=24|OwnerPartId=-1|Location.X=218|Location.Y=1011|Color=8388608|FontID=1|IsHidden=T|Text=150A|Name=Peak Non-Repetitive Surge Current
|RECORD=41|OwnerIndex=160|IndexInSheet=25|OwnerPartId=-1|Location.X=218|Location.Y=1011|Color=8388608|FontID=1|IsHidden=T|Text=220uA|Name=Max Reverse Leakage Current
|RECORD=41|OwnerIndex=160|IndexInSheet=26|OwnerPartId=-1|Location.X=218|Location.Y=1011|Color=8388608|FontID=1|IsHidden=T|Text=5A|Name=Average Rectified Current
|RECORD=41|OwnerIndex=160|IndexInSheet=27|OwnerPartId=-1|Location.X=218|Location.Y=1011|Color=8388608|FontID=1|IsHidden=T|Text=150A|Name=Max Surge Current
|RECORD=41|OwnerIndex=160|IndexInSheet=28|OwnerPartId=-1|Location.X=218|Location.Y=1011|Color=8388608|FontID=1|IsHidden=T|Text=SMC|Name=Case/Package
|RECORD=41|OwnerIndex=160|IndexInSheet=29|OwnerPartId=-1|Location.X=218|Location.Y=1011|Color=8388608|FontID=1|IsHidden=T|Text=Lead Free|Name=Lead Free
|RECORD=41|OwnerIndex=160|IndexInSheet=30|OwnerPartId=-1|Location.X=218|Location.Y=1011|Color=8388608|FontID=1|IsHidden=T|Text=60V|Name=Max Repetitive Reverse Voltage (Vrrm)
|RECORD=41|OwnerIndex=160|IndexInSheet=31|OwnerPartId=-1|Location.X=218|Location.Y=1011|Color=8388608|FontID=1|IsHidden=T|Text=-65°C|Name=Min Operating Temperature
|RECORD=41|OwnerIndex=160|IndexInSheet=32|OwnerPartId=-1|Location.X=218|Location.Y=1011|Color=8388608|FontID=1|IsHidden=T|Text=520mV|Name=Forward Voltage
|RECORD=41|OwnerIndex=160|IndexInSheet=33|OwnerPartId=-1|Location.X=218|Location.Y=1011|Color=8388608|FontID=1|IsHidden=T|Text=Yes|Name=RoHS Compliant
|RECORD=41|OwnerIndex=160|IndexInSheet=34|OwnerPartId=-1|Location.X=218|Location.Y=1011|Color=8388608|FontID=1|IsHidden=T|Text=Single|Name=Element Configuration
|RECORD=41|OwnerIndex=160|IndexInSheet=35|OwnerPartId=-1|Location.X=218|Location.Y=1011|Color=8388608|FontID=1|IsHidden=T|Text=7.15mm|Name=Length
|RECORD=41|OwnerIndex=160|IndexInSheet=36|OwnerPartId=-1|Location.X=218|Location.Y=1011|Color=8388608|FontID=1|IsHidden=T|Text=220uA|Name=Max Reverse Current
|RECORD=41|OwnerIndex=160|IndexInSheet=37|OwnerPartId=-1|Location.X=218|Location.Y=1011|Color=8388608|FontID=1|IsHidden=T|Text=150°C|Name=Max Operating Temperature
|RECORD=34|OwnerIndex=160|IndexInSheet=-1|OwnerPartId=-1|Location.X=236|Location.Y=1011|Color=8388608|FontID=1|Text=D12|Name=Designator|ReadOnlyState=1
|RECORD=41|OwnerIndex=160|IndexInSheet=-1|OwnerPartId=1|Location.X=236|Location.Y=979|Color=8388608|FontID=1|Text=STPS5L60S|Name=Comment
|RECORD=44|OwnerIndex=160
|RECORD=45|OwnerIndex=203|IndexInSheet=-1|UseComponentLibrary=T|ModelName=FP-STPS5L60S-MFG|ModelType=PCBLIB|DatafileCount=1|ModelDatafileEntity0=FP-STPS5L60S-MFG|ModelDatafileKind0=PCBLib|IsCurrent=T|DatalinksLocked=T|DatabaseDatalinksLocked=T
|RECORD=46|OwnerIndex=204
|RECORD=48|OwnerIndex=204
|RECORD=1|LibReference=1d6ec82d83fb6aee721767c19dac4b9|ComponentDescription=DIODE SCHOTTKY 60V 5A SMC|PartCount=2|DisplayModeCount=1|IndexInSheet=46|OwnerPartId=-1|Location.X=135|Location.Y=830|CurrentPartId=1|LibraryPath=*|SourceLibraryName=Altium Content Vault|TargetFileName=*|AreaColor=11599871|Color=128|PartIDLocked=T|DesignItemId=CMP-12187-000009-2|AllPinCount=2
|RECORD=2|OwnerIndex=207|OwnerPartId=1|Electrical=4|PinConglomerate=50|PinLength=20|Location.X=155|Location.Y=830|Name=A|Designator=2|PinPropagationDelay=0.000000E+000
|RECORD=2|OwnerIndex=207|OwnerPartId=1|Electrical=4|PinConglomerate=48|PinLength=20|Location.X=175|Location.Y=830|Name=C|Designator=1|PinPropagationDelay=0.000000E+000
|RECORD=13|OwnerIndex=207|IsNotAccesible=T|IndexInSheet=2|OwnerPartId=1|Location.X=155|Location.Y=840|Corner.X=155|Corner.Y=820|LineWidth=1|Color=16711680
|RECORD=13|OwnerIndex=207|IsNotAccesible=T|IndexInSheet=3|OwnerPartId=1|Location.X=175|Location.Y=840|Corner.X=175|Corner.Y=820|LineWidth=1|Color=16711680
|RECORD=13|OwnerIndex=207|IsNotAccesible=T|IndexInSheet=4|OwnerPartId=1|Location.X=155|Location.Y=840|Corner.X=175|Corner.Y=830|LineWidth=1|Color=16711680
|RECORD=13|OwnerIndex=207|IsNotAccesible=T|IndexInSheet=5|OwnerPartId=1|Location.X=155|Location.Y=820|Corner.X=175|Corner.Y=830|LineWidth=1|Color=16711680
|RECORD=13|OwnerIndex=207|IsNotAccesible=T|IndexInSheet=6|OwnerPartId=1|Location.X=175|Location.Y=840|Corner.X=172|Corner.Y=840|LineWidth=1|Color=16711680
|RECORD=13|OwnerIndex=207|IsNotAccesible=T|IndexInSheet=7|OwnerPartId=1|Location.X=178|Location.Y=820|Corner.X=178|Corner.Y=823|LineWidth=1|Color=16711680
|RECORD=13|OwnerIndex=207|IsNotAccesible=T|IndexInSheet=8|OwnerPartId=1|Location.X=172|Location.Y=840|Corner.X=172|Corner.Y=837|LineWidth=1|Color=16711680
|RECORD=13|OwnerIndex=207|IsNotAccesible=T|IndexInSheet=9|OwnerPartId=1|Location.X=175|Location.Y=820|Corner.X=178|Corner.Y=820|LineWidth=1|Color=16711680
|RECORD=13|OwnerIndex=207|IsNotAccesible=T|IndexInSheet=10|OwnerPartId=1|Location.X=155|Location.Y=830|Corner.X=152|Corner.Y=830|LineWidth=1|Color=16711680
|RECORD=13|OwnerIndex=207|IsNotAccesible=T|IndexInSheet=11|OwnerPartId=1|Location.X=175|Location.Y=830|Corner.X=178|Corner.Y=830|LineWidth=1|Color=16711680
|RECORD=41|OwnerIndex=207|IndexInSheet=12|OwnerPartId=-1|Location.X=133|Location.Y=841|Color=8388608|FontID=1|IsHidden=T|Text=No|Name=Radiation Hardening
|RECORD=41|OwnerIndex=207|IndexInSheet=13|OwnerPartId=-1|Location.X=133|Location.Y=841|Color=8388608|FontID=1|IsHidden=T|Text=150A|Name=Max Forward Surge Current (Ifsm)
|RECORD=41|OwnerIndex=207|IndexInSheet=14|OwnerPartId=-1|Location.X=133|Location.Y=841|Color=8388608|FontID=1|IsHidden=T|Text=2500|Name=Package Quantity
|RECORD=41|OwnerIndex=207|IndexInSheet=15|OwnerPartId=-1|Location.X=133|Location.Y=841|Color=8388608|FontID=1|IsHidden=T|Text=No SVHC|Name=REACH SVHC
|RECORD=41|OwnerIndex=207|IndexInSheet=16|OwnerPartId=-1|Location.X=133|Location.Y=841|Color=8388608|FontID=1|IsHidden=T|Text=60V|Name=Max Reverse Voltage (DC)
|RECORD=41|OwnerIndex=207|IndexInSheet=17|OwnerPartId=-1|Location.X=133|Location.Y=841|Color=8388608|FontID=1|IsHidden=T|Text=2|Name=Number of Pins
|RECORD=41|OwnerIndex=207|IndexInSheet=18|OwnerPartId=-1|Location.X=133|Location.Y=841|Color=8388608|FontID=1|IsHidden=T|Text=Surface Mount|Name=Mount
|RECORD=41|OwnerIndex=207|IndexInSheet=19|OwnerPartId=-1|Location.X=133|Location.Y=841|Color=8388608|FontID=1|IsHidden=T|Text=2.45mm|Name=Height
|RECORD=41|OwnerIndex=207|IndexInSheet=20|OwnerPartId=-1|Location.X=133|Location.Y=841|Color=8388608|FontID=1|IsHidden=T|Text=5A|Name=Forward Current
|RECORD=41|OwnerIndex=207|IndexInSheet=21|OwnerPartId=-1|Location.X=133|Location.Y=841|Color=8388608|FontID=1|IsHidden=T|Text=Tape and Reel|Name=Packaging
|RECORD=41|OwnerIndex=207|IndexInSheet=22|OwnerPartId=-1|Location.X=133|Location.Y=841|Color=8388608|FontID=1|IsHidden=T|Text=6.25mm|Name=Width
|RECORD=41|OwnerIndex=207|IndexInSheet=23|OwnerPartId=-1|Location.X=133|Location.Y=841|Color=8388608|FontID=1|IsHidden=T|Text=-|Name=Series
|RECORD=41|OwnerIndex=207|IndexInSheet=24|OwnerPartId=-1|Location.X=133|Location.Y=841|Color=8388608|FontID=1|IsHidden=T|Text=150A|Name=Peak Non-Repetitive Surge Current
|RECORD=41|OwnerIndex=207|IndexInSheet=25|OwnerPartId=-1|Location.X=133|Location.Y=841|Color=8388608|FontID=1|IsHidden=T|Text=220uA|Name=Max Reverse Leakage Current
|RECORD=41|OwnerIndex=207|IndexInSheet=26|OwnerPartId=-1|Location.X=133|Location.Y=841|Color=8388608|FontID=1|IsHidden=T|Text=5A|Name=Average Rectified Current
|RECORD=41|OwnerIndex=207|IndexInSheet=27|OwnerPartId=-1|Location.X=133|Location.Y=841|Color=8388608|FontID=1|IsHidden=T|Text=150A|Name=Max Surge Current
|RECORD=41|OwnerIndex=207|IndexInSheet=28|OwnerPartId=-1|Location.X=133|Location.Y=841|Color=8388608|FontID=1|IsHidden=T|Text=SMC|Name=Case/Package
|RECORD=41|OwnerIndex=207|IndexInSheet=29|OwnerPartId=-1|Location.X=133|Location.Y=841|Color=8388608|FontID=1|IsHidden=T|Text=Lead Free|Name=Lead Free
|RECORD=41|OwnerIndex=207|IndexInSheet=30|OwnerPartId=-1|Location.X=133|Location.Y=841|Color=8388608|FontID=1|IsHidden=T|Text=60V|Name=Max Repetitive Reverse Voltage (Vrrm)
|RECORD=41|OwnerIndex=207|IndexInSheet=31|OwnerPartId=-1|Location.X=133|Location.Y=841|Color=8388608|FontID=1|IsHidden=T|Text=-65°C|Name=Min Operating Temperature
|RECORD=41|OwnerIndex=207|IndexInSheet=32|OwnerPartId=-1|Location.X=133|Location.Y=841|Color=8388608|FontID=1|IsHidden=T|Text=520mV|Name=Forward Voltage
|RECORD=41|OwnerIndex=207|IndexInSheet=33|OwnerPartId=-1|Location.X=133|Location.Y=841|Color=8388608|FontID=1|IsHidden=T|Text=Yes|Name=RoHS Compliant
|RECORD=41|OwnerIndex=207|IndexInSheet=34|OwnerPartId=-1|Location.X=133|Location.Y=841|Color=8388608|FontID=1|IsHidden=T|Text=Single|Name=Element Configuration
|RECORD=41|OwnerIndex=207|IndexInSheet=35|OwnerPartId=-1|Location.X=133|Location.Y=841|Color=8388608|FontID=1|IsHidden=T|Text=7.15mm|Name=Length
|RECORD=41|OwnerIndex=207|IndexInSheet=36|OwnerPartId=-1|Location.X=133|Location.Y=841|Color=8388608|FontID=1|IsHidden=T|Text=220uA|Name=Max Reverse Current
|RECORD=41|OwnerIndex=207|IndexInSheet=37|OwnerPartId=-1|Location.X=133|Location.Y=841|Color=8388608|FontID=1|IsHidden=T|Text=150°C|Name=Max Operating Temperature
|RECORD=34|OwnerIndex=207|IndexInSheet=-1|OwnerPartId=-1|Location.X=151|Location.Y=841|Color=8388608|FontID=1|Text=D19|Name=Designator|ReadOnlyState=1
|RECORD=41|OwnerIndex=207|IndexInSheet=-1|OwnerPartId=1|Location.X=151|Location.Y=809|Color=8388608|FontID=1|Text=STPS5L60S|Name=Comment
|RECORD=44|OwnerIndex=207
|RECORD=45|OwnerIndex=250|IndexInSheet=-1|UseComponentLibrary=T|ModelName=FP-STPS5L60S-MFG|ModelType=PCBLIB|DatafileCount=1|ModelDatafileEntity0=FP-STPS5L60S-MFG|ModelDatafileKind0=PCBLib|IsCurrent=T|DatalinksLocked=T|DatabaseDatalinksLocked=T
|RECORD=46|OwnerIndex=251
|RECORD=48|OwnerIndex=251
|RECORD=1|LibReference=RES|PartCount=2|DisplayModeCount=2|IndexInSheet=47|OwnerPartId=-1|Location.X=335|Location.Y=965|CurrentPartId=1|SourceLibraryName=Altium Content Vault|TargetFileName=*|AreaColor=11599871|Color=128|PartIDLocked=F|DesignItemId=CMP-2003-04873-1|AllPinCount=2|ComponentKindVersion2=5
|RECORD=2|OwnerIndex=254|OwnerPartId=1|OwnerPartDisplayMode=1|FormalType=1|Electrical=4|PinConglomerate=32|PinLength=10|Location.X=355|Location.Y=955|Name=2|Designator=2|PinPropagationDelay=0.000000E+000
|RECORD=2|OwnerIndex=254|OwnerPartId=1|OwnerPartDisplayMode=1|FormalType=1|Electrical=4|PinConglomerate=34|PinLength=10|Location.X=335|Location.Y=955|Name=1|Designator=1|PinPropagationDelay=0.000000E+000
|RECORD=14|OwnerIndex=254|IsNotAccesible=T|IndexInSheet=2|OwnerPartId=1|OwnerPartDisplayMode=1|Location.X=335|Location.Y=951|Corner.X=355|Corner.Y=959|LineWidth=1|Color=16711680|AreaColor=11599871
|RECORD=2|OwnerIndex=254|OwnerPartId=1|FormalType=1|Electrical=4|PinConglomerate=32|PinLength=10|Location.X=355|Location.Y=955|Name=2|Designator=2|PinPropagationDelay=0.000000E+000
|RECORD=2|OwnerIndex=254|OwnerPartId=1|FormalType=1|Electrical=4|PinConglomerate=34|PinLength=10|Location.X=335|Location.Y=955|Name=1|Designator=1|PinPropagationDelay=0.000000E+000
|RECORD=6|OwnerIndex=254|IsNotAccesible=T|IndexInSheet=5|OwnerPartId=1|LineWidth=1|Color=16711680|LocationCount=10|X1=355|Y1=955|X2=351|Y2=955|X3=350|Y3=953|X4=348|Y4=957|X5=346|Y5=953|X6=344|Y6=957|X7=342|Y7=953|X8=340|Y8=957|X9=339|Y9=955|X10=335|Y10=955
|RECORD=41|OwnerIndex=254|IndexInSheet=6|OwnerPartId=-1|Location.X=323|Location.Y=968|Color=8388608|FontID=1|IsHidden=T|Text=CRCW12060000Z0EAHP|Name=Part Number
|RECORD=41|OwnerIndex=254|IndexInSheet=7|OwnerPartId=-1|Location.X=323|Location.Y=968|Color=8388608|FontID=1|IsHidden=T|Text=Vishay Dale|Name=Manufacturer
|RECORD=34|OwnerIndex=254|IndexInSheet=-1|OwnerPartId=-1|Location.X=334|Location.Y=958|Color=8388608|FontID=1|Text=R44|Name=Designator|ReadOnlyState=1
|RECORD=41|OwnerIndex=254|IndexInSheet=-1|OwnerPartId=-1|Location.X=334|Location.Y=942|Color=8388608|FontID=1|Text=DNI_0_5%_1206|Name=Comment
|RECORD=44|OwnerIndex=254
|RECORD=45|OwnerIndex=269|IndexInSheet=-1|Description=Chip Resistor, 2-Leads, Body 3.10x1.60mm, IPC Low Density|UseComponentLibrary=T|ModelName=RESC3116X65X50ML20T20|ModelType=PCBLIB|DatafileCount=1|ModelDatafileEntity0=RESC3116X65X50ML20T20|ModelDatafileKind0=PCBLib|IsCurrent=T|DatalinksLocked=T|DatabaseDatalinksLocked=T
|RECORD=46|OwnerIndex=270
|RECORD=48|OwnerIndex=270
|RECORD=41|OwnerIndex=272|IndexInSheet=-1|OwnerPartId=-1|Color=8388608|FontID=1|IsHidden=T|Text=2D|Name=Available Preview Images
|RECORD=45|OwnerIndex=269|IndexInSheet=-1|Description=Chip Resistor, 2-Leads, Body 3.10x1.60mm, IPC High Density|UseComponentLibrary=T|ModelName=RESC3116X65X50LL20T20|ModelType=PCBLIB|DatafileCount=1|ModelDatafileEntity0=RESC3116X65X50LL20T20|ModelDatafileKind0=PCBLib|DatalinksLocked=T|DatabaseDatalinksLocked=T
|RECORD=46|OwnerIndex=274
|RECORD=48|OwnerIndex=274
|RECORD=41|OwnerIndex=276|IndexInSheet=-1|OwnerPartId=-1|Color=8388608|FontID=1|IsHidden=T|Text=2D|Name=Available Preview Images
|RECORD=45|OwnerIndex=269|IndexInSheet=-1|Description=Chip Resistor, 2-Leads, Body 3.10x1.60mm, IPC Medium Density|UseComponentLibrary=T|ModelName=RESC3116X65X50NL20T20|ModelType=PCBLIB|DatafileCount=1|ModelDatafileEntity0=RESC3116X65X50NL20T20|ModelDatafileKind0=PCBLib|DatalinksLocked=T|DatabaseDatalinksLocked=T
|RECORD=46|OwnerIndex=278
|RECORD=48|OwnerIndex=278
|RECORD=41|OwnerIndex=280|IndexInSheet=-1|OwnerPartId=-1|Color=8388608|FontID=1|IsHidden=T|Text=2D|Name=Available Preview Images
|RECORD=1|LibReference=ac72c5313ea981db199dbd0e8237b04|ComponentDescription=CONN HEADER R/A 4POS 4.2MM|PartCount=3|DisplayModeCount=1|IndexInSheet=48|OwnerPartId=-1|Location.X=105|Location.Y=930|CurrentPartId=1|LibraryPath=*|SourceLibraryName=Altium Content Vault|TargetFileName=*|AreaColor=11599871|Color=128|PartIDLocked=T|DesignItemId=CMP-2000-05600-2|AllPinCount=4
|RECORD=14|OwnerIndex=282|IsNotAccesible=T|OwnerPartId=1|Location.X=65|Location.Y=890|Corner.X=85|Corner.Y=950|LineWidth=1|Color=128|AreaColor=11599871|IsSolid=T
|RECORD=14|OwnerIndex=282|IsNotAccesible=T|IndexInSheet=1|OwnerPartId=1|Location.X=69|Location.Y=927|Corner.X=78|Corner.Y=933|LineWidth=1|Color=16711680|AreaColor=16711680|IsSolid=T
|RECORD=13|OwnerIndex=282|IsNotAccesible=T|IndexInSheet=2|OwnerPartId=1|Location.X=78|Location.Y=930|Corner.X=85|Corner.Y=930|LineWidth=1|Color=16711680
|RECORD=14|OwnerIndex=282|IsNotAccesible=T|IndexInSheet=3|OwnerPartId=1|Location.X=69|Location.Y=907|Corner.X=78|Corner.Y=913|LineWidth=1|Color=16711680|AreaColor=16711680|IsSolid=T
|RECORD=13|OwnerIndex=282|IsNotAccesible=T|IndexInSheet=4|OwnerPartId=1|Location.X=78|Location.Y=910|Corner.X=85|Corner.Y=910|LineWidth=1|Color=16711680
|RECORD=4|OwnerIndex=282|IsNotAccesible=T|IndexInSheet=5|OwnerPartId=1|Location.X=78|Location.Y=942|Justification=8|Color=8388608|FontID=1|Text=1
|RECORD=4|OwnerIndex=282|IsNotAccesible=T|IndexInSheet=6|OwnerPartId=1|Location.X=78|Location.Y=922|Justification=8|Color=8388608|FontID=1|Text=2
|RECORD=2|OwnerIndex=282|OwnerPartId=1|Electrical=4|PinConglomerate=48|PinLength=20|Location.X=85|Location.Y=930|Name=1|Designator=1|PinPropagationDelay=0.000000E+000
|RECORD=2|OwnerIndex=282|OwnerPartId=1|Electrical=4|PinConglomerate=48|PinLength=20|Location.X=85|Location.Y=910|Name=2|Designator=2|PinPropagationDelay=0.000000E+000
|RECORD=14|OwnerIndex=282|IsNotAccesible=T|IndexInSheet=9|OwnerPartId=2|Location.X=65|Location.Y=890|Corner.X=85|Corner.Y=950|LineWidth=1|Color=128|AreaColor=11599871|IsSolid=T
|RECORD=14|OwnerIndex=282|IsNotAccesible=T|IndexInSheet=10|OwnerPartId=2|Location.X=69|Location.Y=927|Corner.X=78|Corner.Y=933|LineWidth=1|Color=16711680|AreaColor=16711680|IsSolid=T
|RECORD=13|OwnerIndex=282|IsNotAccesible=T|IndexInSheet=11|OwnerPartId=2|Location.X=78|Location.Y=930|Corner.X=85|Corner.Y=930|LineWidth=1|Color=16711680
|RECORD=14|OwnerIndex=282|IsNotAccesible=T|IndexInSheet=12|OwnerPartId=2|Location.X=69|Location.Y=907|Corner.X=78|Corner.Y=913|LineWidth=1|Color=16711680|AreaColor=16711680|IsSolid=T
|RECORD=13|OwnerIndex=282|IsNotAccesible=T|IndexInSheet=13|OwnerPartId=2|Location.X=78|Location.Y=910|Corner.X=85|Corner.Y=910|LineWidth=1|Color=16711680
|RECORD=4|OwnerIndex=282|IsNotAccesible=T|IndexInSheet=14|OwnerPartId=2|Location.X=78|Location.Y=942|Justification=8|Color=8388608|FontID=1|Text=3
|RECORD=4|OwnerIndex=282|IsNotAccesible=T|IndexInSheet=15|OwnerPartId=2|Location.X=78|Location.Y=922|Justification=8|Color=8388608|FontID=1|Text=4
|RECORD=2|OwnerIndex=282|OwnerPartId=2|Electrical=4|PinConglomerate=48|PinLength=20|Location.X=85|Location.Y=930|Name=3|Designator=3|PinPropagationDelay=0.000000E+000
|RECORD=2|OwnerIndex=282|OwnerPartId=2|Electrical=4|PinConglomerate=48|PinLength=20|Location.X=85|Location.Y=910|Name=4|Designator=4|PinPropagationDelay=0.000000E+000
|RECORD=41|OwnerIndex=282|IndexInSheet=18|OwnerPartId=-1|Location.X=65|Location.Y=950|Color=8388608|FontID=1|IsHidden=T|Text=13A|Name=Current Rating
|RECORD=41|OwnerIndex=282|IndexInSheet=19|OwnerPartId=-1|Location.X=65|Location.Y=950|Color=8388608|FontID=1|IsHidden=T|Text=Connectors|Name=Device Class L1
|RECORD=41|OwnerIndex=282|IndexInSheet=20|OwnerPartId=-1|Location.X=65|Location.Y=950|Color=8388608|FontID=1|IsHidden=T|Text=4.2mm|Name=Pitch
|RECORD=41|OwnerIndex=282|IndexInSheet=21|OwnerPartId=-1|Location.X=65|Location.Y=950|Color=8388608|FontID=1|IsHidden=T|Text=39-30-0040|Name=Package
|RECORD=41|OwnerIndex=282|IndexInSheet=22|OwnerPartId=-1|Location.X=65|Location.Y=950|Color=8388608|FontID=7|IsHidden=T|Text=https://octopart.com/39-30-0040-molex-277428|Name=Octopart
|RECORD=41|OwnerIndex=282|IndexInSheet=23|OwnerPartId=-1|Location.X=65|Location.Y=950|Color=8388608|FontID=1|IsHidden=T|Text=Headers & Wire Housings 4 CKT R/A HEADER|Name=Mouser Description
|RECORD=41|OwnerIndex=282|IndexInSheet=24|OwnerPartId=-1|Location.X=65|Location.Y=950|Color=8388608|FontID=1|IsHidden=T|Text=+105°C|Name=Temperature Range High
|RECORD=41|OwnerIndex=282|IndexInSheet=25|OwnerPartId=-1|Location.X=65|Location.Y=950|Color=8388608|FontID=1|IsHidden=T|Text=2|Name=Number Of Rows
|RECORD=41|OwnerIndex=282|IndexInSheet=26|OwnerPartId=-1|Location.X=65|Location.Y=950|Color=8388608|FontID=1|IsHidden=T|Text=600V|Name=Voltage Rating
|RECORD=41|OwnerIndex=282|IndexInSheet=27|OwnerPartId=-1|Location.X=65|Location.Y=950|Color=8388608|FontID=1|IsHidden=T|Text=Datasheet|Name=ComponentLink2Description
|RECORD=41|OwnerIndex=282|IndexInSheet=28|OwnerPartId=-1|Location.X=65|Location.Y=950|Color=8388608|FontID=7|IsHidden=T|Text=https://www.molex.com/webdocs/datasheets/pdf/en-us/0039300040_PCB_HEADERS.pdf|Name=ComponentLink2URL
|RECORD=41|OwnerIndex=282|IndexInSheet=29|OwnerPartId=-1|Location.X=65|Location.Y=950|Color=8388608|FontID=1|IsHidden=T|Text=4|Name=Number Of Contacts
|RECORD=41|OwnerIndex=282|IndexInSheet=30|OwnerPartId=-1|Location.X=65|Location.Y=950|Color=8388608|FontID=1|IsHidden=T|Text=39-30-0040|Name=Manufacturer Part Number
|RECORD=41|OwnerIndex=282|IndexInSheet=31|OwnerPartId=-1|Location.X=65|Location.Y=950|Color=8388608|FontID=1|IsHidden=T|Text=Gold,Nickel|Name=Contact Material
|RECORD=41|OwnerIndex=282|IndexInSheet=32|OwnerPartId=-1|Location.X=65|Location.Y=950|Color=8388608|FontID=1|IsHidden=T|Text=CONN HEADER R/A 4POS 4.2MM|Name=Digikey Description
|RECORD=41|OwnerIndex=282|IndexInSheet=33|OwnerPartId=-1|Location.X=65|Location.Y=950|Color=8388608|FontID=1|IsHidden=T|Text=-40°C to +105°C|Name=Temperature
|RECORD=41|OwnerIndex=282|IndexInSheet=34|OwnerPartId=-1|Location.X=65|Location.Y=950|Color=8388608|FontID=1|IsHidden=T|Text=0.4mm|Name=Standoff Height
|RECORD=41|OwnerIndex=282|IndexInSheet=35|OwnerPartId=-1|Location.X=65|Location.Y=950|Color=8388608|FontID=1|IsHidden=T|Text=No|Name=Automotive
|RECORD=41|OwnerIndex=282|IndexInSheet=36|OwnerPartId=-1|Location.X=65|Location.Y=950|Color=8388608|FontID=1|IsHidden=T|Text=Headers and Wire Housings|Name=Device Class L2
|RECORD=41|OwnerIndex=282|IndexInSheet=37|OwnerPartId=-1|Location.X=65|Location.Y=950|Color=8388608|FontID=1|IsHidden=T|Text=Right Angle|Name=Conn Orientation
|RECORD=41|OwnerIndex=282|IndexInSheet=38|OwnerPartId=-1|Location.X=65|Location.Y=950|Color=8388608|FontID=1|IsHidden=T|Text=TRUE|Name=RoHS
|RECORD=41|OwnerIndex=282|IndexInSheet=39|OwnerPartId=-1|Location.X=65|Location.Y=950|Color=8388608|FontID=1|IsHidden=T|Text=Yes|Name=Lead Free
|RECORD=41|OwnerIndex=282|IndexInSheet=40|OwnerPartId=-1|Location.X=65|Location.Y=950|Color=8388608|FontID=1|IsHidden=T|Text=unset|Name=Device Class L3
|RECORD=41|OwnerIndex=282|IndexInSheet=41|OwnerPartId=-1|Location.X=65|Location.Y=950|Color=8388608|FontID=1|IsHidden=T|Text=Conn|Name=Category
|RECORD=41|OwnerIndex=282|IndexInSheet=42|OwnerPartId=-1|Location.X=65|Location.Y=950|Color=8388608|FontID=7|IsHidden=T|Text=https://www.molex.com/pdm_docs/sd/039300040_sd.pdf|Name=Footprint Url
|RECORD=41|OwnerIndex=282|IndexInSheet=43|OwnerPartId=-1|Location.X=65|Location.Y=950|Color=8388608|FontID=1|IsHidden=T|Text=-40°C|Name=Temperature Range Low
|RECORD=41|OwnerIndex=282|IndexInSheet=44|OwnerPartId=-1|Location.X=65|Location.Y=950|Color=8388608|FontID=1|IsHidden=T|Text=Male|Name=Conn Gender
|RECORD=41|OwnerIndex=282|IndexInSheet=45|OwnerPartId=-1|Location.X=65|Location.Y=950|Color=8388608|FontID=1|IsHidden=T|Text=Molex|Name=Manufacturer
|RECORD=34|OwnerIndex=282|IndexInSheet=-1|OwnerPartId=-1|Location.X=65|Location.Y=950|Color=8388608|FontID=1|Text=J38|Name=Designator|ReadOnlyState=1
|RECORD=41|OwnerIndex=282|IndexInSheet=-1|OwnerPartId=1|Location.X=65|Location.Y=880|Color=8388608|FontID=1|Text=39-30-0040|Name=Comment
|RECORD=44|OwnerIndex=282
|RECORD=45|OwnerIndex=335|IndexInSheet=-1|UseComponentLibrary=T|ModelName=FP-39-30-0040-MFG|ModelType=PCBLIB|DatafileCount=1|ModelDatafileEntity0=FP-39-30-0040-MFG|ModelDatafileKind0=PCBLib|IsCurrent=T|DatalinksLocked=T|DatabaseDatalinksLocked=T
|RECORD=46|OwnerIndex=336
|RECORD=48|OwnerIndex=336
|RECORD=1|LibReference=ac72c5313ea981db199dbd0e8237b04|ComponentDescription=CONN HEADER R/A 4POS 4.2MM|PartCount=3|DisplayModeCount=1|IndexInSheet=49|OwnerPartId=-1|Location.X=105|Location.Y=1010|CurrentPartId=2|LibraryPath=*|SourceLibraryName=Altium Content Vault|TargetFileName=*|AreaColor=11599871|Color=128|PartIDLocked=T|DesignItemId=CMP-2000-05600-2|AllPinCount=4
|RECORD=14|OwnerIndex=339|IsNotAccesible=T|OwnerPartId=1|Location.X=65|Location.Y=970|Corner.X=85|Corner.Y=1030|LineWidth=1|Color=128|AreaColor=11599871|IsSolid=T
|RECORD=14|OwnerIndex=339|IsNotAccesible=T|IndexInSheet=1|OwnerPartId=1|Location.X=69|Location.Y=1007|Corner.X=78|Corner.Y=1013|LineWidth=1|Color=16711680|AreaColor=16711680|IsSolid=T
|RECORD=13|OwnerIndex=339|IsNotAccesible=T|IndexInSheet=2|OwnerPartId=1|Location.X=78|Location.Y=1010|Corner.X=85|Corner.Y=1010|LineWidth=1|Color=16711680
|RECORD=14|OwnerIndex=339|IsNotAccesible=T|IndexInSheet=3|OwnerPartId=1|Location.X=69|Location.Y=987|Corner.X=78|Corner.Y=993|LineWidth=1|Color=16711680|AreaColor=16711680|IsSolid=T
|RECORD=13|OwnerIndex=339|IsNotAccesible=T|IndexInSheet=4|OwnerPartId=1|Location.X=78|Location.Y=990|Corner.X=85|Corner.Y=990|LineWidth=1|Color=16711680
|RECORD=4|OwnerIndex=339|IsNotAccesible=T|IndexInSheet=5|OwnerPartId=1|Location.X=78|Location.Y=1022|Justification=8|Color=8388608|FontID=1|Text=1
|RECORD=4|OwnerIndex=339|IsNotAccesible=T|IndexInSheet=6|OwnerPartId=1|Location.X=78|Location.Y=1002|Justification=8|Color=8388608|FontID=1|Text=2
|RECORD=2|OwnerIndex=339|OwnerPartId=1|Electrical=4|PinConglomerate=48|PinLength=20|Location.X=85|Location.Y=1010|Name=1|Designator=1|PinPropagationDelay=0.000000E+000
|RECORD=2|OwnerIndex=339|OwnerPartId=1|Electrical=4|PinConglomerate=48|PinLength=20|Location.X=85|Location.Y=990|Name=2|Designator=2|PinPropagationDelay=0.000000E+000
|RECORD=14|OwnerIndex=339|IsNotAccesible=T|IndexInSheet=9|OwnerPartId=2|Location.X=65|Location.Y=970|Corner.X=85|Corner.Y=1030|LineWidth=1|Color=128|AreaColor=11599871|IsSolid=T
|RECORD=14|OwnerIndex=339|IsNotAccesible=T|IndexInSheet=10|OwnerPartId=2|Location.X=69|Location.Y=1007|Corner.X=78|Corner.Y=1013|LineWidth=1|Color=16711680|AreaColor=16711680|IsSolid=T
|RECORD=13|OwnerIndex=339|IsNotAccesible=T|IndexInSheet=11|OwnerPartId=2|Location.X=78|Location.Y=1010|Corner.X=85|Corner.Y=1010|LineWidth=1|Color=16711680
|RECORD=14|OwnerIndex=339|IsNotAccesible=T|IndexInSheet=12|OwnerPartId=2|Location.X=69|Location.Y=987|Corner.X=78|Corner.Y=993|LineWidth=1|Color=16711680|AreaColor=16711680|IsSolid=T
|RECORD=13|OwnerIndex=339|IsNotAccesible=T|IndexInSheet=13|OwnerPartId=2|Location.X=78|Location.Y=990|Corner.X=85|Corner.Y=990|LineWidth=1|Color=16711680
|RECORD=4|OwnerIndex=339|IsNotAccesible=T|IndexInSheet=14|OwnerPartId=2|Location.X=78|Location.Y=1022|Justification=8|Color=8388608|FontID=1|Text=3
|RECORD=4|OwnerIndex=339|IsNotAccesible=T|IndexInSheet=15|OwnerPartId=2|Location.X=78|Location.Y=1002|Justification=8|Color=8388608|FontID=1|Text=4
|RECORD=2|OwnerIndex=339|OwnerPartId=2|Electrical=4|PinConglomerate=48|PinLength=20|Location.X=85|Location.Y=1010|Name=3|Designator=3|PinPropagationDelay=0.000000E+000
|RECORD=2|OwnerIndex=339|OwnerPartId=2|Electrical=4|PinConglomerate=48|PinLength=20|Location.X=85|Location.Y=990|Name=4|Designator=4|PinPropagationDelay=0.000000E+000
|RECORD=41|OwnerIndex=339|IndexInSheet=18|OwnerPartId=-1|Location.X=65|Location.Y=1030|Color=8388608|FontID=1|IsHidden=T|Text=13A|Name=Current Rating
|RECORD=41|OwnerIndex=339|IndexInSheet=19|OwnerPartId=-1|Location.X=65|Location.Y=1030|Color=8388608|FontID=1|IsHidden=T|Text=Connectors|Name=Device Class L1
|RECORD=41|OwnerIndex=339|IndexInSheet=20|OwnerPartId=-1|Location.X=65|Location.Y=1030|Color=8388608|FontID=1|IsHidden=T|Text=4.2mm|Name=Pitch
|RECORD=41|OwnerIndex=339|IndexInSheet=21|OwnerPartId=-1|Location.X=65|Location.Y=1030|Color=8388608|FontID=1|IsHidden=T|Text=39-30-0040|Name=Package
|RECORD=41|OwnerIndex=339|IndexInSheet=22|OwnerPartId=-1|Location.X=65|Location.Y=1030|Color=8388608|FontID=7|IsHidden=T|Text=https://octopart.com/39-30-0040-molex-277428|Name=Octopart
|RECORD=41|OwnerIndex=339|IndexInSheet=23|OwnerPartId=-1|Location.X=65|Location.Y=1030|Color=8388608|FontID=1|IsHidden=T|Text=Headers & Wire Housings 4 CKT R/A HEADER|Name=Mouser Description
|RECORD=41|OwnerIndex=339|IndexInSheet=24|OwnerPartId=-1|Location.X=65|Location.Y=1030|Color=8388608|FontID=1|IsHidden=T|Text=+105°C|Name=Temperature Range High
|RECORD=41|OwnerIndex=339|IndexInSheet=25|OwnerPartId=-1|Location.X=65|Location.Y=1030|Color=8388608|FontID=1|IsHidden=T|Text=2|Name=Number Of Rows
|RECORD=41|OwnerIndex=339|IndexInSheet=26|OwnerPartId=-1|Location.X=65|Location.Y=1030|Color=8388608|FontID=1|IsHidden=T|Text=600V|Name=Voltage Rating
|RECORD=41|OwnerIndex=339|IndexInSheet=27|OwnerPartId=-1|Location.X=65|Location.Y=1030|Color=8388608|FontID=1|IsHidden=T|Text=Datasheet|Name=ComponentLink2Description
|RECORD=41|OwnerIndex=339|IndexInSheet=28|OwnerPartId=-1|Location.X=65|Location.Y=1030|Color=8388608|FontID=7|IsHidden=T|Text=https://www.molex.com/webdocs/datasheets/pdf/en-us/0039300040_PCB_HEADERS.pdf|Name=ComponentLink2URL
|RECORD=41|OwnerIndex=339|IndexInSheet=29|OwnerPartId=-1|Location.X=65|Location.Y=1030|Color=8388608|FontID=1|IsHidden=T|Text=4|Name=Number Of Contacts
|RECORD=41|OwnerIndex=339|IndexInSheet=30|OwnerPartId=-1|Location.X=65|Location.Y=1030|Color=8388608|FontID=1|IsHidden=T|Text=39-30-0040|Name=Manufacturer Part Number
|RECORD=41|OwnerIndex=339|IndexInSheet=31|OwnerPartId=-1|Location.X=65|Location.Y=1030|Color=8388608|FontID=1|IsHidden=T|Text=Gold,Nickel|Name=Contact Material
|RECORD=41|OwnerIndex=339|IndexInSheet=32|OwnerPartId=-1|Location.X=65|Location.Y=1030|Color=8388608|FontID=1|IsHidden=T|Text=CONN HEADER R/A 4POS 4.2MM|Name=Digikey Description
|RECORD=41|OwnerIndex=339|IndexInSheet=33|OwnerPartId=-1|Location.X=65|Location.Y=1030|Color=8388608|FontID=1|IsHidden=T|Text=-40°C to +105°C|Name=Temperature
|RECORD=41|OwnerIndex=339|IndexInSheet=34|OwnerPartId=-1|Location.X=65|Location.Y=1030|Color=8388608|FontID=1|IsHidden=T|Text=0.4mm|Name=Standoff Height
|RECORD=41|OwnerIndex=339|IndexInSheet=35|OwnerPartId=-1|Location.X=65|Location.Y=1030|Color=8388608|FontID=1|IsHidden=T|Text=No|Name=Automotive
|RECORD=41|OwnerIndex=339|IndexInSheet=36|OwnerPartId=-1|Location.X=65|Location.Y=1030|Color=8388608|FontID=1|IsHidden=T|Text=Headers and Wire Housings|Name=Device Class L2
|RECORD=41|OwnerIndex=339|IndexInSheet=37|OwnerPartId=-1|Location.X=65|Location.Y=1030|Color=8388608|FontID=1|IsHidden=T|Text=Right Angle|Name=Conn Orientation
|RECORD=41|OwnerIndex=339|IndexInSheet=38|OwnerPartId=-1|Location.X=65|Location.Y=1030|Color=8388608|FontID=1|IsHidden=T|Text=TRUE|Name=RoHS
|RECORD=41|OwnerIndex=339|IndexInSheet=39|OwnerPartId=-1|Location.X=65|Location.Y=1030|Color=8388608|FontID=1|IsHidden=T|Text=Yes|Name=Lead Free
|RECORD=41|OwnerIndex=339|IndexInSheet=40|OwnerPartId=-1|Location.X=65|Location.Y=1030|Color=8388608|FontID=1|IsHidden=T|Text=unset|Name=Device Class L3
|RECORD=41|OwnerIndex=339|IndexInSheet=41|OwnerPartId=-1|Location.X=65|Location.Y=1030|Color=8388608|FontID=1|IsHidden=T|Text=Conn|Name=Category
|RECORD=41|OwnerIndex=339|IndexInSheet=42|OwnerPartId=-1|Location.X=65|Location.Y=1030|Color=8388608|FontID=7|IsHidden=T|Text=https://www.molex.com/pdm_docs/sd/039300040_sd.pdf|Name=Footprint Url
|RECORD=41|OwnerIndex=339|IndexInSheet=43|OwnerPartId=-1|Location.X=65|Location.Y=1030|Color=8388608|FontID=1|IsHidden=T|Text=-40°C|Name=Temperature Range Low
|RECORD=41|OwnerIndex=339|IndexInSheet=44|OwnerPartId=-1|Location.X=65|Location.Y=1030|Color=8388608|FontID=1|IsHidden=T|Text=Male|Name=Conn Gender
|RECORD=41|OwnerIndex=339|IndexInSheet=45|OwnerPartId=-1|Location.X=65|Location.Y=1030|Color=8388608|FontID=1|IsHidden=T|Text=Molex|Name=Manufacturer
|RECORD=34|OwnerIndex=339|IndexInSheet=-1|OwnerPartId=-1|Location.X=65|Location.Y=1030|Color=8388608|FontID=1|Text=J38|Name=Designator|ReadOnlyState=1
|RECORD=41|OwnerIndex=339|IndexInSheet=-1|OwnerPartId=1|Location.X=65|Location.Y=960|Color=8388608|FontID=1|Text=39-30-0040|Name=Comment
|RECORD=44|OwnerIndex=339
|RECORD=45|OwnerIndex=392|IndexInSheet=-1|UseComponentLibrary=T|ModelName=FP-39-30-0040-MFG|ModelType=PCBLIB|DatafileCount=1|ModelDatafileEntity0=FP-39-30-0040-MFG|ModelDatafileKind0=PCBLib|IsCurrent=T|DatalinksLocked=T|DatabaseDatalinksLocked=T
|RECORD=46|OwnerIndex=393
|RECORD=48|OwnerIndex=393
|RECORD=1|LibReference=41cc1aee4cbc9fa2660a15773fa0e79|ComponentDescription=IC MONITOR PWR/CURR BIDIR 8-SOIC|PartCount=2|DisplayModeCount=1|IndexInSheet=50|OwnerPartId=-1|Location.X=340|Location.Y=755|CurrentPartId=1|LibraryPath=*|SourceLibraryName=Altium Content Vault|TargetFileName=*|AreaColor=11599871|Color=128|PartIDLocked=T|DesignItemId=CMP-0704-00005-3|AllPinCount=8
|RECORD=14|OwnerIndex=396|IsNotAccesible=T|OwnerPartId=1|Location.X=360|Location.Y=675|Corner.X=450|Corner.Y=765|LineWidth=1|Color=128|AreaColor=11599871|IsSolid=T
|RECORD=2|OwnerIndex=396|OwnerPartId=1|PinConglomerate=58|PinLength=20|Location.X=360|Location.Y=695|Name=VIN+|Designator=8|PinName_PositionConglomerate=16|Name_CustomFontID=1|PinDesignator_PositionConglomerate=16|Designator_CustomFontID=1|PinPropagationDelay=0.000000E+000
|RECORD=2|OwnerIndex=396|OwnerPartId=1|PinConglomerate=58|PinLength=20|Location.X=360|Location.Y=685|Name=VIN-|Designator=7|PinName_PositionConglomerate=16|Name_CustomFontID=1|PinDesignator_PositionConglomerate=16|Designator_CustomFontID=1|PinPropagationDelay=0.000000E+000
|RECORD=2|OwnerIndex=396|OwnerPartId=1|PinConglomerate=56|PinLength=20|Location.X=450|Location.Y=715|Name=A0|Designator=2|PinName_PositionConglomerate=16|Name_CustomFontID=1|PinDesignator_PositionConglomerate=16|Designator_CustomFontID=1|PinPropagationDelay=0.000000E+000
|RECORD=2|OwnerIndex=396|OwnerPartId=1|PinConglomerate=56|PinLength=20|Location.X=450|Location.Y=705|Name=A1|Designator=1|PinName_PositionConglomerate=16|Name_CustomFontID=1|PinDesignator_PositionConglomerate=16|Designator_CustomFontID=1|PinPropagationDelay=0.000000E+000
|RECORD=2|OwnerIndex=396|OwnerPartId=1|SymBol_InnerEdge=3|Electrical=1|PinConglomerate=56|PinLength=20|Location.X=450|Location.Y=735|Name=SCL|Designator=4|PinName_PositionConglomerate=16|Name_CustomFontID=1|PinDesignator_PositionConglomerate=16|Designator_CustomFontID=1|PinPropagationDelay=0.000000E+000
|RECORD=2|OwnerIndex=396|OwnerPartId=1|Electrical=1|PinConglomerate=56|PinLength=20|Location.X=450|Location.Y=755|Name=SDA|Designator=3|PinName_PositionConglomerate=16|Name_CustomFontID=1|PinDesignator_PositionConglomerate=16|Designator_CustomFontID=1|PinPropagationDelay=0.000000E+000
|RECORD=2|OwnerIndex=396|OwnerPartId=1|Electrical=7|PinConglomerate=58|PinLength=20|Location.X=360|Location.Y=755|Name=VS|Designator=5|PinName_PositionConglomerate=16|Name_CustomFontID=1|PinDesignator_PositionConglomerate=16|Designator_CustomFontID=1|PinPropagationDelay=0.000000E+000
|RECORD=2|OwnerIndex=396|OwnerPartId=1|Electrical=7|PinConglomerate=56|PinLength=20|Location.X=450|Location.Y=685|Name=GND|Designator=6|PinName_PositionConglomerate=16|Name_CustomFontID=1|PinDesignator_PositionConglomerate=16|Designator_CustomFontID=1|PinPropagationDelay=0.000000E+000
|RECORD=41|OwnerIndex=396|IndexInSheet=9|OwnerPartId=-1|Location.X=338|Location.Y=765|Color=8388608|FontID=1|IsHidden=T|Text=3V|Name=Min Supply Voltage
|RECORD=41|OwnerIndex=396|IndexInSheet=10|OwnerPartId=-1|Location.X=338|Location.Y=765|Color=8388608|FontID=1|IsHidden=T|Text=100dB|Name=Common Mode Rejection Ratio
|RECORD=41|OwnerIndex=396|IndexInSheet=11|OwnerPartId=-1|Location.X=338|Location.Y=765|Color=8388608|FontID=1|IsHidden=T|Text=Tape and Reel|Name=Packaging
|RECORD=41|OwnerIndex=396|IndexInSheet=12|OwnerPartId=-1|Location.X=338|Location.Y=765|Color=8388608|FontID=1|IsHidden=T|Text=No SVHC|Name=REACH SVHC
|RECORD=41|OwnerIndex=396|IndexInSheet=13|OwnerPartId=-1|Location.X=338|Location.Y=765|Color=8388608|FontID=1|IsHidden=T|Text=125°C|Name=Max Operating Temperature
|RECORD=41|OwnerIndex=396|IndexInSheet=14|OwnerPartId=-1|Location.X=338|Location.Y=765|Color=8388608|FontID=1|IsHidden=T|Text=8|Name=Number of Pins
|RECORD=41|OwnerIndex=396|IndexInSheet=15|OwnerPartId=-1|Location.X=338|Location.Y=765|Color=8388608|FontID=1|IsHidden=T|Text=10mA|Name=Output Current
|RECORD=41|OwnerIndex=396|IndexInSheet=16|OwnerPartId=-1|Location.X=338|Location.Y=765|Color=8388608|FontID=1|IsHidden=T|Text=Lead Free|Name=Lead Free
|RECORD=41|OwnerIndex=396|IndexInSheet=17|OwnerPartId=-1|Location.X=338|Location.Y=765|Color=8388608|FontID=1|IsHidden=T|Text=1|Name=Package Quantity
|RECORD=41|OwnerIndex=396|IndexInSheet=18|OwnerPartId=-1|Location.X=338|Location.Y=765|Color=8388608|FontID=1|IsHidden=T|Text=No|Name=Radiation Hardening
|RECORD=41|OwnerIndex=396|IndexInSheet=19|OwnerPartId=-1|Location.X=338|Location.Y=765|Color=8388608|FontID=1|IsHidden=T|Text=SOIC|Name=Case/Package
|RECORD=41|OwnerIndex=396|IndexInSheet=20|OwnerPartId=-1|Location.X=338|Location.Y=765|Color=8388608|FontID=1|IsHidden=T|Text=1|Name=Number of Amplifiers
|RECORD=41|OwnerIndex=396|IndexInSheet=21|OwnerPartId=-1|Location.X=338|Location.Y=765|Color=8388608|FontID=1|IsHidden=T|Text=-40°C|Name=Min Operating Temperature
|RECORD=41|OwnerIndex=396|IndexInSheet=22|OwnerPartId=-1|Location.X=338|Location.Y=765|Color=8388608|FontID=1|IsHidden=T|Text=0.5%|Name=Accuracy
|RECORD=41|OwnerIndex=396|IndexInSheet=23|OwnerPartId=-1|Location.X=338|Location.Y=765|Color=8388608|FontID=1|IsHidden=T|Text=1mA|Name=Supply Current
|RECORD=41|OwnerIndex=396|IndexInSheet=24|OwnerPartId=-1|Location.X=338|Location.Y=765|Color=8388608|FontID=1|IsHidden=T|Text=Gold|Name=Contact Plating
|RECORD=41|OwnerIndex=396|IndexInSheet=25|OwnerPartId=-1|Location.X=338|Location.Y=765|Color=8388608|FontID=1|IsHidden=T|Text=700uA|Name=Quiescent Current
|RECORD=41|OwnerIndex=396|IndexInSheet=26|OwnerPartId=-1|Location.X=338|Location.Y=765|Color=8388608|FontID=1|IsHidden=T|Text=Zero-Drift|Name=Series
|RECORD=41|OwnerIndex=396|IndexInSheet=27|OwnerPartId=-1|Location.X=338|Location.Y=765|Color=8388608|FontID=1|IsHidden=T|Text=1mA|Name=Nominal Supply Current
|RECORD=41|OwnerIndex=396|IndexInSheet=28|OwnerPartId=-1|Location.X=338|Location.Y=765|Color=8388608|FontID=1|IsHidden=T|Text=11kHz|Name=Bandwidth
|RECORD=41|OwnerIndex=396|IndexInSheet=29|OwnerPartId=-1|Location.X=338|Location.Y=765|Color=8388608|FontID=1|IsHidden=T|Text=40uV|Name=Input Offset Voltage (Vos)
|RECORD=41|OwnerIndex=396|IndexInSheet=30|OwnerPartId=-1|Location.X=338|Location.Y=765|Color=8388608|FontID=1|IsHidden=T|Text=5.5V|Name=Max Supply Voltage
|RECORD=41|OwnerIndex=396|IndexInSheet=31|OwnerPartId=-1|Location.X=338|Location.Y=765|Color=8388608|FontID=1|IsHidden=T|Text=Yes|Name=RoHS Compliant
|RECORD=34|OwnerIndex=396|IndexInSheet=-1|OwnerPartId=-1|Location.X=360|Location.Y=765|Color=8388608|FontID=1|Text=U2|Name=Designator|ReadOnlyState=1
|RECORD=41|OwnerIndex=396|IndexInSheet=-1|OwnerPartId=1|Location.X=360|Location.Y=665|Color=8388608|FontID=1|Text=INA219BIDR|Name=Comment
|RECORD=44|OwnerIndex=396
|RECORD=45|OwnerIndex=439|IndexInSheet=-1|UseComponentLibrary=T|ModelName=FP-D0008A-MFG|ModelType=PCBLIB|DatafileCount=1|ModelDatafileEntity0=FP-D0008A-MFG|ModelDatafileKind0=PCBLib|IsCurrent=T|DatalinksLocked=T|DatabaseDatalinksLocked=T
|RECORD=46|OwnerIndex=440
|RECORD=48|OwnerIndex=440
|RECORD=45|OwnerIndex=439|IndexInSheet=-1|UseComponentLibrary=T|ModelName=FP-D0008A-IPC_A|ModelType=PCBLIB|DatafileCount=1|ModelDatafileEntity0=FP-D0008A-IPC_A|ModelDatafileKind0=PCBLib|DatalinksLocked=T|DatabaseDatalinksLocked=T
|RECORD=46|OwnerIndex=443
|RECORD=48|OwnerIndex=443
|RECORD=45|OwnerIndex=439|IndexInSheet=-1|UseComponentLibrary=T|ModelName=FP-D0008A-IPC_C|ModelType=PCBLIB|DatafileCount=1|ModelDatafileEntity0=FP-D0008A-IPC_C|ModelDatafileKind0=PCBLib|DatalinksLocked=T|DatabaseDatalinksLocked=T
|RECORD=46|OwnerIndex=446
|RECORD=48|OwnerIndex=446
|RECORD=45|OwnerIndex=439|IndexInSheet=-1|UseComponentLibrary=T|ModelName=FP-D0008A-IPC_B|ModelType=PCBLIB|DatafileCount=1|ModelDatafileEntity0=FP-D0008A-IPC_B|ModelDatafileKind0=PCBLib|DatalinksLocked=T|DatabaseDatalinksLocked=T
|RECORD=46|OwnerIndex=449
|RECORD=48|OwnerIndex=449
|RECORD=1|LibReference=RES|PartCount=2|DisplayModeCount=2|IndexInSheet=51|OwnerPartId=-1|Location.X=440|Location.Y=925|CurrentPartId=1|SourceLibraryName=Altium Content Vault|TargetFileName=*|AreaColor=11599871|Color=128|PartIDLocked=F|DesignItemId=CMP-2003-04334-1|AllPinCount=2
|RECORD=2|OwnerIndex=452|OwnerPartId=1|OwnerPartDisplayMode=1|FormalType=1|Electrical=4|PinConglomerate=32|PinLength=10|Location.X=460|Location.Y=915|Name=2|Designator=2|PinPropagationDelay=0.000000E+000
|RECORD=2|OwnerIndex=452|OwnerPartId=1|OwnerPartDisplayMode=1|FormalType=1|Electrical=4|PinConglomerate=34|PinLength=10|Location.X=440|Location.Y=915|Name=1|Designator=1|PinPropagationDelay=0.000000E+000
|RECORD=14|OwnerIndex=452|IsNotAccesible=T|IndexInSheet=2|OwnerPartId=1|OwnerPartDisplayMode=1|Location.X=440|Location.Y=911|Corner.X=460|Corner.Y=919|LineWidth=1|Color=16711680|AreaColor=11599871
|RECORD=2|OwnerIndex=452|OwnerPartId=1|FormalType=1|Electrical=4|PinConglomerate=32|PinLength=10|Location.X=460|Location.Y=915|Name=2|Designator=2|PinPropagationDelay=0.000000E+000
|RECORD=2|OwnerIndex=452|OwnerPartId=1|FormalType=1|Electrical=4|PinConglomerate=34|PinLength=10|Location.X=440|Location.Y=915|Name=1|Designator=1|PinPropagationDelay=0.000000E+000
|RECORD=6|OwnerIndex=452|IsNotAccesible=T|IndexInSheet=5|OwnerPartId=1|LineWidth=1|Color=16711680|LocationCount=10|X1=460|Y1=915|X2=456|Y2=915|X3=455|Y3=913|X4=453|Y4=917|X5=451|Y5=913|X6=449|Y6=917|X7=447|Y7=913|X8=445|Y8=917|X9=444|Y9=915|X10=440|Y10=915
|RECORD=41|OwnerIndex=452|IndexInSheet=6|OwnerPartId=-1|Location.X=428|Location.Y=928|Color=8388608|FontID=1|IsHidden=T|Text=Vishay Dale|Name=Manufacturer
|RECORD=41|OwnerIndex=452|IndexInSheet=7|OwnerPartId=-1|Location.X=428|Location.Y=928|Color=8388608|FontID=1|IsHidden=T|Text=WSL12062L000FEA18|Name=Part Number
|RECORD=34|OwnerIndex=452|IndexInSheet=-1|OwnerPartId=-1|Location.X=439|Location.Y=918|Color=8388608|FontID=1|Text=R7|Name=Designator|ReadOnlyState=1
|RECORD=41|OwnerIndex=452|IndexInSheet=-1|OwnerPartId=-1|Location.X=439|Location.Y=902|Color=8388608|FontID=1|Text=2mOhm_1%_1206|Name=Comment
|RECORD=44|OwnerIndex=452
|RECORD=45|OwnerIndex=467|IndexInSheet=-1|Description=Chip Resistor, 2-Leads, Body 3.20x1.60mm, IPC Medium Density|UseComponentLibrary=T|ModelName=RESC3216X89X64NL25T25|ModelType=PCBLIB|DatafileCount=1|ModelDatafileEntity0=RESC3216X89X64NL25T25|ModelDatafileKind0=PCBLib|IsCurrent=T|DatalinksLocked=T|DatabaseDatalinksLocked=T
|RECORD=46|OwnerIndex=468
|RECORD=48|OwnerIndex=468
|RECORD=41|OwnerIndex=470|IndexInSheet=-1|OwnerPartId=-1|Color=8388608|FontID=1|IsHidden=T|Text=2D|Name=Available Preview Images
|RECORD=45|OwnerIndex=467|IndexInSheet=-1|Description=Chip Resistor, 2-Leads, Body 3.20x1.60mm, IPC High Density|UseComponentLibrary=T|ModelName=RESC3216X89X64LL25T25|ModelType=PCBLIB|DatafileCount=1|ModelDatafileEntity0=RESC3216X89X64LL25T25|ModelDatafileKind0=PCBLib|DatalinksLocked=T|DatabaseDatalinksLocked=T
|RECORD=46|OwnerIndex=472
|RECORD=48|OwnerIndex=472
|RECORD=41|OwnerIndex=474|IndexInSheet=-1|OwnerPartId=-1|Color=8388608|FontID=1|IsHidden=T|Text=2D|Name=Available Preview Images
|RECORD=45|OwnerIndex=467|IndexInSheet=-1|Description=Chip Resistor, 2-Leads, Body 3.20x1.60mm, IPC Low Density|UseComponentLibrary=T|ModelName=RESC3216X89X64ML25T25|ModelType=PCBLIB|DatafileCount=1|ModelDatafileEntity0=RESC3216X89X64ML25T25|ModelDatafileKind0=PCBLib|DatalinksLocked=T|DatabaseDatalinksLocked=T
|RECORD=46|OwnerIndex=476
|RECORD=48|OwnerIndex=476
|RECORD=41|OwnerIndex=478|IndexInSheet=-1|OwnerPartId=-1|Color=8388608|FontID=1|IsHidden=T|Text=2D|Name=Available Preview Images
|RECORD=17|IndexInSheet=52|OwnerPartId=-1|ShowNetName=T|Location.X=405|Location.Y=980|Orientation=1|Color=128|FontID=1|Text=+12V_SENS
|RECORD=1|LibReference=CAP|PartCount=2|DisplayModeCount=2|IndexInSheet=53|OwnerPartId=-1|Location.X=230|Location.Y=720|Orientation=1|CurrentPartId=1|SourceLibraryName=Altium Content Vault|TargetFileName=*|AreaColor=11599871|Color=128|PartIDLocked=F|DesignItemId=CMP-2008-00031-1|AllPinCount=2
|RECORD=2|OwnerIndex=481|OwnerPartId=1|OwnerPartDisplayMode=1|FormalType=1|Electrical=4|PinConglomerate=35|PinLength=10|Location.X=240|Location.Y=720|Name=1|Designator=1|PinPropagationDelay=0.000000E+000
|RECORD=2|OwnerIndex=481|OwnerPartId=1|OwnerPartDisplayMode=1|FormalType=1|Electrical=4|PinConglomerate=33|PinLength=10|Location.X=240|Location.Y=730|Name=2|Designator=2|PinPropagationDelay=0.000000E+000
|RECORD=13|OwnerIndex=481|IsNotAccesible=T|IndexInSheet=2|OwnerPartId=1|OwnerPartDisplayMode=1|Location.X=248|Location.Y=720|Corner.X=232|Corner.Y=720|LineWidth=1|Color=16711680
|RECORD=13|OwnerIndex=481|IsNotAccesible=T|IndexInSheet=3|OwnerPartId=1|OwnerPartDisplayMode=1|Location.X=240|Location.Y=724|Corner.X=240|Corner.Y=730|LineWidth=1|Color=16711680
|RECORD=12|OwnerIndex=481|IsNotAccesible=T|IndexInSheet=4|OwnerPartId=1|OwnerPartDisplayMode=1|Location.X=240|Location.Y=740|Radius=16|LineWidth=1|StartAngle=241.000|EndAngle=270.000|Color=16711680
|RECORD=12|OwnerIndex=481|IsNotAccesible=T|IndexInSheet=5|OwnerPartId=1|OwnerPartDisplayMode=1|Location.X=240|Location.Y=740|Radius=16|LineWidth=1|StartAngle=270.000|EndAngle=299.000|Color=16711680
|RECORD=2|OwnerIndex=481|OwnerPartId=1|FormalType=1|Electrical=4|PinConglomerate=35|PinLength=10|Location.X=240|Location.Y=720|Name=1|Designator=1|PinPropagationDelay=0.000000E+000
|RECORD=2|OwnerIndex=481|OwnerPartId=1|FormalType=1|Electrical=4|PinConglomerate=33|PinLength=10|Location.X=240|Location.Y=730|Name=2|Designator=2|PinPropagationDelay=0.000000E+000
|RECORD=13|OwnerIndex=481|IsNotAccesible=T|IndexInSheet=8|OwnerPartId=1|Location.X=232|Location.Y=727|Corner.X=248|Corner.Y=727|LineWidth=1|Color=16711680
|RECORD=13|OwnerIndex=481|IsNotAccesible=T|IndexInSheet=9|OwnerPartId=1|Location.X=248|Location.Y=723|Corner.X=232|Corner.Y=723|LineWidth=1|Color=16711680
|RECORD=6|OwnerIndex=481|IsNotAccesible=T|IndexInSheet=10|OwnerPartId=1|LineWidth=1|Color=16711680|LocationCount=2|X1=240|Y1=720|X2=240|Y2=723
|RECORD=6|OwnerIndex=481|IsNotAccesible=T|IndexInSheet=11|OwnerPartId=1|LineWidth=1|Color=16711680|LocationCount=2|X1=240|Y1=730|X2=240|Y2=727
|RECORD=41|OwnerIndex=481|IndexInSheet=12|OwnerPartId=-1|Location.X=231|Location.Y=742|Color=8388608|FontID=1|IsHidden=T|Text=LD02YD104KAB2A|Name=Part Number
|RECORD=41|OwnerIndex=481|IndexInSheet=13|OwnerPartId=-1|Location.X=231|Location.Y=742|Color=8388608|FontID=1|IsHidden=T|Text=AVX Interconnect / Elco|Name=Manufacturer
|RECORD=34|OwnerIndex=481|IndexInSheet=-1|OwnerPartId=-1|Location.X=240|Location.Y=730|Orientation=1|Color=8388608|FontID=2|Text=C19|Name=Designator|ReadOnlyState=1
|RECORD=41|OwnerIndex=481|IndexInSheet=-1|OwnerPartId=-1|Location.X=250|Location.Y=735|Orientation=1|Color=8388608|FontID=2|Text=0.1uF_0402|Name=Comment
|RECORD=44|OwnerIndex=481
|RECORD=45|OwnerIndex=502|IndexInSheet=-1|Description=Chip Capacitor, 2-Leads, Body 1.00x0.50mm, IPC Medium Density|UseComponentLibrary=T|ModelName=CAPC1005X56X25NL10T15|ModelType=PCBLIB|DatafileCount=1|ModelDatafileEntity0=CAPC1005X56X25NL10T15|ModelDatafileKind0=PCBLib|IsCurrent=T|DatalinksLocked=T|DatabaseDatalinksLocked=T
|RECORD=46|OwnerIndex=503
|RECORD=48|OwnerIndex=503
|RECORD=41|OwnerIndex=505|IndexInSheet=-1|OwnerPartId=-1|Color=8388608|FontID=1|IsHidden=T|Text=2D|Name=Available Preview Images
|RECORD=45|OwnerIndex=502|IndexInSheet=-1|Description=Chip Capacitor, 2-Leads, Body 1.00x0.50mm, IPC High Density|UseComponentLibrary=T|ModelName=CAPC1005X56X25LL10T15|ModelType=PCBLIB|DatafileCount=1|ModelDatafileEntity0=CAPC1005X56X25LL10T15|ModelDatafileKind0=PCBLib|DatalinksLocked=T|DatabaseDatalinksLocked=T
|RECORD=46|OwnerIndex=507
|RECORD=48|OwnerIndex=507
|RECORD=41|OwnerIndex=509|IndexInSheet=-1|OwnerPartId=-1|Color=8388608|FontID=1|IsHidden=T|Text=2D|Name=Available Preview Images
|RECORD=45|OwnerIndex=502|IndexInSheet=-1|Description=Chip Capacitor, 2-Leads, Body 1.00x0.50mm, IPC Low Density|UseComponentLibrary=T|ModelName=CAPC1005X56X25ML10T15|ModelType=PCBLIB|DatafileCount=1|ModelDatafileEntity0=CAPC1005X56X25ML10T15|ModelDatafileKind0=PCBLib|DatalinksLocked=T|DatabaseDatalinksLocked=T
|RECORD=46|OwnerIndex=511
|RECORD=48|OwnerIndex=511
|RECORD=41|OwnerIndex=513|IndexInSheet=-1|OwnerPartId=-1|Color=8388608|FontID=1|IsHidden=T|Text=2D|Name=Available Preview Images
|RECORD=1|LibReference=b4654b650e69147ec39a6b967a45e02|ComponentDescription=Multilayer Ceramic Capacitor 10uF 16V X5R 20% SMD 0603 T/R|PartCount=2|DisplayModeCount=1|IndexInSheet=54|OwnerPartId=-1|Location.X=200|Location.Y=735|CurrentPartId=1|LibraryPath=*|SourceLibraryName=Altium Content Vault|TargetFileName=*|AreaColor=11599871|Color=128|PartIDLocked=T|DesignItemId=CMP-2000-06226-4|AllPinCount=2
|RECORD=2|OwnerIndex=515|OwnerPartId=1|Electrical=4|PinConglomerate=49|PinLength=7|Location.X=200|Location.Y=728|Name=1|Designator=1|PinPropagationDelay=0.000000E+000
|RECORD=2|OwnerIndex=515|OwnerPartId=1|Electrical=4|PinConglomerate=51|PinLength=6|Location.X=200|Location.Y=721|Name=2|Designator=2|PinPropagationDelay=0.000000E+000
|RECORD=13|OwnerIndex=515|IsNotAccesible=T|IndexInSheet=2|OwnerPartId=1|Location.X=210|Location.Y=728|Corner.X=190|Corner.Y=728|LineWidth=1|Color=16711680
|RECORD=13|OwnerIndex=515|IsNotAccesible=T|IndexInSheet=3|OwnerPartId=1|Location.X=210|Location.Y=722|Corner.X=190|Corner.Y=722|LineWidth=1|Color=16711680
|RECORD=13|OwnerIndex=515|IsNotAccesible=T|IndexInSheet=4|OwnerPartId=1|Location.X=200|Location.Y=728|Corner.X=200|Corner.Y=731|LineWidth=1|Color=16711680
|RECORD=13|OwnerIndex=515|IsNotAccesible=T|IndexInSheet=5|OwnerPartId=1|Location.X=200|Location.Y=721|Corner.X=200|Corner.Y=720|LineWidth=1|Color=16711680
|RECORD=41|OwnerIndex=515|IndexInSheet=6|OwnerPartId=-1|Location.X=189|Location.Y=737|Color=8388608|FontID=1|IsHidden=T|Text=Tape and Reel|Name=Packaging
|RECORD=41|OwnerIndex=515|IndexInSheet=7|OwnerPartId=-1|Location.X=189|Location.Y=737|Color=8388608|FontID=1|IsHidden=T|Text=Flat|Name=Construction
|RECORD=41|OwnerIndex=515|IndexInSheet=8|OwnerPartId=-1|Location.X=189|Location.Y=737|Color=8388608|FontID=1|IsHidden=T|Text=0.8mm|Name=Height
|RECORD=41|OwnerIndex=515|IndexInSheet=9|OwnerPartId=-1|Location.X=189|Location.Y=737|Color=8388608|FontID=1|IsHidden=T|Text=85°C|Name=Max Operating Temperature
|RECORD=41|OwnerIndex=515|IndexInSheet=10|OwnerPartId=-1|Location.X=189|Location.Y=737|Color=8388608|FontID=1|IsHidden=T|Text=X5R|Name=Dielectric
|RECORD=41|OwnerIndex=515|IndexInSheet=11|OwnerPartId=-1|Location.X=189|Location.Y=737|Color=8388608|FontID=1|IsHidden=T|Text=1608|Name=Case Code (Metric)
|RECORD=41|OwnerIndex=515|IndexInSheet=12|OwnerPartId=-1|Location.X=189|Location.Y=737|Color=8388608|FontID=1|IsHidden=T|Text=16V|Name=Voltage Rating (DC)
|RECORD=41|OwnerIndex=515|IndexInSheet=13|OwnerPartId=-1|Location.X=189|Location.Y=737|Color=8388608|FontID=1|IsHidden=T|Text=0.031inch|Name=Width
|RECORD=41|OwnerIndex=515|IndexInSheet=14|OwnerPartId=-1|Location.X=189|Location.Y=737|Color=8388608|FontID=1|IsHidden=T|Text=16V|Name=Voltage Rating
|RECORD=41|OwnerIndex=515|IndexInSheet=15|OwnerPartId=-1|Location.X=189|Location.Y=737|Color=8388608|FontID=1|IsHidden=T|Text=0.063inch|Name=Length
|RECORD=41|OwnerIndex=515|IndexInSheet=16|OwnerPartId=-1|Location.X=189|Location.Y=737|Color=8388608|FontID=1|IsHidden=T|Text=Yes|Name=RoHS Compliant
|RECORD=41|OwnerIndex=515|IndexInSheet=17|OwnerPartId=-1|Location.X=189|Location.Y=737|Color=8388608|FontID=1|IsHidden=T|Text=Halogen Free|Name=Halogen Free
|RECORD=41|OwnerIndex=515|IndexInSheet=18|OwnerPartId=-1|Location.X=189|Location.Y=737|Color=8388608|FontID=1|IsHidden=T|Text=0603|Name=Case Code (Imperial)
|RECORD=41|OwnerIndex=515|IndexInSheet=19|OwnerPartId=-1|Location.X=189|Location.Y=737|Color=8388608|FontID=1|IsHidden=T|Text=10uF|Name=Capacitance
|RECORD=41|OwnerIndex=515|IndexInSheet=20|OwnerPartId=-1|Location.X=189|Location.Y=737|Color=8388608|FontID=1|IsHidden=T|Text=Surface Mount|Name=Mount
|RECORD=41|OwnerIndex=515|IndexInSheet=21|OwnerPartId=-1|Location.X=189|Location.Y=737|Color=8388608|FontID=1|IsHidden=T|Text=0.031inch|Name=Thickness
|RECORD=41|OwnerIndex=515|IndexInSheet=22|OwnerPartId=-1|Location.X=189|Location.Y=737|Color=8388608|FontID=1|IsHidden=T|Text=20%|Name=Tolerance
|RECORD=41|OwnerIndex=515|IndexInSheet=23|OwnerPartId=-1|Location.X=189|Location.Y=737|Color=8388608|FontID=1|IsHidden=T|Text=-55°C|Name=Min Operating Temperature
|RECORD=41|OwnerIndex=515|IndexInSheet=24|OwnerPartId=-1|Location.X=189|Location.Y=737|Color=8388608|FontID=1|IsHidden=T|Text=M|Name=Series
|RECORD=41|OwnerIndex=515|IndexInSheet=25|OwnerPartId=-1|Location.X=189|Location.Y=737|Color=8388608|FontID=1|IsHidden=T|Text=SMD/SMT|Name=Termination
|RECORD=41|OwnerIndex=515|IndexInSheet=26|OwnerPartId=-1|Location.X=189|Location.Y=737|Color=8388608|FontID=1|IsHidden=T|Text=0603|Name=Case/Package
|RECORD=41|OwnerIndex=515|IndexInSheet=27|OwnerPartId=-1|Location.X=189|Location.Y=737|Color=8388608|FontID=1|IsHidden=T|Text=1|Name=Package Quantity
|RECORD=34|OwnerIndex=515|IndexInSheet=-1|OwnerPartId=-1|Location.X=190|Location.Y=715|Orientation=1|Color=8388608|FontID=2|Text=C20|Name=Designator|ReadOnlyState=1
|RECORD=41|OwnerIndex=515|IndexInSheet=-1|OwnerPartId=1|Location.X=220|Location.Y=700|Orientation=1|Color=8388608|FontID=2|Text=10uF_16V_0603|Name=Comment
|RECORD=44|OwnerIndex=515
|RECORD=45|OwnerIndex=548|IndexInSheet=-1|UseComponentLibrary=T|ModelName=FP-0603-L_1_6_0_2-W_0_8_0-MFG|ModelType=PCBLIB|DatafileCount=1|ModelDatafileEntity0=FP-0603-L_1_6_0_2-W_0_8_0-MFG|ModelDatafileKind0=PCBLib|IsCurrent=T|DatalinksLocked=T|DatabaseDatalinksLocked=T
|RECORD=46|OwnerIndex=549
|RECORD=48|OwnerIndex=549
|RECORD=45|OwnerIndex=548|IndexInSheet=-1|UseComponentLibrary=T|ModelName=FP-0603-L_1_6_0_2-W_0_8_0-IPC_B|ModelType=PCBLIB|DatafileCount=1|ModelDatafileEntity0=FP-0603-L_1_6_0_2-W_0_8_0-IPC_B|ModelDatafileKind0=PCBLib|DatalinksLocked=T|DatabaseDatalinksLocked=T
|RECORD=46|OwnerIndex=552
|RECORD=48|OwnerIndex=552
|RECORD=45|OwnerIndex=548|IndexInSheet=-1|UseComponentLibrary=T|ModelName=FP-0603-L_1_6_0_2-W_0_8_0-IPC_C|ModelType=PCBLIB|DatafileCount=1|ModelDatafileEntity0=FP-0603-L_1_6_0_2-W_0_8_0-IPC_C|ModelDatafileKind0=PCBLib|DatalinksLocked=T|DatabaseDatalinksLocked=T
|RECORD=46|OwnerIndex=555
|RECORD=48|OwnerIndex=555
|RECORD=45|OwnerIndex=548|IndexInSheet=-1|UseComponentLibrary=T|ModelName=FP-0603-L_1_6_0_2-W_0_8_0-IPC_A|ModelType=PCBLIB|DatafileCount=1|ModelDatafileEntity0=FP-0603-L_1_6_0_2-W_0_8_0-IPC_A|ModelDatafileKind0=PCBLib|DatalinksLocked=T|DatabaseDatalinksLocked=T
|RECORD=46|OwnerIndex=558
|RECORD=48|OwnerIndex=558
|RECORD=17|IndexInSheet=55|OwnerPartId=-1|ShowNetName=T|Location.X=200|Location.Y=775|Orientation=1|Color=128|FontID=1|Text=+3.3V
|RECORD=17|IndexInSheet=56|OwnerPartId=-1|Style=4|ShowNetName=T|Location.X=200|Location.Y=705|Orientation=3|Color=128|FontID=1|Text=GND
|RECORD=17|IndexInSheet=57|OwnerPartId=-1|Style=4|ShowNetName=T|Location.X=240|Location.Y=705|Orientation=3|Color=128|FontID=1|Text=GND
|RECORD=17|IndexInSheet=58|OwnerPartId=-1|ShowNetName=T|Location.X=320|Location.Y=720|Orientation=1|Color=128|FontID=1|Text=+12V_SENS
|RECORD=17|IndexInSheet=59|OwnerPartId=-1|ShowNetName=T|Location.X=280|Location.Y=720|Orientation=1|Color=128|FontID=1|Text=+12V
|RECORD=17|IndexInSheet=60|OwnerPartId=-1|Style=4|ShowNetName=T|Location.X=480|Location.Y=680|Orientation=3|Color=128|FontID=1|Text=GND
|RECORD=17|IndexInSheet=61|OwnerPartId=-1|ShowNetName=T|Location.X=515|Location.Y=735|Color=255|FontID=1|Text=SCL|IsCrossSheetConnector=T
|RECORD=17|IndexInSheet=62|OwnerPartId=-1|ShowNetName=T|Location.X=515|Location.Y=755|Color=255|FontID=1|Text=SDA|IsCrossSheetConnector=T
|RECORD=1|LibReference=RES-2|ComponentDescription=Chip Resistor, 0 Ohm, 0.1 W, -55 to 155 degC, 0402 (1005 Metric), RoHS, Tape and Reel|PartCount=2|DisplayModeCount=1|IndexInSheet=63|OwnerPartId=-1|Location.X=500|Location.Y=715|CurrentPartId=1|LibraryPath=*|SourceLibraryName=Altium Content Vault|TargetFileName=*|AreaColor=11599871|Color=128|PartIDLocked=T|DesignItemId=CMP-2000-07451-1|AllPinCount=2
|RECORD=2|OwnerIndex=569|OwnerPartId=1|FormalType=1|Electrical=4|PinConglomerate=32|PinLength=10|Location.X=520|Location.Y=715|Name=2|Designator=2|PinPropagationDelay=0.000000E+000
|RECORD=2|OwnerIndex=569|OwnerPartId=1|FormalType=1|Electrical=4|PinConglomerate=34|PinLength=10|Location.X=500|Location.Y=715|Name=1|Designator=1|PinPropagationDelay=0.000000E+000
|RECORD=6|OwnerIndex=569|IsNotAccesible=T|IndexInSheet=2|OwnerPartId=1|LineWidth=1|Color=16711680|LocationCount=10|X1=520|Y1=715|X2=516|Y2=715|X3=515|Y3=713|X4=513|Y4=717|X5=511|Y5=713|X6=509|Y6=717|X7=507|Y7=713|X8=505|Y8=717|X9=504|Y9=715|X10=500|Y10=715
|RECORD=41|OwnerIndex=569|IndexInSheet=3|OwnerPartId=-1|Location.X=488|Location.Y=730|Color=8388608|FontID=1|IsHidden=T|Text=50V|Name=Voltage Rating (DC)
|RECORD=41|OwnerIndex=569|IndexInSheet=4|OwnerPartId=-1|Location.X=488|Location.Y=730|Color=8388608|FontID=1|IsHidden=T|Text=2|Name=Number of Terminations
|RECORD=41|OwnerIndex=569|IndexInSheet=5|OwnerPartId=-1|Location.X=488|Location.Y=730|Color=8388608|FontID=1|IsHidden=T|Text=SurfaceMount|Name=Mount
|RECORD=41|OwnerIndex=569|IndexInSheet=6|OwnerPartId=-1|Location.X=488|Location.Y=730|Color=8388608|FontID=1|IsHidden=T|Text=0.35mm|Name=Height
|RECORD=41|OwnerIndex=569|IndexInSheet=7|OwnerPartId=-1|Location.X=488|Location.Y=730|Color=8388608|FontID=1|IsHidden=T|Text=TapeandReel|Name=Packaging
|RECORD=41|OwnerIndex=569|IndexInSheet=8|OwnerPartId=-1|Location.X=488|Location.Y=730|Color=8388608|FontID=1|IsHidden=T|Text=Tin|Name=Contact Plating
|RECORD=41|OwnerIndex=569|IndexInSheet=9|OwnerPartId=-1|Location.X=488|Location.Y=730|Color=8388608|FontID=7|IsHidden=T|Text=http://www.panasonic.com/|Name=Manufacturer URL
|RECORD=41|OwnerIndex=569|IndexInSheet=10|OwnerPartId=-1|Location.X=488|Location.Y=730|Color=8388608|FontID=1|IsHidden=T|Text=ThickFilm|Name=Composition
|RECORD=41|OwnerIndex=569|IndexInSheet=11|OwnerPartId=-1|Location.X=488|Location.Y=730|Color=8388608|FontID=1|IsHidden=T|Text=155degC|Name=Max Operating Temperature
|RECORD=41|OwnerIndex=569|IndexInSheet=12|OwnerPartId=-1|Location.X=488|Location.Y=730|Color=8388608|FontID=1|IsHidden=T|Text=600ppm/??C|Name=Temperature Coefficient
|RECORD=41|OwnerIndex=569|IndexInSheet=13|OwnerPartId=-1|Location.X=488|Location.Y=730|Color=8388608|FontID=1|IsHidden=T|Text=NoSVHC|Name=REACH SVHC
|RECORD=41|OwnerIndex=569|IndexInSheet=14|OwnerPartId=-1|Location.X=488|Location.Y=730|Color=8388608|FontID=1|IsHidden=T|Text=0402|Name=Case/Package
|RECORD=41|OwnerIndex=569|IndexInSheet=15|OwnerPartId=-1|Location.X=488|Location.Y=730|Color=8388608|FontID=1|IsHidden=T|Text=100mW|Name=Max Power Dissipation
|RECORD=41|OwnerIndex=569|IndexInSheet=16|OwnerPartId=-1|Location.X=488|Location.Y=730|Color=8388608|FontID=1|IsHidden=T|Text=402|Name=Package Reference
|RECORD=41|OwnerIndex=569|IndexInSheet=17|OwnerPartId=-1|Location.X=488|Location.Y=730|Color=8388608|FontID=1|IsHidden=T|Text=0.5mm|Name=Depth
|RECORD=41|OwnerIndex=569|IndexInSheet=18|OwnerPartId=-1|Location.X=488|Location.Y=730|Color=8388608|FontID=1|IsHidden=T|Text=Panasonic|Name=Manufacturer
|RECORD=41|OwnerIndex=569|IndexInSheet=19|OwnerPartId=-1|Location.X=488|Location.Y=730|Color=8388608|FontID=1|IsHidden=T|Text=2-Pin Surface Mount Device, Body 1 x 0.5 mm|Name=Package Description
|RECORD=41|OwnerIndex=569|IndexInSheet=20|OwnerPartId=-1|Location.X=488|Location.Y=730|Color=8388608|FontID=7|IsHidden=T|Text=https://industrial.panasonic.com/cdbs/www-data/pdf/RDA0000/AOA0000C301.pdf|Name=Datasheet URL
|RECORD=41|OwnerIndex=569|IndexInSheet=21|OwnerPartId=-1|Location.X=488|Location.Y=730|Color=8388608|FontID=1|IsHidden=T|Text=True|Name=RoHSCompliant
|RECORD=41|OwnerIndex=569|IndexInSheet=22|OwnerPartId=-1|Location.X=488|Location.Y=730|Color=8388608|FontID=1|IsHidden=T|Text=0402|Name=Case Code (Imperial)
|RECORD=41|OwnerIndex=569|IndexInSheet=23|OwnerPartId=-1|Location.X=488|Location.Y=730|Color=8388608|FontID=1|IsHidden=T|Text=0mOhm|Name=Resistance
|RECORD=41|OwnerIndex=569|IndexInSheet=24|OwnerPartId=-1|Location.X=488|Location.Y=730|Color=8388608|FontID=1|IsHidden=T|Text=Not|Name=Military Standard
|RECORD=41|OwnerIndex=569|IndexInSheet=25|OwnerPartId=-1|Location.X=488|Location.Y=730|Color=8388608|FontID=1|IsHidden=T|Text=5%|Name=Tolerance
|RECORD=41|OwnerIndex=569|IndexInSheet=26|OwnerPartId=-1|Location.X=488|Location.Y=730|Color=8388608|FontID=1|IsHidden=T|Text=-55degC|Name=Min Operating Temperature
|RECORD=41|OwnerIndex=569|IndexInSheet=27|OwnerPartId=-1|Location.X=488|Location.Y=730|Color=8388608|FontID=1|IsHidden=T|Text=100mW|Name=Power Rating
|RECORD=41|OwnerIndex=569|IndexInSheet=28|OwnerPartId=-1|Location.X=488|Location.Y=730|Color=8388608|FontID=1|IsHidden=T|Text=03/2015|Name=Datasheet Version
|RECORD=41|OwnerIndex=569|IndexInSheet=29|OwnerPartId=-1|Location.X=488|Location.Y=730|Color=8388608|FontID=1|IsHidden=T|Text=1mm|Name=Length
|RECORD=41|OwnerIndex=569|IndexInSheet=30|OwnerPartId=-1|Location.X=488|Location.Y=730|Color=8388608|FontID=1|IsHidden=T|Text=1005|Name=Case Code (Metric)
|RECORD=41|OwnerIndex=569|IndexInSheet=31|OwnerPartId=-1|Location.X=488|Location.Y=730|Color=8388608|FontID=1|IsHidden=T|Text=SMD/SMT|Name=Termination
|RECORD=41|OwnerIndex=569|IndexInSheet=32|OwnerPartId=-1|Location.X=488|Location.Y=730|Color=8388608|FontID=1|IsHidden=T|Text=SurfaceMount|Name=Mounting Technology
|RECORD=41|OwnerIndex=569|IndexInSheet=33|OwnerPartId=-1|Location.X=488|Location.Y=730|Color=8388608|FontID=1|IsHidden=T|Text=50V|Name=Voltage Rating
|RECORD=41|OwnerIndex=569|IndexInSheet=34|OwnerPartId=-1|Location.X=488|Location.Y=730|Color=8388608|FontID=1|IsHidden=T|Text=0.02inch|Name=Width
|RECORD=41|OwnerIndex=569|IndexInSheet=35|OwnerPartId=-1|Location.X=488|Location.Y=730|Color=8388608|FontID=1|IsHidden=T|Text=1|Name=Package Quantity
|RECORD=41|OwnerIndex=569|IndexInSheet=36|OwnerPartId=-1|Location.X=488|Location.Y=730|Color=8388608|FontID=1|IsHidden=T|Text=LeadFree|Name=Lead Free
|RECORD=41|OwnerIndex=569|IndexInSheet=37|OwnerPartId=-1|Location.X=488|Location.Y=730|Color=8388608|FontID=1|IsHidden=T|Text=No|Name=Radiation Hardening
|RECORD=34|OwnerIndex=569|IndexInSheet=-1|OwnerPartId=-1|Location.X=480|Location.Y=715|Color=8388608|FontID=1|Text=R62|Name=Designator|ReadOnlyState=1
|RECORD=41|OwnerIndex=569|IndexInSheet=-1|OwnerPartId=-1|Location.X=520|Location.Y=715|Color=8388608|FontID=1|Text=0_1%_0402|Name=Comment
|RECORD=44|OwnerIndex=569
|RECORD=45|OwnerIndex=612|IndexInSheet=-1|Description=Chip Resistor, 2-Leads, Body 1.05x0.55mm, IPC High Density|UseComponentLibrary=T|ModelName=RESC1005X40X25LL05T05|ModelType=PCBLIB|DatafileCount=1|ModelDatafileEntity0=RESC1005X40X25LL05T05|ModelDatafileKind0=PCBLib|IsCurrent=T|DatalinksLocked=T|DatabaseDatalinksLocked=T
|RECORD=46|OwnerIndex=613
|RECORD=48|OwnerIndex=613
|RECORD=41|OwnerIndex=615|IndexInSheet=-1|OwnerPartId=-1|Color=8388608|FontID=1|IsHidden=T|Text=2D|Name=Available Preview Images
|RECORD=45|OwnerIndex=612|IndexInSheet=-1|Description=Chip Resistor, 2-Leads, Body 1.05x0.55mm, IPC Low Density|UseComponentLibrary=T|ModelName=RESC1005X40X25ML05T05|ModelType=PCBLIB|DatafileCount=1|ModelDatafileEntity0=RESC1005X40X25ML05T05|ModelDatafileKind0=PCBLib|DatalinksLocked=T|DatabaseDatalinksLocked=T
|RECORD=46|OwnerIndex=617
|RECORD=48|OwnerIndex=617
|RECORD=41|OwnerIndex=619|IndexInSheet=-1|OwnerPartId=-1|Color=8388608|FontID=1|IsHidden=T|Text=2D|Name=Available Preview Images
|RECORD=45|OwnerIndex=612|IndexInSheet=-1|Description=Chip Resistor, 2-Leads, Body 1.05x0.55mm, IPC Medium Density|UseComponentLibrary=T|ModelName=RESC1005X40X25NL05T05|ModelType=PCBLIB|DatafileCount=1|ModelDatafileEntity0=RESC1005X40X25NL05T05|ModelDatafileKind0=PCBLib|DatalinksLocked=T|DatabaseDatalinksLocked=T
|RECORD=46|OwnerIndex=621
|RECORD=48|OwnerIndex=621
|RECORD=41|OwnerIndex=623|IndexInSheet=-1|OwnerPartId=-1|Color=8388608|FontID=1|IsHidden=T|Text=2D|Name=Available Preview Images
|RECORD=1|LibReference=RES-2|ComponentDescription=Chip Resistor, 0 Ohm, 0.1 W, -55 to 155 degC, 0402 (1005 Metric), RoHS, Tape and Reel|PartCount=2|DisplayModeCount=1|IndexInSheet=64|OwnerPartId=-1|Location.X=500|Location.Y=705|CurrentPartId=1|LibraryPath=*|SourceLibraryName=Altium Content Vault|TargetFileName=*|AreaColor=11599871|Color=128|PartIDLocked=T|DesignItemId=CMP-2000-07451-1|AllPinCount=2
|RECORD=2|OwnerIndex=625|OwnerPartId=1|FormalType=1|Electrical=4|PinConglomerate=32|PinLength=10|Location.X=520|Location.Y=705|Name=2|Designator=2|PinPropagationDelay=0.000000E+000
|RECORD=2|OwnerIndex=625|OwnerPartId=1|FormalType=1|Electrical=4|PinConglomerate=34|PinLength=10|Location.X=500|Location.Y=705|Name=1|Designator=1|PinPropagationDelay=0.000000E+000
|RECORD=6|OwnerIndex=625|IsNotAccesible=T|IndexInSheet=2|OwnerPartId=1|LineWidth=1|Color=16711680|LocationCount=10|X1=520|Y1=705|X2=516|Y2=705|X3=515|Y3=703|X4=513|Y4=707|X5=511|Y5=703|X6=509|Y6=707|X7=507|Y7=703|X8=505|Y8=707|X9=504|Y9=705|X10=500|Y10=705
|RECORD=41|OwnerIndex=625|IndexInSheet=3|OwnerPartId=-1|Location.X=488|Location.Y=720|Color=8388608|FontID=1|IsHidden=T|Text=50V|Name=Voltage Rating (DC)
|RECORD=41|OwnerIndex=625|IndexInSheet=4|OwnerPartId=-1|Location.X=488|Location.Y=720|Color=8388608|FontID=1|IsHidden=T|Text=2|Name=Number of Terminations
|RECORD=41|OwnerIndex=625|IndexInSheet=5|OwnerPartId=-1|Location.X=488|Location.Y=720|Color=8388608|FontID=1|IsHidden=T|Text=SurfaceMount|Name=Mount
|RECORD=41|OwnerIndex=625|IndexInSheet=6|OwnerPartId=-1|Location.X=488|Location.Y=720|Color=8388608|FontID=1|IsHidden=T|Text=0.35mm|Name=Height
|RECORD=41|OwnerIndex=625|IndexInSheet=7|OwnerPartId=-1|Location.X=488|Location.Y=720|Color=8388608|FontID=1|IsHidden=T|Text=TapeandReel|Name=Packaging
|RECORD=41|OwnerIndex=625|IndexInSheet=8|OwnerPartId=-1|Location.X=488|Location.Y=720|Color=8388608|FontID=1|IsHidden=T|Text=Tin|Name=Contact Plating
|RECORD=41|OwnerIndex=625|IndexInSheet=9|OwnerPartId=-1|Location.X=488|Location.Y=720|Color=8388608|FontID=7|IsHidden=T|Text=http://www.panasonic.com/|Name=Manufacturer URL
|RECORD=41|OwnerIndex=625|IndexInSheet=10|OwnerPartId=-1|Location.X=488|Location.Y=720|Color=8388608|FontID=1|IsHidden=T|Text=ThickFilm|Name=Composition
|RECORD=41|OwnerIndex=625|IndexInSheet=11|OwnerPartId=-1|Location.X=488|Location.Y=720|Color=8388608|FontID=1|IsHidden=T|Text=155degC|Name=Max Operating Temperature
|RECORD=41|OwnerIndex=625|IndexInSheet=12|OwnerPartId=-1|Location.X=488|Location.Y=720|Color=8388608|FontID=1|IsHidden=T|Text=600ppm/??C|Name=Temperature Coefficient
|RECORD=41|OwnerIndex=625|IndexInSheet=13|OwnerPartId=-1|Location.X=488|Location.Y=720|Color=8388608|FontID=1|IsHidden=T|Text=NoSVHC|Name=REACH SVHC
|RECORD=41|OwnerIndex=625|IndexInSheet=14|OwnerPartId=-1|Location.X=488|Location.Y=720|Color=8388608|FontID=1|IsHidden=T|Text=0402|Name=Case/Package
|RECORD=41|OwnerIndex=625|IndexInSheet=15|OwnerPartId=-1|Location.X=488|Location.Y=720|Color=8388608|FontID=1|IsHidden=T|Text=100mW|Name=Max Power Dissipation
|RECORD=41|OwnerIndex=625|IndexInSheet=16|OwnerPartId=-1|Location.X=488|Location.Y=720|Color=8388608|FontID=1|IsHidden=T|Text=402|Name=Package Reference
|RECORD=41|OwnerIndex=625|IndexInSheet=17|OwnerPartId=-1|Location.X=488|Location.Y=720|Color=8388608|FontID=1|IsHidden=T|Text=0.5mm|Name=Depth
|RECORD=41|OwnerIndex=625|IndexInSheet=18|OwnerPartId=-1|Location.X=488|Location.Y=720|Color=8388608|FontID=1|IsHidden=T|Text=Panasonic|Name=Manufacturer
|RECORD=41|OwnerIndex=625|IndexInSheet=19|OwnerPartId=-1|Location.X=488|Location.Y=720|Color=8388608|FontID=1|IsHidden=T|Text=2-Pin Surface Mount Device, Body 1 x 0.5 mm|Name=Package Description
|RECORD=41|OwnerIndex=625|IndexInSheet=20|OwnerPartId=-1|Location.X=488|Location.Y=720|Color=8388608|FontID=7|IsHidden=T|Text=https://industrial.panasonic.com/cdbs/www-data/pdf/RDA0000/AOA0000C301.pdf|Name=Datasheet URL
|RECORD=41|OwnerIndex=625|IndexInSheet=21|OwnerPartId=-1|Location.X=488|Location.Y=720|Color=8388608|FontID=1|IsHidden=T|Text=True|Name=RoHSCompliant
|RECORD=41|OwnerIndex=625|IndexInSheet=22|OwnerPartId=-1|Location.X=488|Location.Y=720|Color=8388608|FontID=1|IsHidden=T|Text=0402|Name=Case Code (Imperial)
|RECORD=41|OwnerIndex=625|IndexInSheet=23|OwnerPartId=-1|Location.X=488|Location.Y=720|Color=8388608|FontID=1|IsHidden=T|Text=0mOhm|Name=Resistance
|RECORD=41|OwnerIndex=625|IndexInSheet=24|OwnerPartId=-1|Location.X=488|Location.Y=720|Color=8388608|FontID=1|IsHidden=T|Text=Not|Name=Military Standard
|RECORD=41|OwnerIndex=625|IndexInSheet=25|OwnerPartId=-1|Location.X=488|Location.Y=720|Color=8388608|FontID=1|IsHidden=T|Text=5%|Name=Tolerance
|RECORD=41|OwnerIndex=625|IndexInSheet=26|OwnerPartId=-1|Location.X=488|Location.Y=720|Color=8388608|FontID=1|IsHidden=T|Text=-55degC|Name=Min Operating Temperature
|RECORD=41|OwnerIndex=625|IndexInSheet=27|OwnerPartId=-1|Location.X=488|Location.Y=720|Color=8388608|FontID=1|IsHidden=T|Text=100mW|Name=Power Rating
|RECORD=41|OwnerIndex=625|IndexInSheet=28|OwnerPartId=-1|Location.X=488|Location.Y=720|Color=8388608|FontID=1|IsHidden=T|Text=03/2015|Name=Datasheet Version
|RECORD=41|OwnerIndex=625|IndexInSheet=29|OwnerPartId=-1|Location.X=488|Location.Y=720|Color=8388608|FontID=1|IsHidden=T|Text=1mm|Name=Length
|RECORD=41|OwnerIndex=625|IndexInSheet=30|OwnerPartId=-1|Location.X=488|Location.Y=720|Color=8388608|FontID=1|IsHidden=T|Text=1005|Name=Case Code (Metric)
|RECORD=41|OwnerIndex=625|IndexInSheet=31|OwnerPartId=-1|Location.X=488|Location.Y=720|Color=8388608|FontID=1|IsHidden=T|Text=SMD/SMT|Name=Termination
|RECORD=41|OwnerIndex=625|IndexInSheet=32|OwnerPartId=-1|Location.X=488|Location.Y=720|Color=8388608|FontID=1|IsHidden=T|Text=SurfaceMount|Name=Mounting Technology
|RECORD=41|OwnerIndex=625|IndexInSheet=33|OwnerPartId=-1|Location.X=488|Location.Y=720|Color=8388608|FontID=1|IsHidden=T|Text=50V|Name=Voltage Rating
|RECORD=41|OwnerIndex=625|IndexInSheet=34|OwnerPartId=-1|Location.X=488|Location.Y=720|Color=8388608|FontID=1|IsHidden=T|Text=0.02inch|Name=Width
|RECORD=41|OwnerIndex=625|IndexInSheet=35|OwnerPartId=-1|Location.X=488|Location.Y=720|Color=8388608|FontID=1|IsHidden=T|Text=1|Name=Package Quantity
|RECORD=41|OwnerIndex=625|IndexInSheet=36|OwnerPartId=-1|Location.X=488|Location.Y=720|Color=8388608|FontID=1|IsHidden=T|Text=LeadFree|Name=Lead Free
|RECORD=41|OwnerIndex=625|IndexInSheet=37|OwnerPartId=-1|Location.X=488|Location.Y=720|Color=8388608|FontID=1|IsHidden=T|Text=No|Name=Radiation Hardening
|RECORD=34|OwnerIndex=625|IndexInSheet=-1|OwnerPartId=-1|Location.X=480|Location.Y=705|Color=8388608|FontID=1|Text=R64|Name=Designator|ReadOnlyState=1
|RECORD=41|OwnerIndex=625|IndexInSheet=-1|OwnerPartId=-1|Location.X=520|Location.Y=705|Color=8388608|FontID=1|Text=0_1%_0402|Name=Comment
|RECORD=44|OwnerIndex=625
|RECORD=45|OwnerIndex=668|IndexInSheet=-1|Description=Chip Resistor, 2-Leads, Body 1.05x0.55mm, IPC High Density|UseComponentLibrary=T|ModelName=RESC1005X40X25LL05T05|ModelType=PCBLIB|DatafileCount=1|ModelDatafileEntity0=RESC1005X40X25LL05T05|ModelDatafileKind0=PCBLib|IsCurrent=T|DatalinksLocked=T|DatabaseDatalinksLocked=T
|RECORD=46|OwnerIndex=669
|RECORD=48|OwnerIndex=669
|RECORD=41|OwnerIndex=671|IndexInSheet=-1|OwnerPartId=-1|Color=8388608|FontID=1|IsHidden=T|Text=2D|Name=Available Preview Images
|RECORD=45|OwnerIndex=668|IndexInSheet=-1|Description=Chip Resistor, 2-Leads, Body 1.05x0.55mm, IPC Low Density|UseComponentLibrary=T|ModelName=RESC1005X40X25ML05T05|ModelType=PCBLIB|DatafileCount=1|ModelDatafileEntity0=RESC1005X40X25ML05T05|ModelDatafileKind0=PCBLib|DatalinksLocked=T|DatabaseDatalinksLocked=T
|RECORD=46|OwnerIndex=673
|RECORD=48|OwnerIndex=673
|RECORD=41|OwnerIndex=675|IndexInSheet=-1|OwnerPartId=-1|Color=8388608|FontID=1|IsHidden=T|Text=2D|Name=Available Preview Images
|RECORD=45|OwnerIndex=668|IndexInSheet=-1|Description=Chip Resistor, 2-Leads, Body 1.05x0.55mm, IPC Medium Density|UseComponentLibrary=T|ModelName=RESC1005X40X25NL05T05|ModelType=PCBLIB|DatafileCount=1|ModelDatafileEntity0=RESC1005X40X25NL05T05|ModelDatafileKind0=PCBLib|DatalinksLocked=T|DatabaseDatalinksLocked=T
|RECORD=46|OwnerIndex=677
|RECORD=48|OwnerIndex=677
|RECORD=41|OwnerIndex=679|IndexInSheet=-1|OwnerPartId=-1|Color=8388608|FontID=1|IsHidden=T|Text=2D|Name=Available Preview Images
|RECORD=4|IndexInSheet=65|OwnerPartId=-1|Location.X=380|Location.Y=785|Color=8388608|FontID=1|Text=Address 0x40
|RECORD=1|LibReference=MIC24052YJL-TR|ComponentDescription=No Description Available|PartCount=3|DisplayModeCount=1|IndexInSheet=66|OwnerPartId=-1|Location.X=885|Location.Y=975|CurrentPartId=1|LibraryPath=*|SourceLibraryName=MIC24052YJL-TR.SchLib|TargetFileName=*|AreaColor=11599871|Color=128|PartIDLocked=T|DesignItemId=MIC24052YJL-TR|AllPinCount=30
|RECORD=41|OwnerIndex=682|OwnerPartId=1|Location.X=885|Location.Y=975|FontID=1|IsHidden=T|Text=Copyright (C) 2023 Ultra Librarian. All rights reserved.|Name=Copyright
|RECORD=41|OwnerIndex=682|IndexInSheet=1|OwnerPartId=1|Location.X=885|Location.Y=975|FontID=1|IsHidden=T|Text=Microchip|Name=Mfr_Name
|RECORD=41|OwnerIndex=682|IndexInSheet=2|OwnerPartId=1|Location.X=885|Location.Y=975|FontID=1|IsHidden=T|Text=MIC24052YJL-TR|Name=Manufacturer_Part_Number
|RECORD=41|OwnerIndex=682|IndexInSheet=3|OwnerPartId=1|Location.X=965|Location.Y=1015|FontID=1|IsHidden=T|Text=RefDes|Name=RefDes
|RECORD=41|OwnerIndex=682|IndexInSheet=4|OwnerPartId=1|Location.X=965|Location.Y=1005|FontID=1|IsHidden=T|Text=DEV|Name=Type
|RECORD=2|OwnerIndex=682|OwnerPartId=2|FormalType=1|Electrical=4|PinConglomerate=58|PinLength=30|Location.X=915|Location.Y=975|Name=NC|Designator=3|SwapIdPin=0|SwapIDPart=0Ž&Ž1|PinPropagationDelay=0.000000E+000
|RECORD=2|OwnerIndex=682|OwnerPartId=2|FormalType=1|Electrical=7|PinConglomerate=58|PinLength=30|Location.X=915|Location.Y=965|Name=PVDD|Designator=1|SwapIdPin=0|SwapIDPart=0Ž&Ž2|PinPropagationDelay=0.000000E+000
|RECORD=2|OwnerIndex=682|OwnerPartId=2|FormalType=1|Electrical=7|PinConglomerate=58|PinLength=30|Location.X=915|Location.Y=955|Name=VDD|Designator=28|SwapIdPin=0|SwapIDPart=0Ž&Ž3|PinPropagationDelay=0.000000E+000
|RECORD=2|OwnerIndex=682|OwnerPartId=2|FormalType=1|Electrical=7|PinConglomerate=58|PinLength=30|Location.X=915|Location.Y=945|Name=PGND|Designator=2|SwapIdPin=0|SwapIDPart=0Ž&Ž4|PinPropagationDelay=0.000000E+000
|RECORD=2|OwnerIndex=682|OwnerPartId=2|FormalType=1|Electrical=7|PinConglomerate=58|PinLength=30|Location.X=915|Location.Y=935|Name=PGND|Designator=5|SwapIdPin=0|SwapIDPart=0Ž&Ž5|PinPropagationDelay=0.000000E+000
|RECORD=2|OwnerIndex=682|OwnerPartId=2|FormalType=1|Electrical=7|PinConglomerate=58|PinLength=30|Location.X=915|Location.Y=925|Name=PGND|Designator=6|SwapIdPin=0|SwapIDPart=0Ž&Ž6|PinPropagationDelay=0.000000E+000
|RECORD=2|OwnerIndex=682|OwnerPartId=2|FormalType=1|Electrical=7|PinConglomerate=58|PinLength=30|Location.X=915|Location.Y=915|Name=PGND|Designator=7|SwapIdPin=0|SwapIDPart=0Ž&Ž7|PinPropagationDelay=0.000000E+000
|RECORD=2|OwnerIndex=682|OwnerPartId=2|FormalType=1|Electrical=7|PinConglomerate=58|PinLength=30|Location.X=915|Location.Y=905|Name=PGND|Designator=8|SwapIdPin=0|SwapIDPart=0Ž&Ž8|PinPropagationDelay=0.000000E+000
|RECORD=2|OwnerIndex=682|OwnerPartId=2|FormalType=1|Electrical=7|PinConglomerate=58|PinLength=30|Location.X=915|Location.Y=895|Name=PGND|Designator=21|SwapIdPin=0|SwapIDPart=0Ž&Ž9|PinPropagationDelay=0.000000E+000
|RECORD=2|OwnerIndex=682|OwnerPartId=2|FormalType=1|Electrical=7|PinConglomerate=58|PinLength=30|Location.X=915|Location.Y=875|Name=SGND|Designator=23|SwapIdPin=0|SwapIDPart=0Ž&Ž10|PinPropagationDelay=0.000000E+000
|RECORD=14|OwnerIndex=682|IsNotAccesible=T|IndexInSheet=15|OwnerPartId=2|Location.X=915|Location.Y=855|Corner.X=1015|Corner.Y=995|LineWidth=1|AreaColor=11599871|IsSolid=T|Transparent=T
|RECORD=4|OwnerIndex=682|IsNotAccesible=T|IndexInSheet=16|OwnerPartId=2|Location.X=965|Location.Y=985|Justification=4|FontID=1|Text=2 of 2
|RECORD=2|OwnerIndex=682|OwnerPartId=1|FormalType=1|PinConglomerate=58|PinLength=30|Location.X=915|Location.Y=975|Name=CS|Designator=22|SwapIdPin=0|SwapIDPart=0Ž&Ž1|PinPropagationDelay=0.000000E+000
|RECORD=2|OwnerIndex=682|OwnerPartId=1|FormalType=1|PinConglomerate=58|PinLength=30|Location.X=915|Location.Y=965|Name=EN|Designator=26|SwapIdPin=0|SwapIDPart=0Ž&Ž2|PinPropagationDelay=0.000000E+000
|RECORD=2|OwnerIndex=682|OwnerPartId=1|FormalType=1|PinConglomerate=58|PinLength=30|Location.X=915|Location.Y=955|Name=FB|Designator=24|SwapIdPin=0|SwapIDPart=0Ž&Ž3|PinPropagationDelay=0.000000E+000
|RECORD=2|OwnerIndex=682|OwnerPartId=1|FormalType=1|PinConglomerate=58|PinLength=30|Location.X=915|Location.Y=935|Name=PVIN|Designator=13|SwapIdPin=0|SwapIDPart=0Ž&Ž4|PinPropagationDelay=0.000000E+000
|RECORD=2|OwnerIndex=682|OwnerPartId=1|FormalType=1|PinConglomerate=58|PinLength=30|Location.X=915|Location.Y=925|Name=PVIN|Designator=14|SwapIdPin=0|SwapIDPart=0Ž&Ž5|PinPropagationDelay=0.000000E+000
|RECORD=2|OwnerIndex=682|OwnerPartId=1|FormalType=1|PinConglomerate=58|PinLength=30|Location.X=915|Location.Y=915|Name=PVIN|Designator=15|SwapIdPin=0|SwapIDPart=0Ž&Ž6|PinPropagationDelay=0.000000E+000
|RECORD=2|OwnerIndex=682|OwnerPartId=1|FormalType=1|PinConglomerate=58|PinLength=30|Location.X=915|Location.Y=905|Name=PVIN|Designator=16|SwapIdPin=0|SwapIDPart=0Ž&Ž7|PinPropagationDelay=0.000000E+000
|RECORD=2|OwnerIndex=682|OwnerPartId=1|FormalType=1|PinConglomerate=58|PinLength=30|Location.X=915|Location.Y=895|Name=PVIN|Designator=17|SwapIdPin=0|SwapIDPart=0Ž&Ž8|PinPropagationDelay=0.000000E+000
|RECORD=2|OwnerIndex=682|OwnerPartId=1|FormalType=1|PinConglomerate=58|PinLength=30|Location.X=915|Location.Y=885|Name=PVIN|Designator=18|SwapIdPin=0|SwapIDPart=0Ž&Ž9|PinPropagationDelay=0.000000E+000
|RECORD=2|OwnerIndex=682|OwnerPartId=1|FormalType=1|PinConglomerate=58|PinLength=30|Location.X=915|Location.Y=875|Name=PVIN|Designator=19|SwapIdPin=0|SwapIDPart=0Ž&Ž10|PinPropagationDelay=0.000000E+000
|RECORD=2|OwnerIndex=682|OwnerPartId=1|FormalType=1|PinConglomerate=58|PinLength=30|Location.X=915|Location.Y=855|Name=VIN|Designator=27|SwapIdPin=0|SwapIDPart=0Ž&Ž11|PinPropagationDelay=0.000000E+000
|RECORD=2|OwnerIndex=682|OwnerPartId=1|FormalType=1|Electrical=4|PinConglomerate=58|PinLength=30|Location.X=915|Location.Y=835|Name=EPAD|Designator=29|SwapIdPin=0|SwapIDPart=0Ž&Ž12|PinPropagationDelay=0.000000E+000
|RECORD=2|OwnerIndex=682|OwnerPartId=1|FormalType=1|Electrical=2|PinConglomerate=56|PinLength=30|Location.X=1015|Location.Y=975|Name=BST|Designator=20|SwapIdPin=0|SwapIDPart=0Ž&Ž13|PinPropagationDelay=0.000000E+000
|RECORD=2|OwnerIndex=682|OwnerPartId=1|FormalType=1|Electrical=2|PinConglomerate=56|PinLength=30|Location.X=1015|Location.Y=965|Name=PG|Designator=25|SwapIdPin=0|SwapIDPart=0Ž&Ž14|PinPropagationDelay=0.000000E+000
|RECORD=2|OwnerIndex=682|OwnerPartId=1|FormalType=1|Electrical=2|PinConglomerate=56|PinLength=30|Location.X=1015|Location.Y=945|Name=SW|Designator=4|SwapIdPin=0|SwapIDPart=0Ž&Ž15|PinPropagationDelay=0.000000E+000
|RECORD=2|OwnerIndex=682|OwnerPartId=1|FormalType=1|Electrical=2|PinConglomerate=56|PinLength=30|Location.X=1015|Location.Y=935|Name=SW|Designator=9|SwapIdPin=0|SwapIDPart=0Ž&Ž16|PinPropagationDelay=0.000000E+000
|RECORD=2|OwnerIndex=682|OwnerPartId=1|FormalType=1|Electrical=2|PinConglomerate=56|PinLength=30|Location.X=1015|Location.Y=925|Name=SW|Designator=10|SwapIdPin=0|SwapIDPart=0Ž&Ž17|PinPropagationDelay=0.000000E+000
|RECORD=2|OwnerIndex=682|OwnerPartId=1|FormalType=1|Electrical=2|PinConglomerate=56|PinLength=30|Location.X=1015|Location.Y=915|Name=SW|Designator=11|SwapIdPin=0|SwapIDPart=0Ž&Ž18|PinPropagationDelay=0.000000E+000
|RECORD=2|OwnerIndex=682|OwnerPartId=1|FormalType=1|Electrical=2|PinConglomerate=56|PinLength=30|Location.X=1015|Location.Y=905|Name=SW|Designator=12|SwapIdPin=0|SwapIDPart=0Ž&Ž19|PinPropagationDelay=0.000000E+000
|RECORD=14|OwnerIndex=682|IsNotAccesible=T|IndexInSheet=36|OwnerPartId=1|Location.X=915|Location.Y=815|Corner.X=1015|Corner.Y=995|LineWidth=1|AreaColor=11599871|IsSolid=T|Transparent=T
|RECORD=4|OwnerIndex=682|IsNotAccesible=T|IndexInSheet=37|OwnerPartId=1|Location.X=965|Location.Y=985|Justification=4|FontID=1|Text=1 of 2
|RECORD=2|OwnerIndex=682|OwnerPartId=1|FormalType=1|Electrical=2|PinConglomerate=56|PinLength=30|Location.X=1015|Location.Y=895|Name=SW|Designator=30|SwapIdPin=0|SwapIDPart=0Ž&Ž19|PinPropagationDelay=0.000000E+000
|RECORD=34|OwnerIndex=682|IndexInSheet=-1|OwnerPartId=-1|Location.X=915|Location.Y=995|Color=8388608|FontID=1|Text=U1|Name=Designator|ReadOnlyState=1
|RECORD=41|OwnerIndex=682|IndexInSheet=-1|OwnerPartId=-1|Location.X=915|Location.Y=805|Color=8388608|FontID=1|Text=MIC24052YJL-TR|Name=Comment
|RECORD=44|OwnerIndex=682
|RECORD=45|OwnerIndex=754|IndexInSheet=-1|ModelName=QFN28_5X6_MCH|ModelType=PCBLIB|DatafileCount=1|ModelDatafileEntity0=QFN28_5X6_MCH|ModelDatafileKind0=PCBLIB|IsCurrent=T
|RECORD=46|OwnerIndex=755
|RECORD=48|OwnerIndex=755
|RECORD=1|LibReference=MIC24052YJL-TR|ComponentDescription=No Description Available|PartCount=3|DisplayModeCount=1|IndexInSheet=67|OwnerPartId=-1|Location.X=1540|Location.Y=955|CurrentPartId=2|LibraryPath=*|SourceLibraryName=MIC24052YJL-TR.SchLib|TargetFileName=*|AreaColor=11599871|Color=128|PartIDLocked=T|DesignItemId=MIC24052YJL-TR|AllPinCount=30
|RECORD=41|OwnerIndex=758|OwnerPartId=1|Location.X=1540|Location.Y=955|FontID=1|IsHidden=T|Text=Copyright (C) 2023 Ultra Librarian. All rights reserved.|Name=Copyright
|RECORD=41|OwnerIndex=758|IndexInSheet=1|OwnerPartId=1|Location.X=1540|Location.Y=955|FontID=1|IsHidden=T|Text=Microchip|Name=Mfr_Name
|RECORD=41|OwnerIndex=758|IndexInSheet=2|OwnerPartId=1|Location.X=1540|Location.Y=955|FontID=1|IsHidden=T|Text=MIC24052YJL-TR|Name=Manufacturer_Part_Number
|RECORD=41|OwnerIndex=758|IndexInSheet=3|OwnerPartId=1|Location.X=1620|Location.Y=995|FontID=1|IsHidden=T|Text=RefDes|Name=RefDes
|RECORD=41|OwnerIndex=758|IndexInSheet=4|OwnerPartId=1|Location.X=1620|Location.Y=985|FontID=1|IsHidden=T|Text=DEV|Name=Type
|RECORD=2|OwnerIndex=758|OwnerPartId=2|FormalType=1|Electrical=4|PinConglomerate=58|PinLength=30|Location.X=1570|Location.Y=955|Name=NC|Designator=3|SwapIdPin=0|SwapIDPart=0Ž&Ž1|PinPropagationDelay=0.000000E+000
|RECORD=2|OwnerIndex=758|OwnerPartId=2|FormalType=1|Electrical=7|PinConglomerate=58|PinLength=30|Location.X=1570|Location.Y=945|Name=PVDD|Designator=1|SwapIdPin=0|SwapIDPart=0Ž&Ž2|PinPropagationDelay=0.000000E+000
|RECORD=2|OwnerIndex=758|OwnerPartId=2|FormalType=1|Electrical=7|PinConglomerate=58|PinLength=30|Location.X=1570|Location.Y=935|Name=VDD|Designator=28|SwapIdPin=0|SwapIDPart=0Ž&Ž3|PinPropagationDelay=0.000000E+000
|RECORD=2|OwnerIndex=758|OwnerPartId=2|FormalType=1|Electrical=7|PinConglomerate=58|PinLength=30|Location.X=1570|Location.Y=925|Name=PGND|Designator=2|SwapIdPin=0|SwapIDPart=0Ž&Ž4|PinPropagationDelay=0.000000E+000
|RECORD=2|OwnerIndex=758|OwnerPartId=2|FormalType=1|Electrical=7|PinConglomerate=58|PinLength=30|Location.X=1570|Location.Y=915|Name=PGND|Designator=5|SwapIdPin=0|SwapIDPart=0Ž&Ž5|PinPropagationDelay=0.000000E+000
|RECORD=2|OwnerIndex=758|OwnerPartId=2|FormalType=1|Electrical=7|PinConglomerate=58|PinLength=30|Location.X=1570|Location.Y=905|Name=PGND|Designator=6|SwapIdPin=0|SwapIDPart=0Ž&Ž6|PinPropagationDelay=0.000000E+000
|RECORD=2|OwnerIndex=758|OwnerPartId=2|FormalType=1|Electrical=7|PinConglomerate=58|PinLength=30|Location.X=1570|Location.Y=895|Name=PGND|Designator=7|SwapIdPin=0|SwapIDPart=0Ž&Ž7|PinPropagationDelay=0.000000E+000
|RECORD=2|OwnerIndex=758|OwnerPartId=2|FormalType=1|Electrical=7|PinConglomerate=58|PinLength=30|Location.X=1570|Location.Y=885|Name=PGND|Designator=8|SwapIdPin=0|SwapIDPart=0Ž&Ž8|PinPropagationDelay=0.000000E+000
|RECORD=2|OwnerIndex=758|OwnerPartId=2|FormalType=1|Electrical=7|PinConglomerate=58|PinLength=30|Location.X=1570|Location.Y=875|Name=PGND|Designator=21|SwapIdPin=0|SwapIDPart=0Ž&Ž9|PinPropagationDelay=0.000000E+000
|RECORD=2|OwnerIndex=758|OwnerPartId=2|FormalType=1|Electrical=7|PinConglomerate=58|PinLength=30|Location.X=1570|Location.Y=855|Name=SGND|Designator=23|SwapIdPin=0|SwapIDPart=0Ž&Ž10|PinPropagationDelay=0.000000E+000
|RECORD=14|OwnerIndex=758|IsNotAccesible=T|IndexInSheet=15|OwnerPartId=2|Location.X=1570|Location.Y=835|Corner.X=1670|Corner.Y=975|LineWidth=1|AreaColor=11599871|IsSolid=T|Transparent=T
|RECORD=4|OwnerIndex=758|IsNotAccesible=T|IndexInSheet=16|OwnerPartId=2|Location.X=1620|Location.Y=965|Justification=4|FontID=1|Text=2 of 2
|RECORD=2|OwnerIndex=758|OwnerPartId=1|FormalType=1|PinConglomerate=58|PinLength=30|Location.X=1570|Location.Y=955|Name=CS|Designator=22|SwapIdPin=0|SwapIDPart=0Ž&Ž1|PinPropagationDelay=0.000000E+000
|RECORD=2|OwnerIndex=758|OwnerPartId=1|FormalType=1|PinConglomerate=58|PinLength=30|Location.X=1570|Location.Y=945|Name=EN|Designator=26|SwapIdPin=0|SwapIDPart=0Ž&Ž2|PinPropagationDelay=0.000000E+000
|RECORD=2|OwnerIndex=758|OwnerPartId=1|FormalType=1|PinConglomerate=58|PinLength=30|Location.X=1570|Location.Y=935|Name=FB|Designator=24|SwapIdPin=0|SwapIDPart=0Ž&Ž3|PinPropagationDelay=0.000000E+000
|RECORD=2|OwnerIndex=758|OwnerPartId=1|FormalType=1|PinConglomerate=58|PinLength=30|Location.X=1570|Location.Y=915|Name=PVIN|Designator=13|SwapIdPin=0|SwapIDPart=0Ž&Ž4|PinPropagationDelay=0.000000E+000
|RECORD=2|OwnerIndex=758|OwnerPartId=1|FormalType=1|PinConglomerate=58|PinLength=30|Location.X=1570|Location.Y=905|Name=PVIN|Designator=14|SwapIdPin=0|SwapIDPart=0Ž&Ž5|PinPropagationDelay=0.000000E+000
|RECORD=2|OwnerIndex=758|OwnerPartId=1|FormalType=1|PinConglomerate=58|PinLength=30|Location.X=1570|Location.Y=895|Name=PVIN|Designator=15|SwapIdPin=0|SwapIDPart=0Ž&Ž6|PinPropagationDelay=0.000000E+000
|RECORD=2|OwnerIndex=758|OwnerPartId=1|FormalType=1|PinConglomerate=58|PinLength=30|Location.X=1570|Location.Y=885|Name=PVIN|Designator=16|SwapIdPin=0|SwapIDPart=0Ž&Ž7|PinPropagationDelay=0.000000E+000
|RECORD=2|OwnerIndex=758|OwnerPartId=1|FormalType=1|PinConglomerate=58|PinLength=30|Location.X=1570|Location.Y=875|Name=PVIN|Designator=17|SwapIdPin=0|SwapIDPart=0Ž&Ž8|PinPropagationDelay=0.000000E+000
|RECORD=2|OwnerIndex=758|OwnerPartId=1|FormalType=1|PinConglomerate=58|PinLength=30|Location.X=1570|Location.Y=865|Name=PVIN|Designator=18|SwapIdPin=0|SwapIDPart=0Ž&Ž9|PinPropagationDelay=0.000000E+000
|RECORD=2|OwnerIndex=758|OwnerPartId=1|FormalType=1|PinConglomerate=58|PinLength=30|Location.X=1570|Location.Y=855|Name=PVIN|Designator=19|SwapIdPin=0|SwapIDPart=0Ž&Ž10|PinPropagationDelay=0.000000E+000
|RECORD=2|OwnerIndex=758|OwnerPartId=1|FormalType=1|PinConglomerate=58|PinLength=30|Location.X=1570|Location.Y=835|Name=VIN|Designator=27|SwapIdPin=0|SwapIDPart=0Ž&Ž11|PinPropagationDelay=0.000000E+000
|RECORD=2|OwnerIndex=758|OwnerPartId=1|FormalType=1|Electrical=4|PinConglomerate=58|PinLength=30|Location.X=1570|Location.Y=815|Name=EPAD|Designator=29|SwapIdPin=0|SwapIDPart=0Ž&Ž12|PinPropagationDelay=0.000000E+000
|RECORD=2|OwnerIndex=758|OwnerPartId=1|FormalType=1|Electrical=2|PinConglomerate=56|PinLength=30|Location.X=1670|Location.Y=955|Name=BST|Designator=20|SwapIdPin=0|SwapIDPart=0Ž&Ž13|PinPropagationDelay=0.000000E+000
|RECORD=2|OwnerIndex=758|OwnerPartId=1|FormalType=1|Electrical=2|PinConglomerate=56|PinLength=30|Location.X=1670|Location.Y=945|Name=PG|Designator=25|SwapIdPin=0|SwapIDPart=0Ž&Ž14|PinPropagationDelay=0.000000E+000
|RECORD=2|OwnerIndex=758|OwnerPartId=1|FormalType=1|Electrical=2|PinConglomerate=56|PinLength=30|Location.X=1670|Location.Y=925|Name=SW|Designator=4|SwapIdPin=0|SwapIDPart=0Ž&Ž15|PinPropagationDelay=0.000000E+000
|RECORD=2|OwnerIndex=758|OwnerPartId=1|FormalType=1|Electrical=2|PinConglomerate=56|PinLength=30|Location.X=1670|Location.Y=915|Name=SW|Designator=9|SwapIdPin=0|SwapIDPart=0Ž&Ž16|PinPropagationDelay=0.000000E+000
|RECORD=2|OwnerIndex=758|OwnerPartId=1|FormalType=1|Electrical=2|PinConglomerate=56|PinLength=30|Location.X=1670|Location.Y=905|Name=SW|Designator=10|SwapIdPin=0|SwapIDPart=0Ž&Ž17|PinPropagationDelay=0.000000E+000
|RECORD=2|OwnerIndex=758|OwnerPartId=1|FormalType=1|Electrical=2|PinConglomerate=56|PinLength=30|Location.X=1670|Location.Y=895|Name=SW|Designator=11|SwapIdPin=0|SwapIDPart=0Ž&Ž18|PinPropagationDelay=0.000000E+000
|RECORD=2|OwnerIndex=758|OwnerPartId=1|FormalType=1|Electrical=2|PinConglomerate=56|PinLength=30|Location.X=1670|Location.Y=885|Name=SW|Designator=12|SwapIdPin=0|SwapIDPart=0Ž&Ž19|PinPropagationDelay=0.000000E+000
|RECORD=14|OwnerIndex=758|IsNotAccesible=T|IndexInSheet=36|OwnerPartId=1|Location.X=1570|Location.Y=795|Corner.X=1670|Corner.Y=975|LineWidth=1|AreaColor=11599871|IsSolid=T|Transparent=T
|RECORD=4|OwnerIndex=758|IsNotAccesible=T|IndexInSheet=37|OwnerPartId=1|Location.X=1620|Location.Y=965|Justification=4|FontID=1|Text=1 of 2
|RECORD=2|OwnerIndex=758|OwnerPartId=1|FormalType=1|Electrical=2|PinConglomerate=56|PinLength=30|Location.X=1670|Location.Y=875|Name=SW|Designator=30|SwapIdPin=0|SwapIDPart=0Ž&Ž19|PinPropagationDelay=0.000000E+000
|RECORD=34|OwnerIndex=758|IndexInSheet=-1|OwnerPartId=-1|Location.X=1570|Location.Y=975|Color=8388608|FontID=1|Text=U1|Name=Designator|ReadOnlyState=1
|RECORD=41|OwnerIndex=758|IndexInSheet=-1|OwnerPartId=-1|Location.X=1570|Location.Y=825|Color=8388608|FontID=1|Text=MIC24052YJL-TR|Name=Comment
|RECORD=44|OwnerIndex=758
|RECORD=45|OwnerIndex=830|IndexInSheet=-1|ModelName=QFN28_5X6_MCH|ModelType=PCBLIB|DatafileCount=1|ModelDatafileEntity0=QFN28_5X6_MCH|ModelDatafileKind0=PCBLIB|IsCurrent=T
|RECORD=46|OwnerIndex=831
|RECORD=48|OwnerIndex=831
|RECORD=17|IndexInSheet=68|OwnerPartId=-1|Style=4|ShowNetName=T|Location.X=1530|Location.Y=835|Orientation=3|Color=128|FontID=1|Text=GND
|RECORD=1|LibReference=RES-2|ComponentDescription=Chip Resistor, 4.7 KOhm, +/- 1%, 0.1 W, -55 to 155 degC, 0402 (1005 Metric), RoHS, Tape and Reel|PartCount=2|DisplayModeCount=1|IndexInSheet=69|OwnerPartId=-1|Location.X=1080|Location.Y=1020|Orientation=3|CurrentPartId=1|LibraryPath=*|SourceLibraryName=Altium Content Vault|TargetFileName=*|AreaColor=11599871|Color=128|PartIDLocked=T|DesignItemId=CMP-2002-01154-4|AllPinCount=2
|RECORD=2|OwnerIndex=835|OwnerPartId=1|FormalType=1|Electrical=4|PinConglomerate=35|PinLength=10|Location.X=1080|Location.Y=1000|Name=2|Designator=2|PinPropagationDelay=0.000000E+000
|RECORD=2|OwnerIndex=835|OwnerPartId=1|FormalType=1|Electrical=4|PinConglomerate=33|PinLength=10|Location.X=1080|Location.Y=1020|Name=1|Designator=1|PinPropagationDelay=0.000000E+000
|RECORD=6|OwnerIndex=835|IsNotAccesible=T|IndexInSheet=2|OwnerPartId=1|LineWidth=1|Color=16711680|LocationCount=10|X1=1080|Y1=1000|X2=1080|Y2=1004|X3=1078|Y3=1005|X4=1082|Y4=1007|X5=1078|Y5=1009|X6=1082|Y6=1011|X7=1078|Y7=1013|X8=1082|Y8=1015|X9=1080|Y9=1016|X10=1080|Y10=1020
|RECORD=41|OwnerIndex=835|IndexInSheet=3|OwnerPartId=-1|Location.X=1077|Location.Y=1032|Color=8388608|FontID=1|IsHidden=T|Text=0.35 mm|Name=Height
|RECORD=41|OwnerIndex=835|IndexInSheet=4|OwnerPartId=-1|Location.X=1077|Location.Y=1032|Color=8388608|FontID=1|IsHidden=T|Text=Surface Mount|Name=Mounting Technology
|RECORD=41|OwnerIndex=835|IndexInSheet=5|OwnerPartId=-1|Location.X=1077|Location.Y=1032|Color=8388608|FontID=1|IsHidden=T|Text=Yes|Name=REACH SVHC
|RECORD=41|OwnerIndex=835|IndexInSheet=6|OwnerPartId=-1|Location.X=1077|Location.Y=1032|Color=8388608|FontID=1|IsHidden=T|Text=4.7 KOhm|Name=Resistance
|RECORD=41|OwnerIndex=835|IndexInSheet=7|OwnerPartId=-1|Location.X=1077|Location.Y=1032|Color=8388608|FontID=1|IsHidden=T|Text=155 degC|Name=Max Operating Temperature
|RECORD=41|OwnerIndex=835|IndexInSheet=8|OwnerPartId=-1|Location.X=1077|Location.Y=1032|Color=8388608|FontID=1|IsHidden=T|Text=Manufacturer URL|Name=ComponentLink1Description
|RECORD=41|OwnerIndex=835|IndexInSheet=9|OwnerPartId=-1|Location.X=1077|Location.Y=1032|Color=8388608|FontID=1|IsHidden=T|Text=Datasheet|Name=ComponentLink2Description
|RECORD=41|OwnerIndex=835|IndexInSheet=10|OwnerPartId=-1|Location.X=1077|Location.Y=1032|Color=8388608|FontID=1|IsHidden=T|Text=2|Name=Pins
|RECORD=41|OwnerIndex=835|IndexInSheet=11|OwnerPartId=-1|Location.X=1077|Location.Y=1032|Color=8388608|FontID=1|IsHidden=T|Text=0402|Name=PackageReference
|RECORD=41|OwnerIndex=835|IndexInSheet=12|OwnerPartId=-1|Location.X=1077|Location.Y=1032|Color=8388608|FontID=1|IsHidden=T|Text=1%|Name=Tolerance
|RECORD=41|OwnerIndex=835|IndexInSheet=13|OwnerPartId=-1|Location.X=1077|Location.Y=1032|Color=8388608|FontID=1|IsHidden=T|Text=0402|Name=Case Code (Imperial)
|RECORD=41|OwnerIndex=835|IndexInSheet=14|OwnerPartId=-1|Location.X=1077|Location.Y=1032|Color=8388608|FontID=1|IsHidden=T|Text=1 mm|Name=Length
|RECORD=41|OwnerIndex=835|IndexInSheet=15|OwnerPartId=-1|Location.X=1077|Location.Y=1032|Color=8388608|FontID=1|IsHidden=T|Text=2-Pin Surface Mount Device, Body 1 x 0.5 mm|Name=PackageDescription
|RECORD=41|OwnerIndex=835|IndexInSheet=16|OwnerPartId=-1|Location.X=1077|Location.Y=1032|Color=8388608|FontID=1|IsHidden=T|Text=ERJ-2RKF4701X|Name=PartNumber
|RECORD=41|OwnerIndex=835|IndexInSheet=17|OwnerPartId=-1|Location.X=1077|Location.Y=1032|Color=8388608|FontID=1|IsHidden=T|Text=true|Name=RoHSCompliant
|RECORD=41|OwnerIndex=835|IndexInSheet=18|OwnerPartId=-1|Location.X=1077|Location.Y=1032|Color=8388608|FontID=1|IsHidden=T|Text=1|Name=Package Quantity
|RECORD=41|OwnerIndex=835|IndexInSheet=19|OwnerPartId=-1|Location.X=1077|Location.Y=1032|Color=8388608|FontID=1|IsHidden=T|Text=No|Name=Radiation Hardening
|RECORD=41|OwnerIndex=835|IndexInSheet=20|OwnerPartId=-1|Location.X=1077|Location.Y=1032|Color=8388608|FontID=1|IsHidden=T|Text=04/2015|Name=DatasheetVersion
|RECORD=41|OwnerIndex=835|IndexInSheet=21|OwnerPartId=-1|Location.X=1077|Location.Y=1032|Color=8388608|FontID=1|IsHidden=T|Text=0.5 mm|Name=Width
|RECORD=41|OwnerIndex=835|IndexInSheet=22|OwnerPartId=-1|Location.X=1077|Location.Y=1032|Color=8388608|FontID=1|IsHidden=T|Text=1005|Name=Case Code (Metric)
|RECORD=41|OwnerIndex=835|IndexInSheet=23|OwnerPartId=-1|Location.X=1077|Location.Y=1032|Color=8388608|FontID=1|IsHidden=T|Text=50 V|Name=Voltage Rating
|RECORD=41|OwnerIndex=835|IndexInSheet=24|OwnerPartId=-1|Location.X=1077|Location.Y=1032|Color=8388608|FontID=1|IsHidden=T|Text=0402|Name=Case\/Package
|RECORD=41|OwnerIndex=835|IndexInSheet=25|OwnerPartId=-1|Location.X=1077|Location.Y=1032|Color=8388608|FontID=1|IsHidden=T|Text=Surface Mount|Name=Mount
|RECORD=41|OwnerIndex=835|IndexInSheet=26|OwnerPartId=-1|Location.X=1077|Location.Y=1032|Color=8388608|FontID=7|IsHidden=T|Text=http://www.panasonic.com/|Name=ComponentLink1URL
|RECORD=41|OwnerIndex=835|IndexInSheet=27|OwnerPartId=-1|Location.X=1077|Location.Y=1032|Color=8388608|FontID=1|IsHidden=T|Text=-55 degC|Name=Min Operating Temperature
|RECORD=41|OwnerIndex=835|IndexInSheet=28|OwnerPartId=-1|Location.X=1077|Location.Y=1032|Color=8388608|FontID=1|IsHidden=T|Text=100 mW|Name=Power Rating
|RECORD=41|OwnerIndex=835|IndexInSheet=29|OwnerPartId=-1|Location.X=1077|Location.Y=1032|Color=8388608|FontID=1|IsHidden=T|Text=Cut Tape|Name=Packaging
|RECORD=41|OwnerIndex=835|IndexInSheet=30|OwnerPartId=-1|Location.X=1077|Location.Y=1032|Color=8388608|FontID=7|IsHidden=T|Text=http://industrial.panasonic.com/cdbs/www-data/pdf/RDA0000/AOA0000C86.pdf|Name=ComponentLink2URL
|RECORD=34|OwnerIndex=835|IndexInSheet=-1|OwnerPartId=-1|Location.X=1083|Location.Y=1011|Color=8388608|FontID=1|Text=R3|Name=Designator|ReadOnlyState=1
|RECORD=41|OwnerIndex=835|IndexInSheet=-1|OwnerPartId=-1|Location.X=1083|Location.Y=1001|Color=8388608|FontID=1|Text=4.7K_0402|Name=Comment
|RECORD=44|OwnerIndex=835
|RECORD=45|OwnerIndex=871|IndexInSheet=-1|Description=Chip Resistor, 2-Leads, Body 1.05x0.55mm, IPC High Density|UseComponentLibrary=T|ModelName=RESC1005X40X25LL05T05|ModelType=PCBLIB|DatafileCount=1|ModelDatafileEntity0=RESC1005X40X25LL05T05|ModelDatafileKind0=PCBLib|IsCurrent=T|DatalinksLocked=T|DatabaseDatalinksLocked=T
|RECORD=46|OwnerIndex=872
|RECORD=48|OwnerIndex=872
|RECORD=41|OwnerIndex=874|IndexInSheet=-1|OwnerPartId=-1|Color=8388608|FontID=1|IsHidden=T|Text=2D|Name=Available Preview Images
|RECORD=45|OwnerIndex=871|IndexInSheet=-1|Description=Chip Resistor, 2-Leads, Body 1.05x0.55mm, IPC Low Density|UseComponentLibrary=T|ModelName=RESC1005X40X25ML05T05|ModelType=PCBLIB|DatafileCount=1|ModelDatafileEntity0=RESC1005X40X25ML05T05|ModelDatafileKind0=PCBLib|DatalinksLocked=T|DatabaseDatalinksLocked=T
|RECORD=46|OwnerIndex=876
|RECORD=48|OwnerIndex=876
|RECORD=41|OwnerIndex=878|IndexInSheet=-1|OwnerPartId=-1|Color=8388608|FontID=1|IsHidden=T|Text=2D|Name=Available Preview Images
|RECORD=45|OwnerIndex=871|IndexInSheet=-1|Description=Chip Resistor, 2-Leads, Body 1.05x0.55mm, IPC Medium Density|UseComponentLibrary=T|ModelName=RESC1005X40X25NL05T05|ModelType=PCBLIB|DatafileCount=1|ModelDatafileEntity0=RESC1005X40X25NL05T05|ModelDatafileKind0=PCBLib|DatalinksLocked=T|DatabaseDatalinksLocked=T
|RECORD=46|OwnerIndex=880
|RECORD=48|OwnerIndex=880
|RECORD=41|OwnerIndex=882|IndexInSheet=-1|OwnerPartId=-1|Color=8388608|FontID=1|IsHidden=T|Text=2D|Name=Available Preview Images
|RECORD=17|IndexInSheet=70|OwnerPartId=-1|Style=4|ShowNetName=T|Location.X=870|Location.Y=750|Orientation=3|Color=128|FontID=1|Text=GND
|RECORD=1|LibReference=RES|PartCount=2|DisplayModeCount=2|IndexInSheet=71|OwnerPartId=-1|Location.X=790|Location.Y=865|CurrentPartId=1|SourceLibraryName=Altium Content Vault|TargetFileName=*|AreaColor=11599871|Color=128|PartIDLocked=F|DesignItemId=CMP-1011-00208-2|AllPinCount=2
|RECORD=2|OwnerIndex=885|OwnerPartId=1|OwnerPartDisplayMode=1|FormalType=1|Electrical=4|PinConglomerate=32|PinLength=10|Location.X=810|Location.Y=855|Name=2|Designator=2|PinPropagationDelay=0.000000E+000
|RECORD=2|OwnerIndex=885|OwnerPartId=1|OwnerPartDisplayMode=1|FormalType=1|Electrical=4|PinConglomerate=34|PinLength=10|Location.X=790|Location.Y=855|Name=1|Designator=1|PinPropagationDelay=0.000000E+000
|RECORD=14|OwnerIndex=885|IsNotAccesible=T|IndexInSheet=2|OwnerPartId=1|OwnerPartDisplayMode=1|Location.X=790|Location.Y=851|Corner.X=810|Corner.Y=859|LineWidth=1|Color=16711680|AreaColor=11599871
|RECORD=2|OwnerIndex=885|OwnerPartId=1|FormalType=1|Electrical=4|PinConglomerate=32|PinLength=10|Location.X=810|Location.Y=855|Name=2|Designator=2|PinPropagationDelay=0.000000E+000
|RECORD=2|OwnerIndex=885|OwnerPartId=1|FormalType=1|Electrical=4|PinConglomerate=34|PinLength=10|Location.X=790|Location.Y=855|Name=1|Designator=1|PinPropagationDelay=0.000000E+000
|RECORD=6|OwnerIndex=885|IsNotAccesible=T|IndexInSheet=5|OwnerPartId=1|LineWidth=1|Color=16711680|LocationCount=10|X1=810|Y1=855|X2=806|Y2=855|X3=805|Y3=853|X4=803|Y4=857|X5=801|Y5=853|X6=799|Y6=857|X7=797|Y7=853|X8=795|Y8=857|X9=794|Y9=855|X10=790|Y10=855
|RECORD=41|OwnerIndex=885|IndexInSheet=6|OwnerPartId=-1|Location.X=778|Location.Y=868|Color=8388608|FontID=1|IsHidden=T|Text=RC0402FR-072R21L|Name=Part Number
|RECORD=41|OwnerIndex=885|IndexInSheet=7|OwnerPartId=-1|Location.X=778|Location.Y=868|Color=8388608|FontID=1|IsHidden=T|Text=Yageo|Name=Manufacturer
|RECORD=34|OwnerIndex=885|IndexInSheet=-1|OwnerPartId=-1|Location.X=789|Location.Y=858|Color=8388608|FontID=1|Text=R59|Name=Designator|ReadOnlyState=1
|RECORD=41|OwnerIndex=885|IndexInSheet=-1|OwnerPartId=-1|Location.X=789|Location.Y=842|Color=8388608|FontID=1|Text=2.21_1%_0402|Name=Comment
|RECORD=44|OwnerIndex=885
|RECORD=45|OwnerIndex=900|IndexInSheet=-1|Description=Chip Resistor, 2-Leads, Body 1.00x0.50mm, IPC Low Density|UseComponentLibrary=T|ModelName=RESC1005X40X25ML05T10|ModelType=PCBLIB|DatafileCount=1|ModelDatafileEntity0=RESC1005X40X25ML05T10|ModelDatafileKind0=PCBLib|IsCurrent=T|DatalinksLocked=T|DatabaseDatalinksLocked=T
|RECORD=46|OwnerIndex=901
|RECORD=48|OwnerIndex=901
|RECORD=41|OwnerIndex=903|IndexInSheet=-1|OwnerPartId=-1|Color=8388608|FontID=1|IsHidden=T|Text=2D|Name=Available Preview Images
|RECORD=45|OwnerIndex=900|IndexInSheet=-1|Description=Chip Resistor, 2-Leads, Body 1.00x0.50mm, IPC High Density|UseComponentLibrary=T|ModelName=RESC1005X40X25LL05T10|ModelType=PCBLIB|DatafileCount=1|ModelDatafileEntity0=RESC1005X40X25LL05T10|ModelDatafileKind0=PCBLib|DatalinksLocked=T|DatabaseDatalinksLocked=T
|RECORD=46|OwnerIndex=905
|RECORD=48|OwnerIndex=905
|RECORD=41|OwnerIndex=907|IndexInSheet=-1|OwnerPartId=-1|Color=8388608|FontID=1|IsHidden=T|Text=2D|Name=Available Preview Images
|RECORD=45|OwnerIndex=900|IndexInSheet=-1|Description=Chip Resistor, 2-Leads, Body 1.00x0.50mm, IPC Medium Density|UseComponentLibrary=T|ModelName=RESC1005X40X25NL05T10|ModelType=PCBLIB|DatafileCount=1|ModelDatafileEntity0=RESC1005X40X25NL05T10|ModelDatafileKind0=PCBLib|DatalinksLocked=T|DatabaseDatalinksLocked=T
|RECORD=46|OwnerIndex=909
|RECORD=48|OwnerIndex=909
|RECORD=41|OwnerIndex=911|IndexInSheet=-1|OwnerPartId=-1|Color=8388608|FontID=1|IsHidden=T|Text=2D|Name=Available Preview Images
|RECORD=17|IndexInSheet=72|OwnerPartId=-1|ShowNetName=T|Location.X=750|Location.Y=1055|Orientation=1|Color=128|FontID=1|Text=+12V
|RECORD=17|IndexInSheet=73|OwnerPartId=-1|ShowNetName=T|Location.X=1080|Location.Y=1045|Orientation=1|Color=128|FontID=1|Text=+3.3V
|RECORD=1|LibReference=RES-2|ComponentDescription=Chip Resistor, 4.7 KOhm, +/- 1%, 0.1 W, -55 to 155 degC, 0402 (1005 Metric), RoHS, Tape and Reel|PartCount=2|DisplayModeCount=1|IndexInSheet=74|OwnerPartId=-1|Location.X=765|Location.Y=1025|Orientation=3|CurrentPartId=1|LibraryPath=*|SourceLibraryName=Altium Content Vault|TargetFileName=*|AreaColor=11599871|Color=128|PartIDLocked=T|DesignItemId=CMP-2002-01154-4|AllPinCount=2
|RECORD=2|OwnerIndex=915|OwnerPartId=1|FormalType=1|Electrical=4|PinConglomerate=35|PinLength=10|Location.X=765|Location.Y=1005|Name=2|Designator=2|PinPropagationDelay=0.000000E+000
|RECORD=2|OwnerIndex=915|OwnerPartId=1|FormalType=1|Electrical=4|PinConglomerate=33|PinLength=10|Location.X=765|Location.Y=1025|Name=1|Designator=1|PinPropagationDelay=0.000000E+000
|RECORD=6|OwnerIndex=915|IsNotAccesible=T|IndexInSheet=2|OwnerPartId=1|LineWidth=1|Color=16711680|LocationCount=10|X1=765|Y1=1005|X2=765|Y2=1009|X3=763|Y3=1010|X4=767|Y4=1012|X5=763|Y5=1014|X6=767|Y6=1016|X7=763|Y7=1018|X8=767|Y8=1020|X9=765|Y9=1021|X10=765|Y10=1025
|RECORD=41|OwnerIndex=915|IndexInSheet=3|OwnerPartId=-1|Location.X=762|Location.Y=1037|Color=8388608|FontID=1|IsHidden=T|Text=0.35 mm|Name=Height
|RECORD=41|OwnerIndex=915|IndexInSheet=4|OwnerPartId=-1|Location.X=762|Location.Y=1037|Color=8388608|FontID=1|IsHidden=T|Text=Surface Mount|Name=Mounting Technology
|RECORD=41|OwnerIndex=915|IndexInSheet=5|OwnerPartId=-1|Location.X=762|Location.Y=1037|Color=8388608|FontID=1|IsHidden=T|Text=Yes|Name=REACH SVHC
|RECORD=41|OwnerIndex=915|IndexInSheet=6|OwnerPartId=-1|Location.X=762|Location.Y=1037|Color=8388608|FontID=1|IsHidden=T|Text=4.7 KOhm|Name=Resistance
|RECORD=41|OwnerIndex=915|IndexInSheet=7|OwnerPartId=-1|Location.X=762|Location.Y=1037|Color=8388608|FontID=1|IsHidden=T|Text=155 degC|Name=Max Operating Temperature
|RECORD=41|OwnerIndex=915|IndexInSheet=8|OwnerPartId=-1|Location.X=762|Location.Y=1037|Color=8388608|FontID=1|IsHidden=T|Text=Manufacturer URL|Name=ComponentLink1Description
|RECORD=41|OwnerIndex=915|IndexInSheet=9|OwnerPartId=-1|Location.X=762|Location.Y=1037|Color=8388608|FontID=1|IsHidden=T|Text=Datasheet|Name=ComponentLink2Description
|RECORD=41|OwnerIndex=915|IndexInSheet=10|OwnerPartId=-1|Location.X=762|Location.Y=1037|Color=8388608|FontID=1|IsHidden=T|Text=2|Name=Pins
|RECORD=41|OwnerIndex=915|IndexInSheet=11|OwnerPartId=-1|Location.X=762|Location.Y=1037|Color=8388608|FontID=1|IsHidden=T|Text=0402|Name=PackageReference
|RECORD=41|OwnerIndex=915|IndexInSheet=12|OwnerPartId=-1|Location.X=762|Location.Y=1037|Color=8388608|FontID=1|IsHidden=T|Text=1%|Name=Tolerance
|RECORD=41|OwnerIndex=915|IndexInSheet=13|OwnerPartId=-1|Location.X=762|Location.Y=1037|Color=8388608|FontID=1|IsHidden=T|Text=0402|Name=Case Code (Imperial)
|RECORD=41|OwnerIndex=915|IndexInSheet=14|OwnerPartId=-1|Location.X=762|Location.Y=1037|Color=8388608|FontID=1|IsHidden=T|Text=1 mm|Name=Length
|RECORD=41|OwnerIndex=915|IndexInSheet=15|OwnerPartId=-1|Location.X=762|Location.Y=1037|Color=8388608|FontID=1|IsHidden=T|Text=2-Pin Surface Mount Device, Body 1 x 0.5 mm|Name=PackageDescription
|RECORD=41|OwnerIndex=915|IndexInSheet=16|OwnerPartId=-1|Location.X=762|Location.Y=1037|Color=8388608|FontID=1|IsHidden=T|Text=ERJ-2RKF4701X|Name=PartNumber
|RECORD=41|OwnerIndex=915|IndexInSheet=17|OwnerPartId=-1|Location.X=762|Location.Y=1037|Color=8388608|FontID=1|IsHidden=T|Text=true|Name=RoHSCompliant
|RECORD=41|OwnerIndex=915|IndexInSheet=18|OwnerPartId=-1|Location.X=762|Location.Y=1037|Color=8388608|FontID=1|IsHidden=T|Text=1|Name=Package Quantity
|RECORD=41|OwnerIndex=915|IndexInSheet=19|OwnerPartId=-1|Location.X=762|Location.Y=1037|Color=8388608|FontID=1|IsHidden=T|Text=No|Name=Radiation Hardening
|RECORD=41|OwnerIndex=915|IndexInSheet=20|OwnerPartId=-1|Location.X=762|Location.Y=1037|Color=8388608|FontID=1|IsHidden=T|Text=04/2015|Name=DatasheetVersion
|RECORD=41|OwnerIndex=915|IndexInSheet=21|OwnerPartId=-1|Location.X=762|Location.Y=1037|Color=8388608|FontID=1|IsHidden=T|Text=0.5 mm|Name=Width
|RECORD=41|OwnerIndex=915|IndexInSheet=22|OwnerPartId=-1|Location.X=762|Location.Y=1037|Color=8388608|FontID=1|IsHidden=T|Text=1005|Name=Case Code (Metric)
|RECORD=41|OwnerIndex=915|IndexInSheet=23|OwnerPartId=-1|Location.X=762|Location.Y=1037|Color=8388608|FontID=1|IsHidden=T|Text=50 V|Name=Voltage Rating
|RECORD=41|OwnerIndex=915|IndexInSheet=24|OwnerPartId=-1|Location.X=762|Location.Y=1037|Color=8388608|FontID=1|IsHidden=T|Text=0402|Name=Case\/Package
|RECORD=41|OwnerIndex=915|IndexInSheet=25|OwnerPartId=-1|Location.X=762|Location.Y=1037|Color=8388608|FontID=1|IsHidden=T|Text=Surface Mount|Name=Mount
|RECORD=41|OwnerIndex=915|IndexInSheet=26|OwnerPartId=-1|Location.X=762|Location.Y=1037|Color=8388608|FontID=7|IsHidden=T|Text=http://www.panasonic.com/|Name=ComponentLink1URL
|RECORD=41|OwnerIndex=915|IndexInSheet=27|OwnerPartId=-1|Location.X=762|Location.Y=1037|Color=8388608|FontID=1|IsHidden=T|Text=-55 degC|Name=Min Operating Temperature
|RECORD=41|OwnerIndex=915|IndexInSheet=28|OwnerPartId=-1|Location.X=762|Location.Y=1037|Color=8388608|FontID=1|IsHidden=T|Text=100 mW|Name=Power Rating
|RECORD=41|OwnerIndex=915|IndexInSheet=29|OwnerPartId=-1|Location.X=762|Location.Y=1037|Color=8388608|FontID=1|IsHidden=T|Text=Cut Tape|Name=Packaging
|RECORD=41|OwnerIndex=915|IndexInSheet=30|OwnerPartId=-1|Location.X=762|Location.Y=1037|Color=8388608|FontID=7|IsHidden=T|Text=http://industrial.panasonic.com/cdbs/www-data/pdf/RDA0000/AOA0000C86.pdf|Name=ComponentLink2URL
|RECORD=34|OwnerIndex=915|IndexInSheet=-1|OwnerPartId=-1|Location.X=768|Location.Y=1016|Color=8388608|FontID=1|Text=R2|Name=Designator|ReadOnlyState=1
|RECORD=41|OwnerIndex=915|IndexInSheet=-1|OwnerPartId=-1|Location.X=768|Location.Y=1006|Color=8388608|FontID=1|Text=4.7K_0402|Name=Comment
|RECORD=44|OwnerIndex=915
|RECORD=45|OwnerIndex=951|IndexInSheet=-1|Description=Chip Resistor, 2-Leads, Body 1.05x0.55mm, IPC High Density|UseComponentLibrary=T|ModelName=RESC1005X40X25LL05T05|ModelType=PCBLIB|DatafileCount=1|ModelDatafileEntity0=RESC1005X40X25LL05T05|ModelDatafileKind0=PCBLib|IsCurrent=T|DatalinksLocked=T|DatabaseDatalinksLocked=T
|RECORD=46|OwnerIndex=952
|RECORD=48|OwnerIndex=952
|RECORD=41|OwnerIndex=954|IndexInSheet=-1|OwnerPartId=-1|Color=8388608|FontID=1|IsHidden=T|Text=2D|Name=Available Preview Images
|RECORD=45|OwnerIndex=951|IndexInSheet=-1|Description=Chip Resistor, 2-Leads, Body 1.05x0.55mm, IPC Low Density|UseComponentLibrary=T|ModelName=RESC1005X40X25ML05T05|ModelType=PCBLIB|DatafileCount=1|ModelDatafileEntity0=RESC1005X40X25ML05T05|ModelDatafileKind0=PCBLib|DatalinksLocked=T|DatabaseDatalinksLocked=T
|RECORD=46|OwnerIndex=956
|RECORD=48|OwnerIndex=956
|RECORD=41|OwnerIndex=958|IndexInSheet=-1|OwnerPartId=-1|Color=8388608|FontID=1|IsHidden=T|Text=2D|Name=Available Preview Images
|RECORD=45|OwnerIndex=951|IndexInSheet=-1|Description=Chip Resistor, 2-Leads, Body 1.05x0.55mm, IPC Medium Density|UseComponentLibrary=T|ModelName=RESC1005X40X25NL05T05|ModelType=PCBLIB|DatafileCount=1|ModelDatafileEntity0=RESC1005X40X25NL05T05|ModelDatafileKind0=PCBLib|DatalinksLocked=T|DatabaseDatalinksLocked=T
|RECORD=46|OwnerIndex=960
|RECORD=48|OwnerIndex=960
|RECORD=41|OwnerIndex=962|IndexInSheet=-1|OwnerPartId=-1|Color=8388608|FontID=1|IsHidden=T|Text=2D|Name=Available Preview Images
|RECORD=1|LibReference=RES|ComponentDescription=1R21 0.063W 1% 0402 (1005 Metric)  SMD|PartCount=2|DisplayModeCount=2|IndexInSheet=75|OwnerPartId=-1|Location.X=1110|Location.Y=985|CurrentPartId=1|SourceLibraryName=Altium Content Vault|TargetFileName=*|AreaColor=11599871|Color=128|PartIDLocked=F|DesignItemId=CMP-1011-00180-1|AllPinCount=2
|RECORD=2|OwnerIndex=964|OwnerPartId=1|OwnerPartDisplayMode=1|FormalType=1|Electrical=4|PinConglomerate=32|PinLength=10|Location.X=1130|Location.Y=975|Name=2|Designator=2|PinPropagationDelay=0.000000E+000
|RECORD=2|OwnerIndex=964|OwnerPartId=1|OwnerPartDisplayMode=1|FormalType=1|Electrical=4|PinConglomerate=34|PinLength=10|Location.X=1110|Location.Y=975|Name=1|Designator=1|PinPropagationDelay=0.000000E+000
|RECORD=14|OwnerIndex=964|IsNotAccesible=T|IndexInSheet=2|OwnerPartId=1|OwnerPartDisplayMode=1|Location.X=1110|Location.Y=971|Corner.X=1130|Corner.Y=979|LineWidth=1|Color=16711680|AreaColor=11599871
|RECORD=2|OwnerIndex=964|OwnerPartId=1|FormalType=1|Electrical=4|PinConglomerate=32|PinLength=10|Location.X=1130|Location.Y=975|Name=2|Designator=2|PinPropagationDelay=0.000000E+000
|RECORD=2|OwnerIndex=964|OwnerPartId=1|FormalType=1|Electrical=4|PinConglomerate=34|PinLength=10|Location.X=1110|Location.Y=975|Name=1|Designator=1|PinPropagationDelay=0.000000E+000
|RECORD=6|OwnerIndex=964|IsNotAccesible=T|IndexInSheet=5|OwnerPartId=1|LineWidth=1|Color=16711680|LocationCount=10|X1=1130|Y1=975|X2=1126|Y2=975|X3=1125|Y3=973|X4=1123|Y4=977|X5=1121|Y5=973|X6=1119|Y6=977|X7=1117|Y7=973|X8=1115|Y8=977|X9=1114|Y9=975|X10=1110|Y10=975
|RECORD=41|OwnerIndex=964|IndexInSheet=6|OwnerPartId=-1|Location.X=1098|Location.Y=988|Color=8388608|FontID=1|IsHidden=T|Text=1 %|Name=Tolerance
|RECORD=41|OwnerIndex=964|IndexInSheet=7|OwnerPartId=-1|Location.X=1098|Location.Y=988|Color=8388608|FontID=1|IsHidden=T|Text=0402|Name=Case-EIA
|RECORD=41|OwnerIndex=964|IndexInSheet=8|OwnerPartId=-1|Location.X=1098|Location.Y=988|Color=8388608|FontID=1|IsHidden=T|Text=1.21 Ohm|Name=Value
|RECORD=41|OwnerIndex=964|IndexInSheet=9|OwnerPartId=-1|Location.X=1098|Location.Y=988|Color=8388608|FontID=1|IsHidden=T|Text=1005|Name=Case-Metric
|RECORD=41|OwnerIndex=964|IndexInSheet=10|OwnerPartId=-1|Location.X=1098|Location.Y=988|Color=8388608|FontID=1|IsHidden=T|Text=0.063 W|Name=Power
|RECORD=41|OwnerIndex=964|IndexInSheet=11|OwnerPartId=-1|Location.X=1098|Location.Y=988|Color=8388608|FontID=1|IsHidden=T|Text=SMT|Name=Technology
|RECORD=34|OwnerIndex=964|IndexInSheet=-1|OwnerPartId=-1|Location.X=1109|Location.Y=978|Color=8388608|FontID=1|Text=R4|Name=Designator|ReadOnlyState=1
|RECORD=41|OwnerIndex=964|IndexInSheet=-1|OwnerPartId=-1|Location.X=1109|Location.Y=962|Color=8388608|FontID=1|Text=1.21_1%_0402|Name=Comment
|RECORD=44|OwnerIndex=964
|RECORD=45|OwnerIndex=983|IndexInSheet=-1|Description=Chip Resistor, Body 1.0x0.5mm, IPC Medium Density|UseComponentLibrary=T|ModelName=RESC0402(1005)_N|ModelType=PCBLIB|DatafileCount=1|ModelDatafileEntity0=RESC0402(1005)_N|ModelDatafileKind0=PCBLib|IsCurrent=T|DatalinksLocked=T|DatabaseDatalinksLocked=T
|RECORD=46|OwnerIndex=984
|RECORD=48|OwnerIndex=984
|RECORD=41|OwnerIndex=986|IndexInSheet=-1|OwnerPartId=-1|Color=8388608|FontID=1|IsHidden=T|Text=2D|Name=Available Preview Images
|RECORD=45|OwnerIndex=983|IndexInSheet=-1|Description=Chip Resistor, Body 1.0x0.5mm, IPC Low Density|UseComponentLibrary=T|ModelName=RESC0402(1005)_M|ModelType=PCBLIB|DatafileCount=1|ModelDatafileEntity0=RESC0402(1005)_M|ModelDatafileKind0=PCBLib|DatalinksLocked=T|DatabaseDatalinksLocked=T
|RECORD=46|OwnerIndex=988
|RECORD=48|OwnerIndex=988
|RECORD=41|OwnerIndex=990|IndexInSheet=-1|OwnerPartId=-1|Color=8388608|FontID=1|IsHidden=T|Text=2D|Name=Available Preview Images
|RECORD=45|OwnerIndex=983|IndexInSheet=-1|Description=Chip Resistor, Body 1.0x0.5mm, IPC High Density|UseComponentLibrary=T|ModelName=RESC0402(1005)_L|ModelType=PCBLIB|DatafileCount=1|ModelDatafileEntity0=RESC0402(1005)_L|ModelDatafileKind0=PCBLib|DatalinksLocked=T|DatabaseDatalinksLocked=T
|RECORD=46|OwnerIndex=992
|RECORD=48|OwnerIndex=992
|RECORD=41|OwnerIndex=994|IndexInSheet=-1|OwnerPartId=-1|Color=8388608|FontID=1|IsHidden=T|Text=2D|Name=Available Preview Images
|RECORD=1|LibReference=b4654b650e69147ec39a6b967a45e02|ComponentDescription=General Purpose Ceramic Capacitor, 0402, 100nF, 10%, X7R, 15%, 25V|PartCount=2|DisplayModeCount=1|IndexInSheet=76|OwnerPartId=-1|Location.X=830|Location.Y=835|CurrentPartId=1|LibraryPath=*|SourceLibraryName=Altium Content Vault|TargetFileName=*|AreaColor=11599871|Color=128|PartIDLocked=T|DesignItemId=CMP-2008-02519-2|AllPinCount=2
|RECORD=2|OwnerIndex=996|OwnerPartId=1|Electrical=4|PinConglomerate=49|PinLength=7|Location.X=830|Location.Y=828|Name=1|Designator=1|PinPropagationDelay=0.000000E+000
|RECORD=2|OwnerIndex=996|OwnerPartId=1|Electrical=4|PinConglomerate=51|PinLength=6|Location.X=830|Location.Y=821|Name=2|Designator=2|PinPropagationDelay=0.000000E+000
|RECORD=13|OwnerIndex=996|IsNotAccesible=T|IndexInSheet=2|OwnerPartId=1|Location.X=840|Location.Y=828|Corner.X=820|Corner.Y=828|LineWidth=1|Color=16711680
|RECORD=13|OwnerIndex=996|IsNotAccesible=T|IndexInSheet=3|OwnerPartId=1|Location.X=840|Location.Y=822|Corner.X=820|Corner.Y=822|LineWidth=1|Color=16711680
|RECORD=13|OwnerIndex=996|IsNotAccesible=T|IndexInSheet=4|OwnerPartId=1|Location.X=830|Location.Y=828|Corner.X=830|Corner.Y=831|LineWidth=1|Color=16711680
|RECORD=13|OwnerIndex=996|IsNotAccesible=T|IndexInSheet=5|OwnerPartId=1|Location.X=830|Location.Y=821|Corner.X=830|Corner.Y=820|LineWidth=1|Color=16711680
|RECORD=41|OwnerIndex=996|IndexInSheet=6|OwnerPartId=-1|Location.X=819|Location.Y=837|Color=8388608|FontID=1|IsHidden=T|Text=1|Name=Package Quantity
|RECORD=41|OwnerIndex=996|IndexInSheet=7|OwnerPartId=-1|Location.X=819|Location.Y=837|Color=8388608|FontID=1|IsHidden=T|Text=100nF|Name=Capacitance
|RECORD=41|OwnerIndex=996|IndexInSheet=8|OwnerPartId=-1|Location.X=819|Location.Y=837|Color=8388608|FontID=1|IsHidden=T|Text=-55°C|Name=Min Operating Temperature
|RECORD=41|OwnerIndex=996|IndexInSheet=9|OwnerPartId=-1|Location.X=819|Location.Y=837|Color=8388608|FontID=1|IsHidden=T|Text=25V|Name=Voltage
|RECORD=41|OwnerIndex=996|IndexInSheet=10|OwnerPartId=-1|Location.X=819|Location.Y=837|Color=8388608|FontID=1|IsHidden=T|Text=25V|Name=Voltage Rating
|RECORD=41|OwnerIndex=996|IndexInSheet=11|OwnerPartId=-1|Location.X=819|Location.Y=837|Color=8388608|FontID=1|IsHidden=T|Text=Flat|Name=Construction
|RECORD=41|OwnerIndex=996|IndexInSheet=12|OwnerPartId=-1|Location.X=819|Location.Y=837|Color=8388608|FontID=1|IsHidden=T|Text=125°C|Name=Max Operating Temperature
|RECORD=41|OwnerIndex=996|IndexInSheet=13|OwnerPartId=-1|Location.X=819|Location.Y=837|Color=8388608|FontID=1|IsHidden=T|Text=No|Name=Radiation Hardening
|RECORD=41|OwnerIndex=996|IndexInSheet=14|OwnerPartId=-1|Location.X=819|Location.Y=837|Color=8388608|FontID=1|IsHidden=T|Text=0.5mm|Name=Depth
|RECORD=41|OwnerIndex=996|IndexInSheet=15|OwnerPartId=-1|Location.X=819|Location.Y=837|Color=8388608|FontID=1|IsHidden=T|Text=0.022inch|Name=Thickness
|RECORD=41|OwnerIndex=996|IndexInSheet=16|OwnerPartId=-1|Location.X=819|Location.Y=837|Color=8388608|FontID=1|IsHidden=T|Text=25V|Name=Voltage Rating (DC)
|RECORD=41|OwnerIndex=996|IndexInSheet=17|OwnerPartId=-1|Location.X=819|Location.Y=837|Color=8388608|FontID=1|IsHidden=T|Text=2|Name=Number of Pins
|RECORD=41|OwnerIndex=996|IndexInSheet=18|OwnerPartId=-1|Location.X=819|Location.Y=837|Color=8388608|FontID=1|IsHidden=T|Text=Lead Free|Name=Lead Free
|RECORD=41|OwnerIndex=996|IndexInSheet=19|OwnerPartId=-1|Location.X=819|Location.Y=837|Color=8388608|FontID=1|IsHidden=T|Text=-|Name=Series
|RECORD=41|OwnerIndex=996|IndexInSheet=20|OwnerPartId=-1|Location.X=819|Location.Y=837|Color=8388608|FontID=1|IsHidden=T|Text=No SVHC|Name=REACH SVHC
|RECORD=41|OwnerIndex=996|IndexInSheet=21|OwnerPartId=-1|Location.X=819|Location.Y=837|Color=8388608|FontID=1|IsHidden=T|Text=1mm|Name=Length
|RECORD=41|OwnerIndex=996|IndexInSheet=22|OwnerPartId=-1|Location.X=819|Location.Y=837|Color=8388608|FontID=1|IsHidden=T|Text=X7R|Name=Dielectric
|RECORD=41|OwnerIndex=996|IndexInSheet=23|OwnerPartId=-1|Location.X=819|Location.Y=837|Color=8388608|FontID=1|IsHidden=T|Text=Yes|Name=RoHS Compliant
|RECORD=41|OwnerIndex=996|IndexInSheet=24|OwnerPartId=-1|Location.X=819|Location.Y=837|Color=8388608|FontID=1|IsHidden=T|Text=Surface Mount|Name=Mount
|RECORD=41|OwnerIndex=996|IndexInSheet=25|OwnerPartId=-1|Location.X=819|Location.Y=837|Color=8388608|FontID=1|IsHidden=T|Text=Tape and Reel|Name=Packaging
|RECORD=41|OwnerIndex=996|IndexInSheet=26|OwnerPartId=-1|Location.X=819|Location.Y=837|Color=8388608|FontID=1|IsHidden=T|Text=0402|Name=Case/Package
|RECORD=41|OwnerIndex=996|IndexInSheet=27|OwnerPartId=-1|Location.X=819|Location.Y=837|Color=8388608|FontID=1|IsHidden=T|Text=0402|Name=Case Code (Imperial)
|RECORD=41|OwnerIndex=996|IndexInSheet=28|OwnerPartId=-1|Location.X=819|Location.Y=837|Color=8388608|FontID=1|IsHidden=T|Text=SMD/SMT|Name=Termination
|RECORD=41|OwnerIndex=996|IndexInSheet=29|OwnerPartId=-1|Location.X=819|Location.Y=837|Color=8388608|FontID=1|IsHidden=T|Text=0.02inch|Name=Width
|RECORD=41|OwnerIndex=996|IndexInSheet=30|OwnerPartId=-1|Location.X=819|Location.Y=837|Color=8388608|FontID=1|IsHidden=T|Text=1005|Name=Case Code (Metric)
|RECORD=41|OwnerIndex=996|IndexInSheet=31|OwnerPartId=-1|Location.X=819|Location.Y=837|Color=8388608|FontID=1|IsHidden=T|Text=10%|Name=Tolerance
|RECORD=34|OwnerIndex=996|IndexInSheet=-1|OwnerPartId=-1|Location.X=841|Location.Y=822|Color=8388608|FontID=1|Text=C6|Name=Designator|ReadOnlyState=1
|RECORD=41|OwnerIndex=996|IndexInSheet=-1|OwnerPartId=1|Location.X=840|Location.Y=810|Color=8388608|FontID=1|Text=0.1uF_25V_0402|Name=Comment
|RECORD=44|OwnerIndex=996
|RECORD=45|OwnerIndex=1033|IndexInSheet=-1|UseComponentLibrary=T|ModelName=FP-0402-L_1_0_1-W_0_5_0_1-IPC_C|ModelType=PCBLIB|DatafileCount=1|ModelDatafileEntity0=FP-0402-L_1_0_1-W_0_5_0_1-IPC_C|ModelDatafileKind0=PCBLib|IsCurrent=T|DatalinksLocked=T|DatabaseDatalinksLocked=T
|RECORD=46|OwnerIndex=1034
|RECORD=48|OwnerIndex=1034
|RECORD=45|OwnerIndex=1033|IndexInSheet=-1|UseComponentLibrary=T|ModelName=FP-0402-L_1_0_1-W_0_5_0_1-IPC_B|ModelType=PCBLIB|DatafileCount=1|ModelDatafileEntity0=FP-0402-L_1_0_1-W_0_5_0_1-IPC_B|ModelDatafileKind0=PCBLib|DatalinksLocked=T|DatabaseDatalinksLocked=T
|RECORD=46|OwnerIndex=1037
|RECORD=48|OwnerIndex=1037
|RECORD=45|OwnerIndex=1033|IndexInSheet=-1|UseComponentLibrary=T|ModelName=FP-0402-L_1_0_1-W_0_5_0_1-MFG|ModelType=PCBLIB|DatafileCount=1|ModelDatafileEntity0=FP-0402-L_1_0_1-W_0_5_0_1-MFG|ModelDatafileKind0=PCBLib|DatalinksLocked=T|DatabaseDatalinksLocked=T
|RECORD=46|OwnerIndex=1040
|RECORD=48|OwnerIndex=1040
|RECORD=45|OwnerIndex=1033|IndexInSheet=-1|UseComponentLibrary=T|ModelName=FP-0402-L_1_0_1-W_0_5_0_1-IPC_A|ModelType=PCBLIB|DatafileCount=1|ModelDatafileEntity0=FP-0402-L_1_0_1-W_0_5_0_1-IPC_A|ModelDatafileKind0=PCBLib|DatalinksLocked=T|DatabaseDatalinksLocked=T
|RECORD=46|OwnerIndex=1043
|RECORD=48|OwnerIndex=1043
|RECORD=1|LibReference=RES|PartCount=2|DisplayModeCount=2|IndexInSheet=77|OwnerPartId=-1|Location.X=1135|Location.Y=915|Orientation=2|CurrentPartId=1|SourceLibraryName=Altium Content Vault|TargetFileName=*|AreaColor=11599871|Color=128|PartIDLocked=F|DesignItemId=CMP-1011-00208-2|AllPinCount=2
|RECORD=2|OwnerIndex=1046|OwnerPartId=1|OwnerPartDisplayMode=1|FormalType=1|Electrical=4|PinConglomerate=34|PinLength=10|Location.X=1115|Location.Y=925|Name=2|Designator=2|PinPropagationDelay=0.000000E+000
|RECORD=2|OwnerIndex=1046|OwnerPartId=1|OwnerPartDisplayMode=1|FormalType=1|Electrical=4|PinConglomerate=32|PinLength=10|Location.X=1135|Location.Y=925|Name=1|Designator=1|PinPropagationDelay=0.000000E+000
|RECORD=14|OwnerIndex=1046|IsNotAccesible=T|IndexInSheet=2|OwnerPartId=1|OwnerPartDisplayMode=1|Location.X=1115|Location.Y=921|Corner.X=1135|Corner.Y=929|LineWidth=1|Color=16711680|AreaColor=11599871
|RECORD=2|OwnerIndex=1046|OwnerPartId=1|FormalType=1|Electrical=4|PinConglomerate=34|PinLength=10|Location.X=1115|Location.Y=925|Name=2|Designator=2|PinPropagationDelay=0.000000E+000
|RECORD=2|OwnerIndex=1046|OwnerPartId=1|FormalType=1|Electrical=4|PinConglomerate=32|PinLength=10|Location.X=1135|Location.Y=925|Name=1|Designator=1|PinPropagationDelay=0.000000E+000
|RECORD=6|OwnerIndex=1046|IsNotAccesible=T|IndexInSheet=5|OwnerPartId=1|LineWidth=1|Color=16711680|LocationCount=10|X1=1115|Y1=925|X2=1119|Y2=925|X3=1120|Y3=927|X4=1122|Y4=923|X5=1124|Y5=927|X6=1126|Y6=923|X7=1128|Y7=927|X8=1130|Y8=923|X9=1131|Y9=925|X10=1135|Y10=925
|RECORD=41|OwnerIndex=1046|IndexInSheet=6|OwnerPartId=-1|Location.X=1103|Location.Y=928|Color=8388608|FontID=1|IsHidden=T|Text=RC0402FR-072R21L|Name=Part Number
|RECORD=41|OwnerIndex=1046|IndexInSheet=7|OwnerPartId=-1|Location.X=1103|Location.Y=928|Color=8388608|FontID=1|IsHidden=T|Text=Yageo|Name=Manufacturer
|RECORD=34|OwnerIndex=1046|IndexInSheet=-1|OwnerPartId=-1|Location.X=1114|Location.Y=928|Color=8388608|FontID=1|Text=R6|Name=Designator|ReadOnlyState=1
|RECORD=41|OwnerIndex=1046|IndexInSheet=-1|OwnerPartId=-1|Location.X=1114|Location.Y=912|Color=8388608|FontID=1|Text=2.21_1%_0402|Name=Comment
|RECORD=44|OwnerIndex=1046
|RECORD=45|OwnerIndex=1061|IndexInSheet=-1|Description=Chip Resistor, 2-Leads, Body 1.00x0.50mm, IPC Low Density|UseComponentLibrary=T|ModelName=RESC1005X40X25ML05T10|ModelType=PCBLIB|DatafileCount=1|ModelDatafileEntity0=RESC1005X40X25ML05T10|ModelDatafileKind0=PCBLib|IsCurrent=T|DatalinksLocked=T|DatabaseDatalinksLocked=T
|RECORD=46|OwnerIndex=1062
|RECORD=48|OwnerIndex=1062
|RECORD=41|OwnerIndex=1064|IndexInSheet=-1|OwnerPartId=-1|Color=8388608|FontID=1|IsHidden=T|Text=2D|Name=Available Preview Images
|RECORD=45|OwnerIndex=1061|IndexInSheet=-1|Description=Chip Resistor, 2-Leads, Body 1.00x0.50mm, IPC High Density|UseComponentLibrary=T|ModelName=RESC1005X40X25LL05T10|ModelType=PCBLIB|DatafileCount=1|ModelDatafileEntity0=RESC1005X40X25LL05T10|ModelDatafileKind0=PCBLib|DatalinksLocked=T|DatabaseDatalinksLocked=T
|RECORD=46|OwnerIndex=1066
|RECORD=48|OwnerIndex=1066
|RECORD=41|OwnerIndex=1068|IndexInSheet=-1|OwnerPartId=-1|Color=8388608|FontID=1|IsHidden=T|Text=2D|Name=Available Preview Images
|RECORD=45|OwnerIndex=1061|IndexInSheet=-1|Description=Chip Resistor, 2-Leads, Body 1.00x0.50mm, IPC Medium Density|UseComponentLibrary=T|ModelName=RESC1005X40X25NL05T10|ModelType=PCBLIB|DatafileCount=1|ModelDatafileEntity0=RESC1005X40X25NL05T10|ModelDatafileKind0=PCBLib|DatalinksLocked=T|DatabaseDatalinksLocked=T
|RECORD=46|OwnerIndex=1070
|RECORD=48|OwnerIndex=1070
|RECORD=41|OwnerIndex=1072|IndexInSheet=-1|OwnerPartId=-1|Color=8388608|FontID=1|IsHidden=T|Text=2D|Name=Available Preview Images
|RECORD=1|LibReference=725321dda6339637d4d059423bc1c3c|ComponentDescription=Commercial Inductors, High Saturation Series 2.2uH 10A 13.6mO 20%|PartCount=2|DisplayModeCount=1|IndexInSheet=78|OwnerPartId=-1|Location.X=1200|Location.Y=895|CurrentPartId=1|LibraryPath=*|SourceLibraryName=Altium Content Vault|TargetFileName=*|AreaColor=11599871|Color=128|PartIDLocked=T|DesignItemId=CMP-02424-000315-1|AllPinCount=2
|RECORD=2|OwnerIndex=1074|OwnerPartId=1|Electrical=4|PinConglomerate=50|PinLength=5|Location.X=1205|Location.Y=895|Name=1|Designator=1|PinPropagationDelay=0.000000E+000
|RECORD=2|OwnerIndex=1074|OwnerPartId=1|Electrical=4|PinConglomerate=48|PinLength=5|Location.X=1235|Location.Y=895|Name=2|Designator=2|PinPropagationDelay=0.000000E+000
|RECORD=12|OwnerIndex=1074|IsNotAccesible=T|IndexInSheet=2|OwnerPartId=1|Location.X=1210|Location.Y=895|Radius=5|LineWidth=1|EndAngle=-180.000|Color=16711680
|RECORD=12|OwnerIndex=1074|IsNotAccesible=T|IndexInSheet=3|OwnerPartId=1|Location.X=1220|Location.Y=895|Radius=5|LineWidth=1|EndAngle=-180.000|Color=16711680
|RECORD=12|OwnerIndex=1074|IsNotAccesible=T|IndexInSheet=4|OwnerPartId=1|Location.X=1230|Location.Y=895|Radius=5|LineWidth=1|EndAngle=-180.000|Color=16711680
|RECORD=13|OwnerIndex=1074|IsNotAccesible=T|IndexInSheet=5|OwnerPartId=1|Location.X=1205|Location.Y=895|Corner.X=1203|Corner.Y=895|LineWidth=1|Color=16711680
|RECORD=13|OwnerIndex=1074|IsNotAccesible=T|IndexInSheet=6|OwnerPartId=1|Location.X=1235|Location.Y=895|Corner.X=1236|Corner.Y=895|LineWidth=1|Color=16711680
|RECORD=41|OwnerIndex=1074|IndexInSheet=7|OwnerPartId=-1|Location.X=1198|Location.Y=900|Color=8388608|FontID=1|IsHidden=T|Text=Ferrite|Name=Core Material
|RECORD=41|OwnerIndex=1074|IndexInSheet=8|OwnerPartId=-1|Location.X=1198|Location.Y=900|Color=8388608|FontID=1|IsHidden=T|Text=Shielded|Name=Shielding
|RECORD=41|OwnerIndex=1074|IndexInSheet=9|OwnerPartId=-1|Location.X=1198|Location.Y=900|Color=8388608|FontID=1|IsHidden=T|Text=20%|Name=Tolerance
|RECORD=41|OwnerIndex=1074|IndexInSheet=10|OwnerPartId=-1|Location.X=1198|Location.Y=900|Color=8388608|FontID=1|IsHidden=T|Text=7.24mm|Name=Length
|RECORD=41|OwnerIndex=1074|IndexInSheet=11|OwnerPartId=-1|Location.X=1198|Location.Y=900|Color=8388608|FontID=1|IsHidden=T|Text=10A|Name=Current Rating
|RECORD=41|OwnerIndex=1074|IndexInSheet=12|OwnerPartId=-1|Location.X=1198|Location.Y=900|Color=8388608|FontID=1|IsHidden=T|Text=2.2uH|Name=Inductance
|RECORD=41|OwnerIndex=1074|IndexInSheet=13|OwnerPartId=-1|Location.X=1198|Location.Y=900|Color=8388608|FontID=1|IsHidden=T|Text=-55°C|Name=Min Operating Temperature
|RECORD=41|OwnerIndex=1074|IndexInSheet=14|OwnerPartId=-1|Location.X=1198|Location.Y=900|Color=8388608|FontID=1|IsHidden=T|Text=20%|Name=Inductance Tolerance
|RECORD=41|OwnerIndex=1074|IndexInSheet=15|OwnerPartId=-1|Location.X=1198|Location.Y=900|Color=8388608|FontID=1|IsHidden=T|Text=500|Name=Package Quantity
|RECORD=41|OwnerIndex=1074|IndexInSheet=16|OwnerPartId=-1|Location.X=1198|Location.Y=900|Color=8388608|FontID=1|IsHidden=T|Text=Tin|Name=Contact Plating
|RECORD=41|OwnerIndex=1074|IndexInSheet=17|OwnerPartId=-1|Location.X=1198|Location.Y=900|Color=8388608|FontID=1|IsHidden=T|Text=SMD/SMT|Name=Termination
|RECORD=41|OwnerIndex=1074|IndexInSheet=18|OwnerPartId=-1|Location.X=1198|Location.Y=900|Color=8388608|FontID=1|IsHidden=T|Text=Tape and Reel|Name=Packaging
|RECORD=41|OwnerIndex=1074|IndexInSheet=19|OwnerPartId=-1|Location.X=1198|Location.Y=900|Color=8388608|FontID=1|IsHidden=T|Text=5mm|Name=Height
|RECORD=41|OwnerIndex=1074|IndexInSheet=20|OwnerPartId=-1|Location.X=1198|Location.Y=900|Color=8388608|FontID=1|IsHidden=T|Text=1MHz|Name=Self Resonant Frequency
|RECORD=41|OwnerIndex=1074|IndexInSheet=21|OwnerPartId=-1|Location.X=1198|Location.Y=900|Color=8388608|FontID=1|IsHidden=T|Text=125°C|Name=Max Operating Temperature
|RECORD=41|OwnerIndex=1074|IndexInSheet=22|OwnerPartId=-1|Location.X=1198|Location.Y=900|Color=8388608|FontID=1|IsHidden=T|Text=2525|Name=Case/Package
|RECORD=41|OwnerIndex=1074|IndexInSheet=23|OwnerPartId=-1|Location.X=1198|Location.Y=900|Color=8388608|FontID=1|IsHidden=T|Text=13.6mR|Name=DC Resistance (DCR)
|RECORD=41|OwnerIndex=1074|IndexInSheet=24|OwnerPartId=-1|Location.X=1198|Location.Y=900|Color=8388608|FontID=1|IsHidden=T|Text=10A|Name=Saturation Current
|RECORD=41|OwnerIndex=1074|IndexInSheet=25|OwnerPartId=-1|Location.X=1198|Location.Y=900|Color=8388608|FontID=1|IsHidden=T|Text=Surface Mount|Name=Mount
|RECORD=41|OwnerIndex=1074|IndexInSheet=26|OwnerPartId=-1|Location.X=1198|Location.Y=900|Color=8388608|FontID=1|IsHidden=T|Text=Not|Name=Military Standard
|RECORD=41|OwnerIndex=1074|IndexInSheet=27|OwnerPartId=-1|Location.X=1198|Location.Y=900|Color=8388608|FontID=1|IsHidden=T|Text=No|Name=Radiation Hardening
|RECORD=41|OwnerIndex=1074|IndexInSheet=28|OwnerPartId=-1|Location.X=1198|Location.Y=900|Color=8388608|FontID=1|IsHidden=T|Text=6.72mm|Name=Depth
|RECORD=41|OwnerIndex=1074|IndexInSheet=29|OwnerPartId=-1|Location.X=1198|Location.Y=900|Color=8388608|FontID=1|IsHidden=T|Text=100kHz|Name=Test Frequency
|RECORD=41|OwnerIndex=1074|IndexInSheet=30|OwnerPartId=-1|Location.X=1198|Location.Y=900|Color=8388608|FontID=1|IsHidden=T|Text=10A|Name=Max DC Current
|RECORD=41|OwnerIndex=1074|IndexInSheet=31|OwnerPartId=-1|Location.X=1198|Location.Y=900|Color=8388608|FontID=1|IsHidden=T|Text=Lead Free|Name=Lead Free
|RECORD=41|OwnerIndex=1074|IndexInSheet=32|OwnerPartId=-1|Location.X=1198|Location.Y=900|Color=8388608|FontID=1|IsHidden=T|Text=10A|Name=RMS Current (Irms)
|RECORD=41|OwnerIndex=1074|IndexInSheet=33|OwnerPartId=-1|Location.X=1198|Location.Y=900|Color=8388608|FontID=1|IsHidden=T|Text=6.47mm|Name=Width
|RECORD=41|OwnerIndex=1074|IndexInSheet=34|OwnerPartId=-1|Location.X=1198|Location.Y=900|Color=8388608|FontID=1|IsHidden=T|Text=0.197inch|Name=Height - Seated (Max)
|RECORD=34|OwnerIndex=1074|IndexInSheet=-1|OwnerPartId=-1|Location.X=1202|Location.Y=900|Color=8388608|FontID=1|Text=L1|Name=Designator|ReadOnlyState=1
|RECORD=41|OwnerIndex=1074|IndexInSheet=-1|OwnerPartId=1|Location.X=1202|Location.Y=882|Color=8388608|FontID=1|Text=2.2uH_10A|Name=Comment
|RECORD=44|OwnerIndex=1074
|RECORD=45|OwnerIndex=1114|IndexInSheet=-1|UseComponentLibrary=T|ModelName=FP-IHLP-2525EZ-FP_2_413x3-MFG|ModelType=PCBLIB|DatafileCount=1|ModelDatafileEntity0=FP-IHLP-2525EZ-FP_2_413x3-MFG|ModelDatafileKind0=PCBLib|IsCurrent=T|DatalinksLocked=T|DatabaseDatalinksLocked=T
|RECORD=46|OwnerIndex=1115
|RECORD=48|OwnerIndex=1115
|RECORD=1|LibReference=11868f565c42a9108669ba33697ecf6|ComponentDescription=CAP CER 0.1UF 50V X7R 0603|PartCount=2|DisplayModeCount=1|IndexInSheet=79|OwnerPartId=-1|Location.X=1180|Location.Y=965|CurrentPartId=1|LibraryPath=*|SourceLibraryName=Altium Content Vault|TargetFileName=*|AreaColor=11599871|Color=128|PartIDLocked=T|DesignItemId=CMP-2100-03601-2|AllPinCount=2
|RECORD=2|OwnerIndex=1118|OwnerPartId=1|Electrical=4|PinConglomerate=49|PinLength=7|Location.X=1180|Location.Y=958|Name=1|Designator=1|PinPropagationDelay=0.000000E+000
|RECORD=2|OwnerIndex=1118|OwnerPartId=1|Electrical=4|PinConglomerate=51|PinLength=6|Location.X=1180|Location.Y=951|Name=2|Designator=2|PinPropagationDelay=0.000000E+000
|RECORD=13|OwnerIndex=1118|IsNotAccesible=T|IndexInSheet=2|OwnerPartId=1|Location.X=1190|Location.Y=958|Corner.X=1170|Corner.Y=958|LineWidth=1|Color=16711680
|RECORD=13|OwnerIndex=1118|IsNotAccesible=T|IndexInSheet=3|OwnerPartId=1|Location.X=1190|Location.Y=952|Corner.X=1170|Corner.Y=952|LineWidth=1|Color=16711680
|RECORD=13|OwnerIndex=1118|IsNotAccesible=T|IndexInSheet=4|OwnerPartId=1|Location.X=1180|Location.Y=958|Corner.X=1180|Corner.Y=961|LineWidth=1|Color=16711680
|RECORD=13|OwnerIndex=1118|IsNotAccesible=T|IndexInSheet=5|OwnerPartId=1|Location.X=1180|Location.Y=951|Corner.X=1180|Corner.Y=950|LineWidth=1|Color=16711680
|RECORD=41|OwnerIndex=1118|IndexInSheet=6|OwnerPartId=-1|Location.X=1169|Location.Y=967|Color=8388608|FontID=1|IsHidden=T|Text=0.9mm|Name=Height
|RECORD=41|OwnerIndex=1118|IndexInSheet=7|OwnerPartId=-1|Location.X=1169|Location.Y=967|Color=8388608|FontID=1|IsHidden=T|Text=Ceramic|Name=Material
|RECORD=41|OwnerIndex=1118|IndexInSheet=8|OwnerPartId=-1|Location.X=1169|Location.Y=967|Color=8388608|FontID=1|IsHidden=T|Text=YAGEO|Name=Manufacturer
|RECORD=41|OwnerIndex=1118|IndexInSheet=9|OwnerPartId=-1|Location.X=1169|Location.Y=967|Color=8388608|FontID=1|IsHidden=T|Text=50 V|Name=Voltage
|RECORD=41|OwnerIndex=1118|IndexInSheet=10|OwnerPartId=-1|Location.X=1169|Location.Y=967|Color=8388608|FontID=1|IsHidden=T|Text=Datasheet|Name=ComponentLink2Description
|RECORD=41|OwnerIndex=1118|IndexInSheet=11|OwnerPartId=-1|Location.X=1169|Location.Y=967|Color=8388608|FontID=1|IsHidden=T|Text=Capacitors|Name=Device Class L2
|RECORD=41|OwnerIndex=1118|IndexInSheet=12|OwnerPartId=-1|Location.X=1169|Location.Y=967|Color=8388608|FontID=1|IsHidden=T|Text=+125°C|Name=Temperature Range High
|RECORD=41|OwnerIndex=1118|IndexInSheet=13|OwnerPartId=-1|Location.X=1169|Location.Y=967|Color=8388608|FontID=1|IsHidden=T|Text=Cap|Name=Category
|RECORD=41|OwnerIndex=1118|IndexInSheet=14|OwnerPartId=-1|Location.X=1169|Location.Y=967|Color=8388608|FontID=1|IsHidden=T|Text=100 nF|Name=Capacitance
|RECORD=41|OwnerIndex=1118|IndexInSheet=15|OwnerPartId=-1|Location.X=1169|Location.Y=967|Color=8388608|FontID=7|IsHidden=T|Text=http://www.yageo.com/exep/pages/download/literatures/UPY-C_GEN_24.pdf|Name=Footprint Url
|RECORD=41|OwnerIndex=1118|IndexInSheet=16|OwnerPartId=-1|Location.X=1169|Location.Y=967|Color=8388608|FontID=7|IsHidden=T|Text=http://www.yageo.com/documents/recent/UPY-GPHC_X7R_6.3V-to-50V_18.pdf|Name=ComponentLink2URL
|RECORD=41|OwnerIndex=1118|IndexInSheet=17|OwnerPartId=-1|Location.X=1169|Location.Y=967|Color=8388608|FontID=1|IsHidden=T|Text=CC0603-DA|Name=Package
|RECORD=41|OwnerIndex=1118|IndexInSheet=18|OwnerPartId=-1|Location.X=1169|Location.Y=967|Color=8388608|FontID=1|IsHidden=T|Text=-55°C to +125°C|Name=Temperature
|RECORD=41|OwnerIndex=1118|IndexInSheet=19|OwnerPartId=-1|Location.X=1169|Location.Y=967|Color=8388608|FontID=1|IsHidden=T|Text=15%|Name=Temperature Coefficient
|RECORD=41|OwnerIndex=1118|IndexInSheet=20|OwnerPartId=-1|Location.X=1169|Location.Y=967|Color=8388608|FontID=1|IsHidden=T|Text=50 V|Name=Voltage Rating
|RECORD=41|OwnerIndex=1118|IndexInSheet=21|OwnerPartId=-1|Location.X=1169|Location.Y=967|Color=8388608|FontID=1|IsHidden=T|Text=X7R|Name=Temperature Characteristic
|RECORD=41|OwnerIndex=1118|IndexInSheet=22|OwnerPartId=-1|Location.X=1169|Location.Y=967|Color=8388608|FontID=1|IsHidden=T|Text=Passive Components|Name=Device Class L1
|RECORD=41|OwnerIndex=1118|IndexInSheet=23|OwnerPartId=-1|Location.X=1169|Location.Y=967|Color=8388608|FontID=1|IsHidden=T|Text=-55°C|Name=Temperature Range Low
|RECORD=41|OwnerIndex=1118|IndexInSheet=24|OwnerPartId=-1|Location.X=1169|Location.Y=967|Color=8388608|FontID=1|IsHidden=T|Text=CC0603KRX7R9BB104|Name=Manufacturer Part Number
|RECORD=41|OwnerIndex=1118|IndexInSheet=25|OwnerPartId=-1|Location.X=1169|Location.Y=967|Color=8388608|FontID=1|IsHidden=T|Text=TRUE|Name=RoHS
|RECORD=41|OwnerIndex=1118|IndexInSheet=26|OwnerPartId=-1|Location.X=1169|Location.Y=967|Color=8388608|FontID=1|IsHidden=T|Text=0.1|Name=Tolerance
|RECORD=41|OwnerIndex=1118|IndexInSheet=27|OwnerPartId=-1|Location.X=1169|Location.Y=967|Color=8388608|FontID=1|IsHidden=T|Text=No|Name=Automotive
|RECORD=41|OwnerIndex=1118|IndexInSheet=28|OwnerPartId=-1|Location.X=1169|Location.Y=967|Color=8388608|FontID=1|IsHidden=T|Text=100 nF|Name=Value
|RECORD=41|OwnerIndex=1118|IndexInSheet=29|OwnerPartId=-1|Location.X=1169|Location.Y=967|Color=8388608|FontID=1|IsHidden=T|Text=Ceramic Capacitors|Name=Device Class L3
|RECORD=41|OwnerIndex=1118|IndexInSheet=30|OwnerPartId=-1|Location.X=1169|Location.Y=967|Color=8388608|FontID=7|IsHidden=T|Text=https://octopart.com/cc0603krx7r9bb104-yageo-42244635|Name=Octopart
|RECORD=41|OwnerIndex=1118|IndexInSheet=31|OwnerPartId=-1|Location.X=1169|Location.Y=967|Color=8388608|FontID=1|IsHidden=T|Text=Multilayer Ceramic Capacitor, CC Series, 0.1 - F, - 10%, X7R, 50 V, 0603 [1608 Metric]|Name=Mouser Description
|RECORD=41|OwnerIndex=1118|IndexInSheet=32|OwnerPartId=-1|Location.X=1169|Location.Y=967|Color=8388608|FontID=1|IsHidden=T|Text=Yes|Name=Lead Free
|RECORD=41|OwnerIndex=1118|IndexInSheet=33|OwnerPartId=-1|Location.X=1169|Location.Y=967|Color=8388608|FontID=1|IsHidden=T|Text=CAP CER 0.1UF 50V X7R 0603|Name=Digikey Description
|RECORD=34|OwnerIndex=1118|IndexInSheet=-1|OwnerPartId=-1|Location.X=1191|Location.Y=952|Color=8388608|FontID=1|Text=C3|Name=Designator|ReadOnlyState=1
|RECORD=41|OwnerIndex=1118|IndexInSheet=-1|OwnerPartId=1|Location.X=1191|Location.Y=942|Color=8388608|FontID=1|Text=0.1uF_50V_0603|Name=Comment
|RECORD=44|OwnerIndex=1118
|RECORD=45|OwnerIndex=1157|IndexInSheet=-1|UseComponentLibrary=T|ModelName=FP-CC0603-DA-MFG|ModelType=PCBLIB|DatafileCount=1|ModelDatafileEntity0=FP-CC0603-DA-MFG|ModelDatafileKind0=PCBLib|IsCurrent=T|DatalinksLocked=T|DatabaseDatalinksLocked=T
|RECORD=46|OwnerIndex=1158
|RECORD=48|OwnerIndex=1158
|RECORD=45|OwnerIndex=1157|IndexInSheet=-1|UseComponentLibrary=T|ModelName=FP-CC0603-DA-IPC_C|ModelType=PCBLIB|DatafileCount=1|ModelDatafileEntity0=FP-CC0603-DA-IPC_C|ModelDatafileKind0=PCBLib|DatalinksLocked=T|DatabaseDatalinksLocked=T
|RECORD=46|OwnerIndex=1161
|RECORD=48|OwnerIndex=1161
|RECORD=45|OwnerIndex=1157|IndexInSheet=-1|UseComponentLibrary=T|ModelName=FP-CC0603-DA-IPC_B|ModelType=PCBLIB|DatafileCount=1|ModelDatafileEntity0=FP-CC0603-DA-IPC_B|ModelDatafileKind0=PCBLib|DatalinksLocked=T|DatabaseDatalinksLocked=T
|RECORD=46|OwnerIndex=1164
|RECORD=48|OwnerIndex=1164
|RECORD=45|OwnerIndex=1157|IndexInSheet=-1|UseComponentLibrary=T|ModelName=FP-CC0603-DA-IPC_A|ModelType=PCBLIB|DatafileCount=1|ModelDatafileEntity0=FP-CC0603-DA-IPC_A|ModelDatafileKind0=PCBLib|DatalinksLocked=T|DatabaseDatalinksLocked=T
|RECORD=46|OwnerIndex=1167
|RECORD=48|OwnerIndex=1167
|RECORD=1|LibReference=b4654b650e69147ec39a6b967a45e02|ComponentDescription=None|PartCount=2|DisplayModeCount=1|IndexInSheet=80|OwnerPartId=-1|Location.X=1400|Location.Y=875|CurrentPartId=1|LibraryPath=*|SourceLibraryName=Altium Content Vault|TargetFileName=*|AreaColor=11599871|Color=128|PartIDLocked=T|DesignItemId=CMP-14477-000104-2|AllPinCount=2
|RECORD=2|OwnerIndex=1170|OwnerPartId=1|Electrical=4|PinConglomerate=49|PinLength=7|Location.X=1400|Location.Y=868|Name=1|Designator=1|PinPropagationDelay=0.000000E+000
|RECORD=2|OwnerIndex=1170|OwnerPartId=1|Electrical=4|PinConglomerate=51|PinLength=6|Location.X=1400|Location.Y=861|Name=2|Designator=2|PinPropagationDelay=0.000000E+000
|RECORD=13|OwnerIndex=1170|IsNotAccesible=T|IndexInSheet=2|OwnerPartId=1|Location.X=1410|Location.Y=868|Corner.X=1390|Corner.Y=868|LineWidth=1|Color=16711680
|RECORD=13|OwnerIndex=1170|IsNotAccesible=T|IndexInSheet=3|OwnerPartId=1|Location.X=1410|Location.Y=862|Corner.X=1390|Corner.Y=862|LineWidth=1|Color=16711680
|RECORD=13|OwnerIndex=1170|IsNotAccesible=T|IndexInSheet=4|OwnerPartId=1|Location.X=1400|Location.Y=868|Corner.X=1400|Corner.Y=871|LineWidth=1|Color=16711680
|RECORD=13|OwnerIndex=1170|IsNotAccesible=T|IndexInSheet=5|OwnerPartId=1|Location.X=1400|Location.Y=861|Corner.X=1400|Corner.Y=860|LineWidth=1|Color=16711680
|RECORD=41|OwnerIndex=1170|IndexInSheet=6|OwnerPartId=-1|Location.X=1389|Location.Y=877|Color=8388608|FontID=1|IsHidden=T|Text=Tape and Reel|Name=Packaging
|RECORD=41|OwnerIndex=1170|IndexInSheet=7|OwnerPartId=-1|Location.X=1389|Location.Y=877|Color=8388608|FontID=1|IsHidden=T|Text=0.5mm|Name=Depth
|RECORD=41|OwnerIndex=1170|IndexInSheet=8|OwnerPartId=-1|Location.X=1389|Location.Y=877|Color=8388608|FontID=1|IsHidden=T|Text=10%|Name=Tolerance
|RECORD=41|OwnerIndex=1170|IndexInSheet=9|OwnerPartId=-1|Location.X=1389|Location.Y=877|Color=8388608|FontID=1|IsHidden=T|Text=Surface Mount|Name=Mount
|RECORD=41|OwnerIndex=1170|IndexInSheet=10|OwnerPartId=-1|Location.X=1389|Location.Y=877|Color=8388608|FontID=1|IsHidden=T|Text=16V|Name=Voltage Rating
|RECORD=41|OwnerIndex=1170|IndexInSheet=11|OwnerPartId=-1|Location.X=1389|Location.Y=877|Color=8388608|FontID=1|IsHidden=T|Text=0.022inch|Name=Thickness
|RECORD=41|OwnerIndex=1170|IndexInSheet=12|OwnerPartId=-1|Location.X=1389|Location.Y=877|Color=8388608|FontID=1|IsHidden=T|Text=1|Name=Package Quantity
|RECORD=41|OwnerIndex=1170|IndexInSheet=13|OwnerPartId=-1|Location.X=1389|Location.Y=877|Color=8388608|FontID=1|IsHidden=T|Text=-55°C|Name=Min Operating Temperature
|RECORD=41|OwnerIndex=1170|IndexInSheet=14|OwnerPartId=-1|Location.X=1389|Location.Y=877|Color=8388608|FontID=1|IsHidden=T|Text=M|Name=Series
|RECORD=41|OwnerIndex=1170|IndexInSheet=15|OwnerPartId=-1|Location.X=1389|Location.Y=877|Color=8388608|FontID=1|IsHidden=T|Text=16V|Name=Voltage Rating (DC)
|RECORD=41|OwnerIndex=1170|IndexInSheet=16|OwnerPartId=-1|Location.X=1389|Location.Y=877|Color=8388608|FontID=1|IsHidden=T|Text=SMD/SMT|Name=Termination
|RECORD=41|OwnerIndex=1170|IndexInSheet=17|OwnerPartId=-1|Location.X=1389|Location.Y=877|Color=8388608|FontID=1|IsHidden=T|Text=0402|Name=Case/Package
|RECORD=41|OwnerIndex=1170|IndexInSheet=18|OwnerPartId=-1|Location.X=1389|Location.Y=877|Color=8388608|FontID=1|IsHidden=T|Text=X5R|Name=Dielectric
|RECORD=41|OwnerIndex=1170|IndexInSheet=19|OwnerPartId=-1|Location.X=1389|Location.Y=877|Color=8388608|FontID=1|IsHidden=T|Text=2|Name=Number of Pins
|RECORD=41|OwnerIndex=1170|IndexInSheet=20|OwnerPartId=-1|Location.X=1389|Location.Y=877|Color=8388608|FontID=1|IsHidden=T|Text=0402|Name=Case Code (Imperial)
|RECORD=41|OwnerIndex=1170|IndexInSheet=21|OwnerPartId=-1|Location.X=1389|Location.Y=877|Color=8388608|FontID=1|IsHidden=T|Text=1uF|Name=Capacitance
|RECORD=41|OwnerIndex=1170|IndexInSheet=22|OwnerPartId=-1|Location.X=1389|Location.Y=877|Color=8388608|FontID=1|IsHidden=T|Text=1mm|Name=Length
|RECORD=41|OwnerIndex=1170|IndexInSheet=23|OwnerPartId=-1|Location.X=1389|Location.Y=877|Color=8388608|FontID=1|IsHidden=T|Text=Halogen Free|Name=Halogen Free
|RECORD=41|OwnerIndex=1170|IndexInSheet=24|OwnerPartId=-1|Location.X=1389|Location.Y=877|Color=8388608|FontID=1|IsHidden=T|Text=1005|Name=Case Code (Metric)
|RECORD=41|OwnerIndex=1170|IndexInSheet=25|OwnerPartId=-1|Location.X=1389|Location.Y=877|Color=8388608|FontID=1|IsHidden=T|Text=0.02inch|Name=Width
|RECORD=41|OwnerIndex=1170|IndexInSheet=26|OwnerPartId=-1|Location.X=1389|Location.Y=877|Color=8388608|FontID=1|IsHidden=T|Text=Yes|Name=RoHS Compliant
|RECORD=41|OwnerIndex=1170|IndexInSheet=27|OwnerPartId=-1|Location.X=1389|Location.Y=877|Color=8388608|FontID=1|IsHidden=T|Text=No|Name=Radiation Hardening
|RECORD=41|OwnerIndex=1170|IndexInSheet=28|OwnerPartId=-1|Location.X=1389|Location.Y=877|Color=8388608|FontID=1|IsHidden=T|Text=85°C|Name=Max Operating Temperature
|RECORD=41|OwnerIndex=1170|IndexInSheet=29|OwnerPartId=-1|Location.X=1389|Location.Y=877|Color=8388608|FontID=1|IsHidden=T|Text=0.5mm|Name=Height
|RECORD=41|OwnerIndex=1170|IndexInSheet=30|OwnerPartId=-1|Location.X=1389|Location.Y=877|Color=8388608|FontID=1|IsHidden=T|Text=Flat|Name=Construction
|RECORD=34|OwnerIndex=1170|IndexInSheet=-1|OwnerPartId=-1|Location.X=1385|Location.Y=855|Orientation=1|Color=8388608|FontID=2|Text=C4|Name=Designator|ReadOnlyState=1
|RECORD=41|OwnerIndex=1170|IndexInSheet=-1|OwnerPartId=1|Location.X=1420|Location.Y=840|Orientation=1|Color=8388608|FontID=2|Text=1uF_16V_0402|Name=Comment
|RECORD=44|OwnerIndex=1170
|RECORD=45|OwnerIndex=1206|IndexInSheet=-1|UseComponentLibrary=T|ModelName=FP-0402-L_1_0_0_05-W_0_5-IPC_A|ModelType=PCBLIB|DatafileCount=1|ModelDatafileEntity0=FP-0402-L_1_0_0_05-W_0_5-IPC_A|ModelDatafileKind0=PCBLib|IsCurrent=T|DatalinksLocked=T|DatabaseDatalinksLocked=T
|RECORD=46|OwnerIndex=1207
|RECORD=48|OwnerIndex=1207
|RECORD=45|OwnerIndex=1206|IndexInSheet=-1|UseComponentLibrary=T|ModelName=EMK105BJ105_V-F|ModelType=SIM|IsCurrent=T|DatalinksLocked=T|DatabaseDatalinksLocked=T
|RECORD=46|OwnerIndex=1210
|RECORD=48|OwnerIndex=1210
|RECORD=41|OwnerIndex=1212|IndexInSheet=-1|OwnerPartId=-1|Color=8388608|FontID=1|IsHidden=T|Text=General|Name=Kind
|RECORD=41|OwnerIndex=1212|IndexInSheet=-1|OwnerPartId=-1|Color=8388608|FontID=1|IsHidden=T|Text=Spice Subcircuit|Name=SubKind
|RECORD=41|OwnerIndex=1212|IndexInSheet=-1|OwnerPartId=-1|Color=8388608|FontID=1|IsHidden=T|Name=Spice Prefix
|RECORD=41|OwnerIndex=1212|IndexInSheet=-1|OwnerPartId=-1|Color=8388608|FontID=1|IsHidden=T|Name=Excluded Parts
|RECORD=41|OwnerIndex=1212|IndexInSheet=-1|OwnerPartId=-1|Color=8388608|FontID=1|IsHidden=T|Name=Netlist
|RECORD=41|OwnerIndex=1212|IndexInSheet=-1|OwnerPartId=-1|Color=8388608|FontID=1|IsHidden=T|Text=document_sim_cache\GNEMVTBT\0|Name=SimulationCacheLocation|ReadOnlyState=3
|RECORD=45|OwnerIndex=1206|IndexInSheet=-1|UseComponentLibrary=T|ModelName=FP-0402-L_1_0_0_05-W_0_5-IPC_B|ModelType=PCBLIB|DatafileCount=1|ModelDatafileEntity0=FP-0402-L_1_0_0_05-W_0_5-IPC_B|ModelDatafileKind0=PCBLib|DatalinksLocked=T|DatabaseDatalinksLocked=T
|RECORD=46|OwnerIndex=1219
|RECORD=48|OwnerIndex=1219
|RECORD=45|OwnerIndex=1206|IndexInSheet=-1|UseComponentLibrary=T|ModelName=FP-0402-L_1_0_0_05-W_0_5-IPC_C|ModelType=PCBLIB|DatafileCount=1|ModelDatafileEntity0=FP-0402-L_1_0_0_05-W_0_5-IPC_C|ModelDatafileKind0=PCBLib|DatalinksLocked=T|DatabaseDatalinksLocked=T
|RECORD=46|OwnerIndex=1222
|RECORD=48|OwnerIndex=1222
|RECORD=45|OwnerIndex=1206|IndexInSheet=-1|UseComponentLibrary=T|ModelName=FP-0402-L_1_0_0_05-W_0_5-MFG|ModelType=PCBLIB|DatafileCount=1|ModelDatafileEntity0=FP-0402-L_1_0_0_05-W_0_5-MFG|ModelDatafileKind0=PCBLib|DatalinksLocked=T|DatabaseDatalinksLocked=T
|RECORD=46|OwnerIndex=1225
|RECORD=48|OwnerIndex=1225
|RECORD=17|IndexInSheet=81|OwnerPartId=-1|ShowNetName=T|Location.X=1525|Location.Y=985|Orientation=1|Color=128|FontID=1|Text=P5V_PVDD
|RECORD=17|IndexInSheet=82|OwnerPartId=-1|ShowNetName=T|Location.X=1460|Location.Y=985|Orientation=1|Color=128|FontID=1|Text=P5V_VDD
|RECORD=17|IndexInSheet=83|OwnerPartId=-1|ShowNetName=T|Location.X=1225|Location.Y=990|Orientation=1|Color=128|FontID=1|Text=P5V_VDD
|RECORD=1|LibReference=RES|ComponentDescription=1R21 0.063W 1% 0402 (1005 Metric)  SMD|PartCount=2|DisplayModeCount=2|IndexInSheet=84|OwnerPartId=-1|Location.X=1260|Location.Y=975|CurrentPartId=1|SourceLibraryName=Altium Content Vault|TargetFileName=*|AreaColor=11599871|Color=128|PartIDLocked=F|DesignItemId=CMP-1011-00180-1|AllPinCount=2
|RECORD=2|OwnerIndex=1231|OwnerPartId=1|OwnerPartDisplayMode=1|FormalType=1|Electrical=4|PinConglomerate=32|PinLength=10|Location.X=1280|Location.Y=965|Name=2|Designator=2|PinPropagationDelay=0.000000E+000
|RECORD=2|OwnerIndex=1231|OwnerPartId=1|OwnerPartDisplayMode=1|FormalType=1|Electrical=4|PinConglomerate=34|PinLength=10|Location.X=1260|Location.Y=965|Name=1|Designator=1|PinPropagationDelay=0.000000E+000
|RECORD=14|OwnerIndex=1231|IsNotAccesible=T|IndexInSheet=2|OwnerPartId=1|OwnerPartDisplayMode=1|Location.X=1260|Location.Y=961|Corner.X=1280|Corner.Y=969|LineWidth=1|Color=16711680|AreaColor=11599871
|RECORD=2|OwnerIndex=1231|OwnerPartId=1|FormalType=1|Electrical=4|PinConglomerate=32|PinLength=10|Location.X=1280|Location.Y=965|Name=2|Designator=2|PinPropagationDelay=0.000000E+000
|RECORD=2|OwnerIndex=1231|OwnerPartId=1|FormalType=1|Electrical=4|PinConglomerate=34|PinLength=10|Location.X=1260|Location.Y=965|Name=1|Designator=1|PinPropagationDelay=0.000000E+000
|RECORD=6|OwnerIndex=1231|IsNotAccesible=T|IndexInSheet=5|OwnerPartId=1|LineWidth=1|Color=16711680|LocationCount=10|X1=1280|Y1=965|X2=1276|Y2=965|X3=1275|Y3=963|X4=1273|Y4=967|X5=1271|Y5=963|X6=1269|Y6=967|X7=1267|Y7=963|X8=1265|Y8=967|X9=1264|Y9=965|X10=1260|Y10=965
|RECORD=41|OwnerIndex=1231|IndexInSheet=6|OwnerPartId=-1|Location.X=1248|Location.Y=978|Color=8388608|FontID=1|IsHidden=T|Text=1 %|Name=Tolerance
|RECORD=41|OwnerIndex=1231|IndexInSheet=7|OwnerPartId=-1|Location.X=1248|Location.Y=978|Color=8388608|FontID=1|IsHidden=T|Text=0402|Name=Case-EIA
|RECORD=41|OwnerIndex=1231|IndexInSheet=8|OwnerPartId=-1|Location.X=1248|Location.Y=978|Color=8388608|FontID=1|IsHidden=T|Text=1.21 Ohm|Name=Value
|RECORD=41|OwnerIndex=1231|IndexInSheet=9|OwnerPartId=-1|Location.X=1248|Location.Y=978|Color=8388608|FontID=1|IsHidden=T|Text=1005|Name=Case-Metric
|RECORD=41|OwnerIndex=1231|IndexInSheet=10|OwnerPartId=-1|Location.X=1248|Location.Y=978|Color=8388608|FontID=1|IsHidden=T|Text=0.063 W|Name=Power
|RECORD=41|OwnerIndex=1231|IndexInSheet=11|OwnerPartId=-1|Location.X=1248|Location.Y=978|Color=8388608|FontID=1|IsHidden=T|Text=SMT|Name=Technology
|RECORD=34|OwnerIndex=1231|IndexInSheet=-1|OwnerPartId=-1|Location.X=1235|Location.Y=965|Color=8388608|FontID=1|Text=R5|Name=Designator|ReadOnlyState=1
|RECORD=41|OwnerIndex=1231|IndexInSheet=-1|OwnerPartId=-1|Location.X=1275|Location.Y=965|Color=8388608|FontID=1|Text=1.21_1%_0402|Name=Comment
|RECORD=44|OwnerIndex=1231
|RECORD=45|OwnerIndex=1250|IndexInSheet=-1|Description=Chip Resistor, Body 1.0x0.5mm, IPC Medium Density|UseComponentLibrary=T|ModelName=RESC0402(1005)_N|ModelType=PCBLIB|DatafileCount=1|ModelDatafileEntity0=RESC0402(1005)_N|ModelDatafileKind0=PCBLib|IsCurrent=T|DatalinksLocked=T|DatabaseDatalinksLocked=T
|RECORD=46|OwnerIndex=1251
|RECORD=48|OwnerIndex=1251
|RECORD=41|OwnerIndex=1253|IndexInSheet=-1|OwnerPartId=-1|Color=8388608|FontID=1|IsHidden=T|Text=2D|Name=Available Preview Images
|RECORD=45|OwnerIndex=1250|IndexInSheet=-1|Description=Chip Resistor, Body 1.0x0.5mm, IPC Low Density|UseComponentLibrary=T|ModelName=RESC0402(1005)_M|ModelType=PCBLIB|DatafileCount=1|ModelDatafileEntity0=RESC0402(1005)_M|ModelDatafileKind0=PCBLib|DatalinksLocked=T|DatabaseDatalinksLocked=T
|RECORD=46|OwnerIndex=1255
|RECORD=48|OwnerIndex=1255
|RECORD=41|OwnerIndex=1257|IndexInSheet=-1|OwnerPartId=-1|Color=8388608|FontID=1|IsHidden=T|Text=2D|Name=Available Preview Images
|RECORD=45|OwnerIndex=1250|IndexInSheet=-1|Description=Chip Resistor, Body 1.0x0.5mm, IPC High Density|UseComponentLibrary=T|ModelName=RESC0402(1005)_L|ModelType=PCBLIB|DatafileCount=1|ModelDatafileEntity0=RESC0402(1005)_L|ModelDatafileKind0=PCBLib|DatalinksLocked=T|DatabaseDatalinksLocked=T
|RECORD=46|OwnerIndex=1259
|RECORD=48|OwnerIndex=1259
|RECORD=41|OwnerIndex=1261|IndexInSheet=-1|OwnerPartId=-1|Color=8388608|FontID=1|IsHidden=T|Text=2D|Name=Available Preview Images
|RECORD=17|IndexInSheet=85|OwnerPartId=-1|ShowNetName=T|Location.X=1340|Location.Y=990|Orientation=1|Color=128|FontID=1|Text=P5V_PVDD
|RECORD=17|IndexInSheet=86|OwnerPartId=-1|ShowNetName=T|Location.X=1400|Location.Y=900|Orientation=1|Color=128|FontID=1|Text=P5V_VDD
|RECORD=17|IndexInSheet=87|OwnerPartId=-1|ShowNetName=T|Location.X=1465|Location.Y=900|Orientation=1|Color=128|FontID=1|Text=P5V_PVDD
|RECORD=1|LibReference=b4654b650e69147ec39a6b967a45e02|ComponentDescription=Multilayer Ceramic Capacitors 2.2µF ±10% 16V X5R SMD 0402|PartCount=2|DisplayModeCount=1|IndexInSheet=88|OwnerPartId=-1|Location.X=1465|Location.Y=875|CurrentPartId=1|LibraryPath=*|SourceLibraryName=Altium Content Vault|TargetFileName=*|AreaColor=11599871|Color=128|PartIDLocked=T|DesignItemId=CMP-2000-05998-2|AllPinCount=2
|RECORD=2|OwnerIndex=1266|OwnerPartId=1|Electrical=4|PinConglomerate=49|PinLength=7|Location.X=1465|Location.Y=868|Name=1|Designator=1|PinPropagationDelay=0.000000E+000
|RECORD=2|OwnerIndex=1266|OwnerPartId=1|Electrical=4|PinConglomerate=51|PinLength=6|Location.X=1465|Location.Y=861|Name=2|Designator=2|PinPropagationDelay=0.000000E+000
|RECORD=13|OwnerIndex=1266|IsNotAccesible=T|IndexInSheet=2|OwnerPartId=1|Location.X=1475|Location.Y=868|Corner.X=1455|Corner.Y=868|LineWidth=1|Color=16711680
|RECORD=13|OwnerIndex=1266|IsNotAccesible=T|IndexInSheet=3|OwnerPartId=1|Location.X=1475|Location.Y=862|Corner.X=1455|Corner.Y=862|LineWidth=1|Color=16711680
|RECORD=13|OwnerIndex=1266|IsNotAccesible=T|IndexInSheet=4|OwnerPartId=1|Location.X=1465|Location.Y=868|Corner.X=1465|Corner.Y=871|LineWidth=1|Color=16711680
|RECORD=13|OwnerIndex=1266|IsNotAccesible=T|IndexInSheet=5|OwnerPartId=1|Location.X=1465|Location.Y=861|Corner.X=1465|Corner.Y=860|LineWidth=1|Color=16711680
|RECORD=41|OwnerIndex=1266|IndexInSheet=6|OwnerPartId=-1|Location.X=1454|Location.Y=877|Color=8388608|FontID=1|IsHidden=T|Text=No SVHC|Name=REACH SVHC
|RECORD=41|OwnerIndex=1266|IndexInSheet=7|OwnerPartId=-1|Location.X=1454|Location.Y=877|Color=8388608|FontID=1|IsHidden=T|Text=C|Name=Series
|RECORD=41|OwnerIndex=1266|IndexInSheet=8|OwnerPartId=-1|Location.X=1454|Location.Y=877|Color=8388608|FontID=1|IsHidden=T|Text=SMD/SMT|Name=Termination
|RECORD=41|OwnerIndex=1266|IndexInSheet=9|OwnerPartId=-1|Location.X=1454|Location.Y=877|Color=8388608|FontID=1|IsHidden=T|Text=0402|Name=Case Code (Imperial)
|RECORD=41|OwnerIndex=1266|IndexInSheet=10|OwnerPartId=-1|Location.X=1454|Location.Y=877|Color=8388608|FontID=1|IsHidden=T|Text=0.5mm|Name=Depth
|RECORD=41|OwnerIndex=1266|IndexInSheet=11|OwnerPartId=-1|Location.X=1454|Location.Y=877|Color=8388608|FontID=1|IsHidden=T|Text=Surface Mount|Name=Mount
|RECORD=41|OwnerIndex=1266|IndexInSheet=12|OwnerPartId=-1|Location.X=1454|Location.Y=877|Color=8388608|FontID=1|IsHidden=T|Text=0.02inch|Name=Width
|RECORD=41|OwnerIndex=1266|IndexInSheet=13|OwnerPartId=-1|Location.X=1454|Location.Y=877|Color=8388608|FontID=1|IsHidden=T|Text=1|Name=Package Quantity
|RECORD=41|OwnerIndex=1266|IndexInSheet=14|OwnerPartId=-1|Location.X=1454|Location.Y=877|Color=8388608|FontID=1|IsHidden=T|Text=Ceramic|Name=Dielectric Material
|RECORD=41|OwnerIndex=1266|IndexInSheet=15|OwnerPartId=-1|Location.X=1454|Location.Y=877|Color=8388608|FontID=1|IsHidden=T|Text=1mm|Name=Length
|RECORD=41|OwnerIndex=1266|IndexInSheet=16|OwnerPartId=-1|Location.X=1454|Location.Y=877|Color=8388608|FontID=1|IsHidden=T|Text=Tape and Reel|Name=Packaging
|RECORD=41|OwnerIndex=1266|IndexInSheet=17|OwnerPartId=-1|Location.X=1454|Location.Y=877|Color=8388608|FontID=1|IsHidden=T|Text=1005|Name=Case Code (Metric)
|RECORD=41|OwnerIndex=1266|IndexInSheet=18|OwnerPartId=-1|Location.X=1454|Location.Y=877|Color=8388608|FontID=1|IsHidden=T|Text=Yes|Name=RoHS Compliant
|RECORD=41|OwnerIndex=1266|IndexInSheet=19|OwnerPartId=-1|Location.X=1454|Location.Y=877|Color=8388608|FontID=1|IsHidden=T|Text=X5R|Name=Dielectric
|RECORD=41|OwnerIndex=1266|IndexInSheet=20|OwnerPartId=-1|Location.X=1454|Location.Y=877|Color=8388608|FontID=1|IsHidden=T|Text=85°C|Name=Max Operating Temperature
|RECORD=41|OwnerIndex=1266|IndexInSheet=21|OwnerPartId=-1|Location.X=1454|Location.Y=877|Color=8388608|FontID=1|IsHidden=T|Text=Lead Free|Name=Lead Free
|RECORD=41|OwnerIndex=1266|IndexInSheet=22|OwnerPartId=-1|Location.X=1454|Location.Y=877|Color=8388608|FontID=1|IsHidden=T|Text=2.3E-05oz|Name=Weight
|RECORD=41|OwnerIndex=1266|IndexInSheet=23|OwnerPartId=-1|Location.X=1454|Location.Y=877|Color=8388608|FontID=1|IsHidden=T|Text=0.022inch|Name=Thickness
|RECORD=41|OwnerIndex=1266|IndexInSheet=24|OwnerPartId=-1|Location.X=1454|Location.Y=877|Color=8388608|FontID=1|IsHidden=T|Text=2.2uF|Name=Capacitance
|RECORD=41|OwnerIndex=1266|IndexInSheet=25|OwnerPartId=-1|Location.X=1454|Location.Y=877|Color=8388608|FontID=1|IsHidden=T|Text=16V|Name=Voltage Rating (DC)
|RECORD=41|OwnerIndex=1266|IndexInSheet=26|OwnerPartId=-1|Location.X=1454|Location.Y=877|Color=8388608|FontID=1|IsHidden=T|Text=10%|Name=Tolerance
|RECORD=41|OwnerIndex=1266|IndexInSheet=27|OwnerPartId=-1|Location.X=1454|Location.Y=877|Color=8388608|FontID=1|IsHidden=T|Text=16V|Name=Voltage Rating
|RECORD=41|OwnerIndex=1266|IndexInSheet=28|OwnerPartId=-1|Location.X=1454|Location.Y=877|Color=8388608|FontID=1|IsHidden=T|Text=Ceramic|Name=Resistor Type
|RECORD=41|OwnerIndex=1266|IndexInSheet=29|OwnerPartId=-1|Location.X=1454|Location.Y=877|Color=8388608|FontID=1|IsHidden=T|Text=0.5mm|Name=Height
|RECORD=41|OwnerIndex=1266|IndexInSheet=30|OwnerPartId=-1|Location.X=1454|Location.Y=877|Color=8388608|FontID=1|IsHidden=T|Text=0402|Name=Case/Package
|RECORD=41|OwnerIndex=1266|IndexInSheet=31|OwnerPartId=-1|Location.X=1454|Location.Y=877|Color=8388608|FontID=1|IsHidden=T|Text=-55°C|Name=Min Operating Temperature
|RECORD=34|OwnerIndex=1266|IndexInSheet=-1|OwnerPartId=-1|Location.X=1455|Location.Y=855|Orientation=1|Color=8388608|FontID=2|Text=C5|Name=Designator|ReadOnlyState=1
|RECORD=41|OwnerIndex=1266|IndexInSheet=-1|OwnerPartId=1|Location.X=1485|Location.Y=830|Orientation=1|Color=8388608|FontID=2|Text=2.2uF_16V_0402|Name=Comment
|RECORD=44|OwnerIndex=1266
|RECORD=45|OwnerIndex=1303|IndexInSheet=-1|UseComponentLibrary=T|ModelName=FP-C1005-050-0_05-IPC_A|ModelType=PCBLIB|DatafileCount=1|ModelDatafileEntity0=FP-C1005-050-0_05-IPC_A|ModelDatafileKind0=PCBLib|IsCurrent=T|DatalinksLocked=T|DatabaseDatalinksLocked=T
|RECORD=46|OwnerIndex=1304
|RECORD=48|OwnerIndex=1304
|RECORD=45|OwnerIndex=1303|IndexInSheet=-1|UseComponentLibrary=T|ModelName=FP-C1005-050-0_05-MFG|ModelType=PCBLIB|DatafileCount=1|ModelDatafileEntity0=FP-C1005-050-0_05-MFG|ModelDatafileKind0=PCBLib|DatalinksLocked=T|DatabaseDatalinksLocked=T
|RECORD=46|OwnerIndex=1307
|RECORD=48|OwnerIndex=1307
|RECORD=45|OwnerIndex=1303|IndexInSheet=-1|UseComponentLibrary=T|ModelName=FP-C1005-050-0_05-IPC_C|ModelType=PCBLIB|DatafileCount=1|ModelDatafileEntity0=FP-C1005-050-0_05-IPC_C|ModelDatafileKind0=PCBLib|DatalinksLocked=T|DatabaseDatalinksLocked=T
|RECORD=46|OwnerIndex=1310
|RECORD=48|OwnerIndex=1310
|RECORD=45|OwnerIndex=1303|IndexInSheet=-1|UseComponentLibrary=T|ModelName=FP-C1005-050-0_05-IPC_B|ModelType=PCBLIB|DatafileCount=1|ModelDatafileEntity0=FP-C1005-050-0_05-IPC_B|ModelDatafileKind0=PCBLib|DatalinksLocked=T|DatabaseDatalinksLocked=T
|RECORD=46|OwnerIndex=1313
|RECORD=48|OwnerIndex=1313
|RECORD=17|IndexInSheet=89|OwnerPartId=-1|Style=4|ShowNetName=T|Location.X=1465|Location.Y=835|Orientation=3|Color=128|FontID=1|Text=GND
|RECORD=1|LibReference=b4654b650e69147ec39a6b967a45e02|ComponentDescription=Cap Ceramic 1nF 50V C0G ±5% SMD 0402 +125°C Paper T/R|PartCount=2|DisplayModeCount=1|IndexInSheet=90|OwnerPartId=-1|Location.X=1095|Location.Y=835|CurrentPartId=1|LibraryPath=*|SourceLibraryName=Altium Content Vault|TargetFileName=*|AreaColor=11599871|Color=128|PartIDLocked=T|DesignItemId=CMP-13271-002012-1|AllPinCount=2|ComponentKindVersion2=5
|RECORD=2|OwnerIndex=1317|OwnerPartId=1|Electrical=4|PinConglomerate=49|PinLength=7|Location.X=1095|Location.Y=828|Name=1|Designator=1|PinPropagationDelay=0.000000E+000
|RECORD=2|OwnerIndex=1317|OwnerPartId=1|Electrical=4|PinConglomerate=51|PinLength=6|Location.X=1095|Location.Y=821|Name=2|Designator=2|PinPropagationDelay=0.000000E+000
|RECORD=13|OwnerIndex=1317|IsNotAccesible=T|IndexInSheet=2|OwnerPartId=1|Location.X=1105|Location.Y=828|Corner.X=1085|Corner.Y=828|LineWidth=1|Color=16711680
|RECORD=13|OwnerIndex=1317|IsNotAccesible=T|IndexInSheet=3|OwnerPartId=1|Location.X=1105|Location.Y=822|Corner.X=1085|Corner.Y=822|LineWidth=1|Color=16711680
|RECORD=13|OwnerIndex=1317|IsNotAccesible=T|IndexInSheet=4|OwnerPartId=1|Location.X=1095|Location.Y=828|Corner.X=1095|Corner.Y=831|LineWidth=1|Color=16711680
|RECORD=13|OwnerIndex=1317|IsNotAccesible=T|IndexInSheet=5|OwnerPartId=1|Location.X=1095|Location.Y=821|Corner.X=1095|Corner.Y=820|LineWidth=1|Color=16711680
|RECORD=41|OwnerIndex=1317|IndexInSheet=6|OwnerPartId=-1|Location.X=1084|Location.Y=837|Color=8388608|FontID=1|IsHidden=T|Text=0402|Name=Case Code (Imperial)
|RECORD=41|OwnerIndex=1317|IndexInSheet=7|OwnerPartId=-1|Location.X=1084|Location.Y=837|Color=8388608|FontID=1|IsHidden=T|Text=1|Name=Package Quantity
|RECORD=41|OwnerIndex=1317|IndexInSheet=8|OwnerPartId=-1|Location.X=1084|Location.Y=837|Color=8388608|FontID=1|IsHidden=T|Text=1005|Name=Case Code (Metric)
|RECORD=41|OwnerIndex=1317|IndexInSheet=9|OwnerPartId=-1|Location.X=1084|Location.Y=837|Color=8388608|FontID=1|IsHidden=T|Text=1nF|Name=Capacitance
|RECORD=41|OwnerIndex=1317|IndexInSheet=10|OwnerPartId=-1|Location.X=1084|Location.Y=837|Color=8388608|FontID=1|IsHidden=T|Text=50V|Name=Voltage Rating (DC)
|RECORD=41|OwnerIndex=1317|IndexInSheet=11|OwnerPartId=-1|Location.X=1084|Location.Y=837|Color=8388608|FontID=1|IsHidden=T|Text=Tape and Reel|Name=Packaging
|RECORD=41|OwnerIndex=1317|IndexInSheet=12|OwnerPartId=-1|Location.X=1084|Location.Y=837|Color=8388608|FontID=1|IsHidden=T|Text=0.022inch|Name=Thickness
|RECORD=41|OwnerIndex=1317|IndexInSheet=13|OwnerPartId=-1|Location.X=1084|Location.Y=837|Color=8388608|FontID=1|IsHidden=T|Text=0.5mm|Name=Height
|RECORD=41|OwnerIndex=1317|IndexInSheet=14|OwnerPartId=-1|Location.X=1084|Location.Y=837|Color=8388608|FontID=1|IsHidden=T|Text=50V|Name=Voltage Rating
|RECORD=41|OwnerIndex=1317|IndexInSheet=15|OwnerPartId=-1|Location.X=1084|Location.Y=837|Color=8388608|FontID=1|IsHidden=T|Text=C0G|Name=Dielectric
|RECORD=41|OwnerIndex=1317|IndexInSheet=16|OwnerPartId=-1|Location.X=1084|Location.Y=837|Color=8388608|FontID=1|IsHidden=T|Text=No|Name=Radiation Hardening
|RECORD=41|OwnerIndex=1317|IndexInSheet=17|OwnerPartId=-1|Location.X=1084|Location.Y=837|Color=8388608|FontID=1|IsHidden=T|Text=0.5mm|Name=Depth
|RECORD=41|OwnerIndex=1317|IndexInSheet=18|OwnerPartId=-1|Location.X=1084|Location.Y=837|Color=8388608|FontID=1|IsHidden=T|Text=0.02inch|Name=Width
|RECORD=41|OwnerIndex=1317|IndexInSheet=19|OwnerPartId=-1|Location.X=1084|Location.Y=837|Color=8388608|FontID=1|IsHidden=T|Text=0402|Name=Case/Package
|RECORD=41|OwnerIndex=1317|IndexInSheet=20|OwnerPartId=-1|Location.X=1084|Location.Y=837|Color=8388608|FontID=1|IsHidden=T|Text=Surface Mount|Name=Mount
|RECORD=41|OwnerIndex=1317|IndexInSheet=21|OwnerPartId=-1|Location.X=1084|Location.Y=837|Color=8388608|FontID=1|IsHidden=T|Text=1mm|Name=Length
|RECORD=41|OwnerIndex=1317|IndexInSheet=22|OwnerPartId=-1|Location.X=1084|Location.Y=837|Color=8388608|FontID=1|IsHidden=T|Text=Ceramic|Name=Material
|RECORD=41|OwnerIndex=1317|IndexInSheet=23|OwnerPartId=-1|Location.X=1084|Location.Y=837|Color=8388608|FontID=1|IsHidden=T|Text=125°C|Name=Max Operating Temperature
|RECORD=41|OwnerIndex=1317|IndexInSheet=24|OwnerPartId=-1|Location.X=1084|Location.Y=837|Color=8388608|FontID=1|IsHidden=T|Text=5%|Name=Tolerance
|RECORD=41|OwnerIndex=1317|IndexInSheet=25|OwnerPartId=-1|Location.X=1084|Location.Y=837|Color=8388608|FontID=1|IsHidden=T|Text=50V|Name=Voltage
|RECORD=41|OwnerIndex=1317|IndexInSheet=26|OwnerPartId=-1|Location.X=1084|Location.Y=837|Color=8388608|FontID=1|IsHidden=T|Text=-55°C|Name=Min Operating Temperature
|RECORD=41|OwnerIndex=1317|IndexInSheet=27|OwnerPartId=-1|Location.X=1084|Location.Y=837|Color=8388608|FontID=1|IsHidden=T|Text=300ppm/°C|Name=Temperature Coefficient
|RECORD=41|OwnerIndex=1317|IndexInSheet=28|OwnerPartId=-1|Location.X=1084|Location.Y=837|Color=8388608|FontID=1|IsHidden=T|Text=Lead Free|Name=Lead Free
|RECORD=34|OwnerIndex=1317|IndexInSheet=-1|OwnerPartId=-1|Location.X=1106|Location.Y=822|Color=8388608|FontID=1|Text=C7|Name=Designator|ReadOnlyState=1
|RECORD=41|OwnerIndex=1317|IndexInSheet=-1|OwnerPartId=1|Location.X=1106|Location.Y=812|Color=8388608|FontID=1|Text=DNI_1nF_50V_0402|Name=Comment
|RECORD=44|OwnerIndex=1317
|RECORD=45|OwnerIndex=1351|IndexInSheet=-1|UseComponentLibrary=T|ModelName=FP-CL180-IPC_C|ModelType=PCBLIB|DatafileCount=1|ModelDatafileEntity0=FP-CL180-IPC_C|ModelDatafileKind0=PCBLib|IsCurrent=T|DatalinksLocked=T|DatabaseDatalinksLocked=T
|RECORD=46|OwnerIndex=1352
|RECORD=48|OwnerIndex=1352
|RECORD=45|OwnerIndex=1351|IndexInSheet=-1|UseComponentLibrary=T|ModelName=FP-CL180-IPC_B|ModelType=PCBLIB|DatafileCount=1|ModelDatafileEntity0=FP-CL180-IPC_B|ModelDatafileKind0=PCBLib|DatalinksLocked=T|DatabaseDatalinksLocked=T
|RECORD=46|OwnerIndex=1355
|RECORD=48|OwnerIndex=1355
|RECORD=45|OwnerIndex=1351|IndexInSheet=-1|UseComponentLibrary=T|ModelName=FP-CL180-IPC_A|ModelType=PCBLIB|DatafileCount=1|ModelDatafileEntity0=FP-CL180-IPC_A|ModelDatafileKind0=PCBLib|DatalinksLocked=T|DatabaseDatalinksLocked=T
|RECORD=46|OwnerIndex=1358
|RECORD=48|OwnerIndex=1358
|RECORD=1|LibReference=RES|PartCount=2|DisplayModeCount=2|IndexInSheet=91|OwnerPartId=-1|Location.X=1085|Location.Y=855|Orientation=1|CurrentPartId=1|SourceLibraryName=Altium Content Vault|TargetFileName=*|AreaColor=11599871|Color=128|PartIDLocked=F|DesignItemId=CMP-2002-04265-1|AllPinCount=2
|RECORD=2|OwnerIndex=1361|OwnerPartId=1|OwnerPartDisplayMode=1|FormalType=1|Electrical=4|PinConglomerate=33|PinLength=10|Location.X=1095|Location.Y=875|Name=2|Designator=2|PinPropagationDelay=0.000000E+000
|RECORD=2|OwnerIndex=1361|OwnerPartId=1|OwnerPartDisplayMode=1|FormalType=1|Electrical=4|PinConglomerate=35|PinLength=10|Location.X=1095|Location.Y=855|Name=1|Designator=1|PinPropagationDelay=0.000000E+000
|RECORD=14|OwnerIndex=1361|IsNotAccesible=T|IndexInSheet=2|OwnerPartId=1|OwnerPartDisplayMode=1|Location.X=1091|Location.Y=855|Corner.X=1099|Corner.Y=875|LineWidth=1|Color=16711680|AreaColor=11599871
|RECORD=2|OwnerIndex=1361|OwnerPartId=1|FormalType=1|Electrical=4|PinConglomerate=33|PinLength=10|Location.X=1095|Location.Y=875|Name=2|Designator=2|PinPropagationDelay=0.000000E+000
|RECORD=2|OwnerIndex=1361|OwnerPartId=1|FormalType=1|Electrical=4|PinConglomerate=35|PinLength=10|Location.X=1095|Location.Y=855|Name=1|Designator=1|PinPropagationDelay=0.000000E+000
|RECORD=6|OwnerIndex=1361|IsNotAccesible=T|IndexInSheet=5|OwnerPartId=1|LineWidth=1|Color=16711680|LocationCount=10|X1=1095|Y1=875|X2=1095|Y2=871|X3=1097|Y3=870|X4=1093|Y4=868|X5=1097|Y5=866|X6=1093|Y6=864|X7=1097|Y7=862|X8=1093|Y8=860|X9=1095|Y9=859|X10=1095|Y10=855
|RECORD=41|OwnerIndex=1361|IndexInSheet=6|OwnerPartId=-1|Location.X=1092|Location.Y=887|Color=8388608|FontID=1|IsHidden=T|Text=RK73H1ETTP1R21F|Name=Part Number
|RECORD=41|OwnerIndex=1361|IndexInSheet=7|OwnerPartId=-1|Location.X=1092|Location.Y=887|Color=8388608|FontID=1|IsHidden=T|Text=KOA Speer|Name=Manufacturer
|RECORD=34|OwnerIndex=1361|IndexInSheet=-1|OwnerPartId=-1|Location.X=1098|Location.Y=866|Color=8388608|FontID=1|Text=R9|Name=Designator|ReadOnlyState=1
|RECORD=41|OwnerIndex=1361|IndexInSheet=-1|OwnerPartId=-1|Location.X=1098|Location.Y=856|Color=8388608|FontID=1|Text=1.21_1%_0402|Name=Comment
|RECORD=44|OwnerIndex=1361
|RECORD=45|OwnerIndex=1376|IndexInSheet=-1|Description=Chip Resistor, 2-Leads, Body 1.00x0.50mm, IPC High Density|UseComponentLibrary=T|ModelName=RESC1005X40X25LL10T10|ModelType=PCBLIB|DatafileCount=1|ModelDatafileEntity0=RESC1005X40X25LL10T10|ModelDatafileKind0=PCBLib|IsCurrent=T|DatalinksLocked=T|DatabaseDatalinksLocked=T
|RECORD=46|OwnerIndex=1377
|RECORD=48|OwnerIndex=1377
|RECORD=41|OwnerIndex=1379|IndexInSheet=-1|OwnerPartId=-1|Color=8388608|FontID=1|IsHidden=T|Text=2D|Name=Available Preview Images
|RECORD=45|OwnerIndex=1376|IndexInSheet=-1|Description=Chip Resistor, 2-Leads, Body 1.00x0.50mm, IPC Medium Density|UseComponentLibrary=T|ModelName=RESC1005X40X25NL10T10|ModelType=PCBLIB|DatafileCount=1|ModelDatafileEntity0=RESC1005X40X25NL10T10|ModelDatafileKind0=PCBLib|DatalinksLocked=T|DatabaseDatalinksLocked=T
|RECORD=46|OwnerIndex=1381
|RECORD=48|OwnerIndex=1381
|RECORD=41|OwnerIndex=1383|IndexInSheet=-1|OwnerPartId=-1|Color=8388608|FontID=1|IsHidden=T|Text=2D|Name=Available Preview Images
|RECORD=45|OwnerIndex=1376|IndexInSheet=-1|Description=Chip Resistor, 2-Leads, Body 1.00x0.50mm, IPC Low Density|UseComponentLibrary=T|ModelName=RESC1005X40X25ML10T10|ModelType=PCBLIB|DatafileCount=1|ModelDatafileEntity0=RESC1005X40X25ML10T10|ModelDatafileKind0=PCBLib|DatalinksLocked=T|DatabaseDatalinksLocked=T
|RECORD=46|OwnerIndex=1385
|RECORD=48|OwnerIndex=1385
|RECORD=41|OwnerIndex=1387|IndexInSheet=-1|OwnerPartId=-1|Color=8388608|FontID=1|IsHidden=T|Text=2D|Name=Available Preview Images
|RECORD=17|IndexInSheet=92|OwnerPartId=-1|Style=4|ShowNetName=T|Location.X=1095|Location.Y=795|Orientation=3|Color=128|FontID=1|Text=GND
|RECORD=1|LibReference=02cd4be3c70576c341d710602a673aa|ComponentDescription=Chip Multilayer Ceramic Capacitors for General Purpose, 1206, 4.7uF, X7R, 15%, 10%, 50V|PartCount=2|DisplayModeCount=1|IndexInSheet=93|OwnerPartId=-1|Location.X=740|Location.Y=810|CurrentPartId=1|LibraryPath=*|SourceLibraryName=Altium Content Vault|TargetFileName=*|AreaColor=11599871|Color=128|PartIDLocked=T|DesignItemId=CMP-1037-04923-3|AllPinCount=2
|RECORD=2|OwnerIndex=1390|OwnerPartId=1|Electrical=4|PinConglomerate=49|PinLength=7|Location.X=740|Location.Y=803|Name=1|Designator=1|PinPropagationDelay=0.000000E+000
|RECORD=2|OwnerIndex=1390|OwnerPartId=1|Electrical=4|PinConglomerate=51|PinLength=6|Location.X=740|Location.Y=796|Name=2|Designator=2|PinPropagationDelay=0.000000E+000
|RECORD=13|OwnerIndex=1390|IsNotAccesible=T|IndexInSheet=2|OwnerPartId=1|Location.X=750|Location.Y=803|Corner.X=730|Corner.Y=803|LineWidth=1|Color=16711680
|RECORD=13|OwnerIndex=1390|IsNotAccesible=T|IndexInSheet=3|OwnerPartId=1|Location.X=750|Location.Y=797|Corner.X=730|Corner.Y=797|LineWidth=1|Color=16711680
|RECORD=13|OwnerIndex=1390|IsNotAccesible=T|IndexInSheet=4|OwnerPartId=1|Location.X=740|Location.Y=803|Corner.X=740|Corner.Y=806|LineWidth=1|Color=16711680
|RECORD=13|OwnerIndex=1390|IsNotAccesible=T|IndexInSheet=5|OwnerPartId=1|Location.X=740|Location.Y=796|Corner.X=740|Corner.Y=795|LineWidth=1|Color=16711680
|RECORD=41|OwnerIndex=1390|IndexInSheet=6|OwnerPartId=-1|Location.X=729|Location.Y=812|Color=8388608|FontID=1|IsHidden=T|Text=1.6mm|Name=Height
|RECORD=41|OwnerIndex=1390|IndexInSheet=7|OwnerPartId=-1|Location.X=729|Location.Y=812|Color=8388608|FontID=1|IsHidden=T|Text=50V|Name=Voltage
|RECORD=41|OwnerIndex=1390|IndexInSheet=8|OwnerPartId=-1|Location.X=729|Location.Y=812|Color=8388608|FontID=1|IsHidden=T|Text=4.7uF|Name=Capacitance
|RECORD=41|OwnerIndex=1390|IndexInSheet=9|OwnerPartId=-1|Location.X=729|Location.Y=812|Color=8388608|FontID=1|IsHidden=T|Text=Lead Free|Name=Lead Free
|RECORD=41|OwnerIndex=1390|IndexInSheet=10|OwnerPartId=-1|Location.X=729|Location.Y=812|Color=8388608|FontID=1|IsHidden=T|Text=125°C|Name=Max Operating Temperature
|RECORD=41|OwnerIndex=1390|IndexInSheet=11|OwnerPartId=-1|Location.X=729|Location.Y=812|Color=8388608|FontID=1|IsHidden=T|Text=Tape and Reel|Name=Packaging
|RECORD=41|OwnerIndex=1390|IndexInSheet=12|OwnerPartId=-1|Location.X=729|Location.Y=812|Color=8388608|FontID=1|IsHidden=T|Text=No SVHC|Name=REACH SVHC
|RECORD=41|OwnerIndex=1390|IndexInSheet=13|OwnerPartId=-1|Location.X=729|Location.Y=812|Color=8388608|FontID=1|IsHidden=T|Text=50V|Name=Voltage Rating
|RECORD=41|OwnerIndex=1390|IndexInSheet=14|OwnerPartId=-1|Location.X=729|Location.Y=812|Color=8388608|FontID=1|IsHidden=T|Text=Surface Mount|Name=Mount
|RECORD=41|OwnerIndex=1390|IndexInSheet=15|OwnerPartId=-1|Location.X=729|Location.Y=812|Color=8388608|FontID=1|IsHidden=T|Text=SMD/SMT|Name=Termination
|RECORD=41|OwnerIndex=1390|IndexInSheet=16|OwnerPartId=-1|Location.X=729|Location.Y=812|Color=8388608|FontID=1|IsHidden=T|Text=10%|Name=Tolerance
|RECORD=41|OwnerIndex=1390|IndexInSheet=17|OwnerPartId=-1|Location.X=729|Location.Y=812|Color=8388608|FontID=1|IsHidden=T|Text=1206|Name=Case/Package
|RECORD=41|OwnerIndex=1390|IndexInSheet=18|OwnerPartId=-1|Location.X=729|Location.Y=812|Color=8388608|FontID=1|IsHidden=T|Text=Ceramic|Name=Material
|RECORD=41|OwnerIndex=1390|IndexInSheet=19|OwnerPartId=-1|Location.X=729|Location.Y=812|Color=8388608|FontID=1|IsHidden=T|Text=1.6mm|Name=Depth
|RECORD=41|OwnerIndex=1390|IndexInSheet=20|OwnerPartId=-1|Location.X=729|Location.Y=812|Color=8388608|FontID=1|IsHidden=T|Text=3.2mm|Name=Length
|RECORD=41|OwnerIndex=1390|IndexInSheet=21|OwnerPartId=-1|Location.X=729|Location.Y=812|Color=8388608|FontID=1|IsHidden=T|Text=3216|Name=Case Code (Metric)
|RECORD=41|OwnerIndex=1390|IndexInSheet=22|OwnerPartId=-1|Location.X=729|Location.Y=812|Color=8388608|FontID=1|IsHidden=T|Text=50V|Name=Voltage Rating (DC)
|RECORD=41|OwnerIndex=1390|IndexInSheet=23|OwnerPartId=-1|Location.X=729|Location.Y=812|Color=8388608|FontID=1|IsHidden=T|Text=1206|Name=Case Code (Imperial)
|RECORD=41|OwnerIndex=1390|IndexInSheet=24|OwnerPartId=-1|Location.X=729|Location.Y=812|Color=8388608|FontID=1|IsHidden=T|Text=No|Name=Radiation Hardening
|RECORD=41|OwnerIndex=1390|IndexInSheet=25|OwnerPartId=-1|Location.X=729|Location.Y=812|Color=8388608|FontID=1|IsHidden=T|Text=0.063inch|Name=Width
|RECORD=41|OwnerIndex=1390|IndexInSheet=26|OwnerPartId=-1|Location.X=729|Location.Y=812|Color=8388608|FontID=1|IsHidden=T|Text=0.071inch|Name=Thickness
|RECORD=41|OwnerIndex=1390|IndexInSheet=27|OwnerPartId=-1|Location.X=729|Location.Y=812|Color=8388608|FontID=1|IsHidden=T|Text=2000|Name=Package Quantity
|RECORD=41|OwnerIndex=1390|IndexInSheet=28|OwnerPartId=-1|Location.X=729|Location.Y=812|Color=8388608|FontID=1|IsHidden=T|Text=-55°C|Name=Min Operating Temperature
|RECORD=41|OwnerIndex=1390|IndexInSheet=29|OwnerPartId=-1|Location.X=729|Location.Y=812|Color=8388608|FontID=1|IsHidden=T|Text=X7R|Name=Dielectric
|RECORD=34|OwnerIndex=1390|IndexInSheet=-1|OwnerPartId=-1|Location.X=730|Location.Y=790|Orientation=1|Color=8388608|FontID=2|Text=C11|Name=Designator|ReadOnlyState=1
|RECORD=41|OwnerIndex=1390|IndexInSheet=-1|OwnerPartId=1|Location.X=760|Location.Y=775|Orientation=1|Color=8388608|FontID=2|Text=4.7uF_50V_1206|Name=Comment
|RECORD=44|OwnerIndex=1390
|RECORD=45|OwnerIndex=1425|IndexInSheet=-1|UseComponentLibrary=T|ModelName=FP-GRM31C-0_2-e0_3_0_8-IPC_C|ModelType=PCBLIB|DatafileCount=1|ModelDatafileEntity0=FP-GRM31C-0_2-e0_3_0_8-IPC_C|ModelDatafileKind0=PCBLib|IsCurrent=T|DatalinksLocked=T|DatabaseDatalinksLocked=T
|RECORD=46|OwnerIndex=1426
|RECORD=48|OwnerIndex=1426
|RECORD=45|OwnerIndex=1425|IndexInSheet=-1|UseComponentLibrary=T|ModelName=FP-GRM31C-0_2-e0_3_0_8-IPC_B|ModelType=PCBLIB|DatafileCount=1|ModelDatafileEntity0=FP-GRM31C-0_2-e0_3_0_8-IPC_B|ModelDatafileKind0=PCBLib|DatalinksLocked=T|DatabaseDatalinksLocked=T
|RECORD=46|OwnerIndex=1429
|RECORD=48|OwnerIndex=1429
|RECORD=45|OwnerIndex=1425|IndexInSheet=-1|UseComponentLibrary=T|ModelName=FP-GRM31C-0_2-e0_3_0_8-IPC_A|ModelType=PCBLIB|DatafileCount=1|ModelDatafileEntity0=FP-GRM31C-0_2-e0_3_0_8-IPC_A|ModelDatafileKind0=PCBLib|DatalinksLocked=T|DatabaseDatalinksLocked=T
|RECORD=46|OwnerIndex=1432
|RECORD=48|OwnerIndex=1432
|RECORD=45|OwnerIndex=1425|IndexInSheet=-1|UseComponentLibrary=T|ModelName=FP-GRM31C-0_2-e0_3_0_8-MFG|ModelType=PCBLIB|DatafileCount=1|ModelDatafileEntity0=FP-GRM31C-0_2-e0_3_0_8-MFG|ModelDatafileKind0=PCBLib|DatalinksLocked=T|DatabaseDatalinksLocked=T
|RECORD=46|OwnerIndex=1435
|RECORD=48|OwnerIndex=1435
|RECORD=1|LibReference=02cd4be3c70576c341d710602a673aa|ComponentDescription=Chip Multilayer Ceramic Capacitors for General Purpose, 1206, 4.7uF, X7R, 15%, 10%, 50V|PartCount=2|DisplayModeCount=1|IndexInSheet=94|OwnerPartId=-1|Location.X=780|Location.Y=810|CurrentPartId=1|LibraryPath=*|SourceLibraryName=Altium Content Vault|TargetFileName=*|AreaColor=11599871|Color=128|PartIDLocked=T|DesignItemId=CMP-1037-04923-3|AllPinCount=2
|RECORD=2|OwnerIndex=1438|OwnerPartId=1|Electrical=4|PinConglomerate=49|PinLength=7|Location.X=780|Location.Y=803|Name=1|Designator=1|PinPropagationDelay=0.000000E+000
|RECORD=2|OwnerIndex=1438|OwnerPartId=1|Electrical=4|PinConglomerate=51|PinLength=6|Location.X=780|Location.Y=796|Name=2|Designator=2|PinPropagationDelay=0.000000E+000
|RECORD=13|OwnerIndex=1438|IsNotAccesible=T|IndexInSheet=2|OwnerPartId=1|Location.X=790|Location.Y=803|Corner.X=770|Corner.Y=803|LineWidth=1|Color=16711680
|RECORD=13|OwnerIndex=1438|IsNotAccesible=T|IndexInSheet=3|OwnerPartId=1|Location.X=790|Location.Y=797|Corner.X=770|Corner.Y=797|LineWidth=1|Color=16711680
|RECORD=13|OwnerIndex=1438|IsNotAccesible=T|IndexInSheet=4|OwnerPartId=1|Location.X=780|Location.Y=803|Corner.X=780|Corner.Y=806|LineWidth=1|Color=16711680
|RECORD=13|OwnerIndex=1438|IsNotAccesible=T|IndexInSheet=5|OwnerPartId=1|Location.X=780|Location.Y=796|Corner.X=780|Corner.Y=795|LineWidth=1|Color=16711680
|RECORD=41|OwnerIndex=1438|IndexInSheet=6|OwnerPartId=-1|Location.X=769|Location.Y=812|Color=8388608|FontID=1|IsHidden=T|Text=1.6mm|Name=Height
|RECORD=41|OwnerIndex=1438|IndexInSheet=7|OwnerPartId=-1|Location.X=769|Location.Y=812|Color=8388608|FontID=1|IsHidden=T|Text=50V|Name=Voltage
|RECORD=41|OwnerIndex=1438|IndexInSheet=8|OwnerPartId=-1|Location.X=769|Location.Y=812|Color=8388608|FontID=1|IsHidden=T|Text=4.7uF|Name=Capacitance
|RECORD=41|OwnerIndex=1438|IndexInSheet=9|OwnerPartId=-1|Location.X=769|Location.Y=812|Color=8388608|FontID=1|IsHidden=T|Text=Lead Free|Name=Lead Free
|RECORD=41|OwnerIndex=1438|IndexInSheet=10|OwnerPartId=-1|Location.X=769|Location.Y=812|Color=8388608|FontID=1|IsHidden=T|Text=125°C|Name=Max Operating Temperature
|RECORD=41|OwnerIndex=1438|IndexInSheet=11|OwnerPartId=-1|Location.X=769|Location.Y=812|Color=8388608|FontID=1|IsHidden=T|Text=Tape and Reel|Name=Packaging
|RECORD=41|OwnerIndex=1438|IndexInSheet=12|OwnerPartId=-1|Location.X=769|Location.Y=812|Color=8388608|FontID=1|IsHidden=T|Text=No SVHC|Name=REACH SVHC
|RECORD=41|OwnerIndex=1438|IndexInSheet=13|OwnerPartId=-1|Location.X=769|Location.Y=812|Color=8388608|FontID=1|IsHidden=T|Text=50V|Name=Voltage Rating
|RECORD=41|OwnerIndex=1438|IndexInSheet=14|OwnerPartId=-1|Location.X=769|Location.Y=812|Color=8388608|FontID=1|IsHidden=T|Text=Surface Mount|Name=Mount
|RECORD=41|OwnerIndex=1438|IndexInSheet=15|OwnerPartId=-1|Location.X=769|Location.Y=812|Color=8388608|FontID=1|IsHidden=T|Text=SMD/SMT|Name=Termination
|RECORD=41|OwnerIndex=1438|IndexInSheet=16|OwnerPartId=-1|Location.X=769|Location.Y=812|Color=8388608|FontID=1|IsHidden=T|Text=10%|Name=Tolerance
|RECORD=41|OwnerIndex=1438|IndexInSheet=17|OwnerPartId=-1|Location.X=769|Location.Y=812|Color=8388608|FontID=1|IsHidden=T|Text=1206|Name=Case/Package
|RECORD=41|OwnerIndex=1438|IndexInSheet=18|OwnerPartId=-1|Location.X=769|Location.Y=812|Color=8388608|FontID=1|IsHidden=T|Text=Ceramic|Name=Material
|RECORD=41|OwnerIndex=1438|IndexInSheet=19|OwnerPartId=-1|Location.X=769|Location.Y=812|Color=8388608|FontID=1|IsHidden=T|Text=1.6mm|Name=Depth
|RECORD=41|OwnerIndex=1438|IndexInSheet=20|OwnerPartId=-1|Location.X=769|Location.Y=812|Color=8388608|FontID=1|IsHidden=T|Text=3.2mm|Name=Length
|RECORD=41|OwnerIndex=1438|IndexInSheet=21|OwnerPartId=-1|Location.X=769|Location.Y=812|Color=8388608|FontID=1|IsHidden=T|Text=3216|Name=Case Code (Metric)
|RECORD=41|OwnerIndex=1438|IndexInSheet=22|OwnerPartId=-1|Location.X=769|Location.Y=812|Color=8388608|FontID=1|IsHidden=T|Text=50V|Name=Voltage Rating (DC)
|RECORD=41|OwnerIndex=1438|IndexInSheet=23|OwnerPartId=-1|Location.X=769|Location.Y=812|Color=8388608|FontID=1|IsHidden=T|Text=1206|Name=Case Code (Imperial)
|RECORD=41|OwnerIndex=1438|IndexInSheet=24|OwnerPartId=-1|Location.X=769|Location.Y=812|Color=8388608|FontID=1|IsHidden=T|Text=No|Name=Radiation Hardening
|RECORD=41|OwnerIndex=1438|IndexInSheet=25|OwnerPartId=-1|Location.X=769|Location.Y=812|Color=8388608|FontID=1|IsHidden=T|Text=0.063inch|Name=Width
|RECORD=41|OwnerIndex=1438|IndexInSheet=26|OwnerPartId=-1|Location.X=769|Location.Y=812|Color=8388608|FontID=1|IsHidden=T|Text=0.071inch|Name=Thickness
|RECORD=41|OwnerIndex=1438|IndexInSheet=27|OwnerPartId=-1|Location.X=769|Location.Y=812|Color=8388608|FontID=1|IsHidden=T|Text=2000|Name=Package Quantity
|RECORD=41|OwnerIndex=1438|IndexInSheet=28|OwnerPartId=-1|Location.X=769|Location.Y=812|Color=8388608|FontID=1|IsHidden=T|Text=-55°C|Name=Min Operating Temperature
|RECORD=41|OwnerIndex=1438|IndexInSheet=29|OwnerPartId=-1|Location.X=769|Location.Y=812|Color=8388608|FontID=1|IsHidden=T|Text=X7R|Name=Dielectric
|RECORD=34|OwnerIndex=1438|IndexInSheet=-1|OwnerPartId=-1|Location.X=770|Location.Y=790|Orientation=1|Color=8388608|FontID=2|Text=C12|Name=Designator|ReadOnlyState=1
|RECORD=41|OwnerIndex=1438|IndexInSheet=-1|OwnerPartId=1|Location.X=800|Location.Y=775|Orientation=1|Color=8388608|FontID=2|Text=4.7uF_50V_1206|Name=Comment
|RECORD=44|OwnerIndex=1438
|RECORD=45|OwnerIndex=1473|IndexInSheet=-1|UseComponentLibrary=T|ModelName=FP-GRM31C-0_2-e0_3_0_8-IPC_C|ModelType=PCBLIB|DatafileCount=1|ModelDatafileEntity0=FP-GRM31C-0_2-e0_3_0_8-IPC_C|ModelDatafileKind0=PCBLib|IsCurrent=T|DatalinksLocked=T|DatabaseDatalinksLocked=T
|RECORD=46|OwnerIndex=1474
|RECORD=48|OwnerIndex=1474
|RECORD=45|OwnerIndex=1473|IndexInSheet=-1|UseComponentLibrary=T|ModelName=FP-GRM31C-0_2-e0_3_0_8-IPC_B|ModelType=PCBLIB|DatafileCount=1|ModelDatafileEntity0=FP-GRM31C-0_2-e0_3_0_8-IPC_B|ModelDatafileKind0=PCBLib|DatalinksLocked=T|DatabaseDatalinksLocked=T
|RECORD=46|OwnerIndex=1477
|RECORD=48|OwnerIndex=1477
|RECORD=45|OwnerIndex=1473|IndexInSheet=-1|UseComponentLibrary=T|ModelName=FP-GRM31C-0_2-e0_3_0_8-IPC_A|ModelType=PCBLIB|DatafileCount=1|ModelDatafileEntity0=FP-GRM31C-0_2-e0_3_0_8-IPC_A|ModelDatafileKind0=PCBLib|DatalinksLocked=T|DatabaseDatalinksLocked=T
|RECORD=46|OwnerIndex=1480
|RECORD=48|OwnerIndex=1480
|RECORD=45|OwnerIndex=1473|IndexInSheet=-1|UseComponentLibrary=T|ModelName=FP-GRM31C-0_2-e0_3_0_8-MFG|ModelType=PCBLIB|DatafileCount=1|ModelDatafileEntity0=FP-GRM31C-0_2-e0_3_0_8-MFG|ModelDatafileKind0=PCBLib|DatalinksLocked=T|DatabaseDatalinksLocked=T
|RECORD=46|OwnerIndex=1483
|RECORD=48|OwnerIndex=1483
|RECORD=1|LibReference=a00bbbee19879c290e62620ae7e47b1|ComponentDescription=CAP TANT 100UF 10% 16V 2917|PartCount=2|DisplayModeCount=1|IndexInSheet=95|OwnerPartId=-1|Location.X=690|Location.Y=810|CurrentPartId=1|LibraryPath=*|SourceLibraryName=Altium Content Vault|TargetFileName=*|AreaColor=11599871|Color=128|PartIDLocked=T|DesignItemId=CMP-2000-07207-2|AllPinCount=2
|RECORD=2|OwnerIndex=1486|OwnerPartId=1|Electrical=4|PinConglomerate=51|PinLength=8|Location.X=690|Location.Y=798|Name=C|Designator=1|PinPropagationDelay=0.000000E+000
|RECORD=2|OwnerIndex=1486|OwnerPartId=1|Electrical=4|PinConglomerate=49|PinLength=8|Location.X=690|Location.Y=802|Name=A|Designator=2|PinPropagationDelay=0.000000E+000
|RECORD=5|OwnerIndex=1486|IsNotAccesible=T|IndexInSheet=2|OwnerPartId=1|LineWidth=1|Color=16711680|LocationCount=4|X1=680|Y1=794|X2=685|Y2=800|X3=695|Y3=800|X4=700|Y4=794
|RECORD=13|OwnerIndex=1486|IsNotAccesible=T|IndexInSheet=3|OwnerPartId=1|Location.X=680|Location.Y=802|Corner.X=700|Corner.Y=802|LineWidth=1|Color=16711680
|RECORD=13|OwnerIndex=1486|IsNotAccesible=T|IndexInSheet=4|OwnerPartId=1|Location.X=690|Location.Y=798|Corner.X=690|Corner.Y=796|LineWidth=1|Color=16711680
|RECORD=13|OwnerIndex=1486|IsNotAccesible=T|IndexInSheet=5|OwnerPartId=1|Location.X=690|Location.Y=802|Corner.X=690|Corner.Y=805|LineWidth=1|Color=16711680
|RECORD=4|OwnerIndex=1486|IsNotAccesible=T|IndexInSheet=6|OwnerPartId=1|Location.X=679|Location.Y=812|Justification=6|Color=8388608|FontID=1|Text=+
|RECORD=41|OwnerIndex=1486|IndexInSheet=7|OwnerPartId=-1|Location.X=679|Location.Y=812|Color=8388608|FontID=1|IsHidden=T|Text=100uF|Name=Capacitance
|RECORD=41|OwnerIndex=1486|IndexInSheet=8|OwnerPartId=-1|Location.X=679|Location.Y=812|Color=8388608|FontID=1|IsHidden=T|Text=No|Name=Radiation Hardening
|RECORD=41|OwnerIndex=1486|IndexInSheet=9|OwnerPartId=-1|Location.X=679|Location.Y=812|Color=8388608|FontID=1|IsHidden=T|Text=Yes|Name=RoHS Compliant
|RECORD=41|OwnerIndex=1486|IndexInSheet=10|OwnerPartId=-1|Location.X=679|Location.Y=812|Color=8388608|FontID=1|IsHidden=T|Text=7.3mm|Name=Length
|RECORD=41|OwnerIndex=1486|IndexInSheet=11|OwnerPartId=-1|Location.X=679|Location.Y=812|Color=8388608|FontID=1|IsHidden=T|Text=General Purpose|Name=Features
|RECORD=41|OwnerIndex=1486|IndexInSheet=12|OwnerPartId=-1|Location.X=679|Location.Y=812|Color=8388608|FontID=1|IsHidden=T|Text=Tape and Reel|Name=Packaging
|RECORD=41|OwnerIndex=1486|IndexInSheet=13|OwnerPartId=-1|Location.X=679|Location.Y=812|Color=8388608|FontID=1|IsHidden=T|Text=1|Name=Package Quantity
|RECORD=41|OwnerIndex=1486|IndexInSheet=14|OwnerPartId=-1|Location.X=679|Location.Y=812|Color=8388608|FontID=1|IsHidden=T|Text=0.023634oz|Name=Weight
|RECORD=41|OwnerIndex=1486|IndexInSheet=15|OwnerPartId=-1|Location.X=679|Location.Y=812|Color=8388608|FontID=1|IsHidden=T|Text=2000Hour|Name=Life (Hours)
|RECORD=41|OwnerIndex=1486|IndexInSheet=16|OwnerPartId=-1|Location.X=679|Location.Y=812|Color=8388608|FontID=1|IsHidden=T|Text=16V|Name=Voltage Rating
|RECORD=41|OwnerIndex=1486|IndexInSheet=17|OwnerPartId=-1|Location.X=679|Location.Y=812|Color=8388608|FontID=1|IsHidden=T|Text=0.169inch|Name=Width
|RECORD=41|OwnerIndex=1486|IndexInSheet=18|OwnerPartId=-1|Location.X=679|Location.Y=812|Color=8388608|FontID=1|IsHidden=T|Text=2917|Name=Case/Package
|RECORD=41|OwnerIndex=1486|IndexInSheet=19|OwnerPartId=-1|Location.X=679|Location.Y=812|Color=8388608|FontID=1|IsHidden=T|Text=125mR|Name=ESR (Equivalent Series Resistance)
|RECORD=41|OwnerIndex=1486|IndexInSheet=20|OwnerPartId=-1|Location.X=679|Location.Y=812|Color=8388608|FontID=1|IsHidden=T|Text=Surface Mount|Name=Mount
|RECORD=41|OwnerIndex=1486|IndexInSheet=21|OwnerPartId=-1|Location.X=679|Location.Y=812|Color=8388608|FontID=1|IsHidden=T|Text=16V|Name=Voltage
|RECORD=41|OwnerIndex=1486|IndexInSheet=22|OwnerPartId=-1|Location.X=679|Location.Y=812|Color=8388608|FontID=1|IsHidden=T|Text=-55°C|Name=Min Operating Temperature
|RECORD=41|OwnerIndex=1486|IndexInSheet=23|OwnerPartId=-1|Location.X=679|Location.Y=812|Color=8388608|FontID=1|IsHidden=T|Text=10%|Name=Tolerance
|RECORD=41|OwnerIndex=1486|IndexInSheet=24|OwnerPartId=-1|Location.X=679|Location.Y=812|Color=8388608|FontID=1|IsHidden=T|Text=No SVHC|Name=REACH SVHC
|RECORD=41|OwnerIndex=1486|IndexInSheet=25|OwnerPartId=-1|Location.X=679|Location.Y=812|Color=8388608|FontID=1|IsHidden=T|Text=0.122inch|Name=Height - Seated (Max)
|RECORD=41|OwnerIndex=1486|IndexInSheet=26|OwnerPartId=-1|Location.X=679|Location.Y=812|Color=8388608|FontID=1|IsHidden=T|Text=2|Name=Number of Pins
|RECORD=41|OwnerIndex=1486|IndexInSheet=27|OwnerPartId=-1|Location.X=679|Location.Y=812|Color=8388608|FontID=1|IsHidden=T|Text=Flat|Name=Construction
|RECORD=41|OwnerIndex=1486|IndexInSheet=28|OwnerPartId=-1|Location.X=679|Location.Y=812|Color=8388608|FontID=1|IsHidden=T|Text=4.3mm|Name=Depth
|RECORD=41|OwnerIndex=1486|IndexInSheet=29|OwnerPartId=-1|Location.X=679|Location.Y=812|Color=8388608|FontID=1|IsHidden=T|Text=T495|Name=Series
|RECORD=41|OwnerIndex=1486|IndexInSheet=30|OwnerPartId=-1|Location.X=679|Location.Y=812|Color=8388608|FontID=1|IsHidden=T|Text=125°C|Name=Max Operating Temperature
|RECORD=41|OwnerIndex=1486|IndexInSheet=31|OwnerPartId=-1|Location.X=679|Location.Y=812|Color=8388608|FontID=1|IsHidden=T|Text=0.001%|Name=Failure Rate
|RECORD=41|OwnerIndex=1486|IndexInSheet=32|OwnerPartId=-1|Location.X=679|Location.Y=812|Color=8388608|FontID=1|IsHidden=T|Text=SMD/SMT|Name=Termination
|RECORD=41|OwnerIndex=1486|IndexInSheet=33|OwnerPartId=-1|Location.X=679|Location.Y=812|Color=8388608|FontID=1|IsHidden=T|Text=Polar|Name=Polarity
|RECORD=41|OwnerIndex=1486|IndexInSheet=34|OwnerPartId=-1|Location.X=679|Location.Y=812|Color=8388608|FontID=1|IsHidden=T|Text=16V|Name=Voltage Rating (DC)
|RECORD=41|OwnerIndex=1486|IndexInSheet=35|OwnerPartId=-1|Location.X=679|Location.Y=812|Color=8388608|FontID=1|IsHidden=T|Text=Tantalum|Name=Dielectric Material
|RECORD=41|OwnerIndex=1486|IndexInSheet=36|OwnerPartId=-1|Location.X=679|Location.Y=812|Color=8388608|FontID=1|IsHidden=T|Text=2917|Name=Case Code (Imperial)
|RECORD=41|OwnerIndex=1486|IndexInSheet=37|OwnerPartId=-1|Location.X=679|Location.Y=812|Color=8388608|FontID=1|IsHidden=T|Text=7343|Name=Case Code (Metric)
|RECORD=41|OwnerIndex=1486|IndexInSheet=38|OwnerPartId=-1|Location.X=679|Location.Y=812|Color=8388608|FontID=1|IsHidden=T|Text=2.8mm|Name=Height
|RECORD=41|OwnerIndex=1486|IndexInSheet=39|OwnerPartId=-1|Location.X=679|Location.Y=812|Color=8388608|FontID=1|IsHidden=T|Text=8%|Name=Dissipation Factor
|RECORD=34|OwnerIndex=1486|IndexInSheet=-1|OwnerPartId=-1|Location.X=675|Location.Y=790|Orientation=1|Color=8388608|FontID=2|Text=C10|Name=Designator|ReadOnlyState=1
|RECORD=41|OwnerIndex=1486|IndexInSheet=-1|OwnerPartId=1|Location.X=715|Location.Y=770|Orientation=1|Color=8388608|FontID=2|Text=100uF_16V_2917|Name=Comment
|RECORD=44|OwnerIndex=1486
|RECORD=45|OwnerIndex=1531|IndexInSheet=-1|UseComponentLibrary=T|ModelName=FP-T495D107K016ATE125-MFG|ModelType=PCBLIB|DatafileCount=1|ModelDatafileEntity0=FP-T495D107K016ATE125-MFG|ModelDatafileKind0=PCBLib|IsCurrent=T|DatalinksLocked=T|DatabaseDatalinksLocked=T
|RECORD=46|OwnerIndex=1532
|RECORD=48|OwnerIndex=1532
|RECORD=1|LibReference=11868f565c42a9108669ba33697ecf6|ComponentDescription=CAP CER 0.1UF 50V X7R 0603|PartCount=2|DisplayModeCount=1|IndexInSheet=96|OwnerPartId=-1|Location.X=1190|Location.Y=810|CurrentPartId=1|LibraryPath=*|SourceLibraryName=Altium Content Vault|TargetFileName=*|AreaColor=11599871|Color=128|PartIDLocked=T|DesignItemId=CMP-2100-03601-2|AllPinCount=2
|RECORD=2|OwnerIndex=1535|OwnerPartId=1|Electrical=4|PinConglomerate=49|PinLength=7|Location.X=1190|Location.Y=803|Name=1|Designator=1|PinPropagationDelay=0.000000E+000
|RECORD=2|OwnerIndex=1535|OwnerPartId=1|Electrical=4|PinConglomerate=51|PinLength=6|Location.X=1190|Location.Y=796|Name=2|Designator=2|PinPropagationDelay=0.000000E+000
|RECORD=13|OwnerIndex=1535|IsNotAccesible=T|IndexInSheet=2|OwnerPartId=1|Location.X=1200|Location.Y=803|Corner.X=1180|Corner.Y=803|LineWidth=1|Color=16711680
|RECORD=13|OwnerIndex=1535|IsNotAccesible=T|IndexInSheet=3|OwnerPartId=1|Location.X=1200|Location.Y=797|Corner.X=1180|Corner.Y=797|LineWidth=1|Color=16711680
|RECORD=13|OwnerIndex=1535|IsNotAccesible=T|IndexInSheet=4|OwnerPartId=1|Location.X=1190|Location.Y=803|Corner.X=1190|Corner.Y=806|LineWidth=1|Color=16711680
|RECORD=13|OwnerIndex=1535|IsNotAccesible=T|IndexInSheet=5|OwnerPartId=1|Location.X=1190|Location.Y=796|Corner.X=1190|Corner.Y=795|LineWidth=1|Color=16711680
|RECORD=41|OwnerIndex=1535|IndexInSheet=6|OwnerPartId=-1|Location.X=1179|Location.Y=812|Color=8388608|FontID=1|IsHidden=T|Text=0.9mm|Name=Height
|RECORD=41|OwnerIndex=1535|IndexInSheet=7|OwnerPartId=-1|Location.X=1179|Location.Y=812|Color=8388608|FontID=1|IsHidden=T|Text=Ceramic|Name=Material
|RECORD=41|OwnerIndex=1535|IndexInSheet=8|OwnerPartId=-1|Location.X=1179|Location.Y=812|Color=8388608|FontID=1|IsHidden=T|Text=YAGEO|Name=Manufacturer
|RECORD=41|OwnerIndex=1535|IndexInSheet=9|OwnerPartId=-1|Location.X=1179|Location.Y=812|Color=8388608|FontID=1|IsHidden=T|Text=50 V|Name=Voltage
|RECORD=41|OwnerIndex=1535|IndexInSheet=10|OwnerPartId=-1|Location.X=1179|Location.Y=812|Color=8388608|FontID=1|IsHidden=T|Text=Datasheet|Name=ComponentLink2Description
|RECORD=41|OwnerIndex=1535|IndexInSheet=11|OwnerPartId=-1|Location.X=1179|Location.Y=812|Color=8388608|FontID=1|IsHidden=T|Text=Capacitors|Name=Device Class L2
|RECORD=41|OwnerIndex=1535|IndexInSheet=12|OwnerPartId=-1|Location.X=1179|Location.Y=812|Color=8388608|FontID=1|IsHidden=T|Text=+125°C|Name=Temperature Range High
|RECORD=41|OwnerIndex=1535|IndexInSheet=13|OwnerPartId=-1|Location.X=1179|Location.Y=812|Color=8388608|FontID=1|IsHidden=T|Text=Cap|Name=Category
|RECORD=41|OwnerIndex=1535|IndexInSheet=14|OwnerPartId=-1|Location.X=1179|Location.Y=812|Color=8388608|FontID=1|IsHidden=T|Text=100 nF|Name=Capacitance
|RECORD=41|OwnerIndex=1535|IndexInSheet=15|OwnerPartId=-1|Location.X=1179|Location.Y=812|Color=8388608|FontID=7|IsHidden=T|Text=http://www.yageo.com/exep/pages/download/literatures/UPY-C_GEN_24.pdf|Name=Footprint Url
|RECORD=41|OwnerIndex=1535|IndexInSheet=16|OwnerPartId=-1|Location.X=1179|Location.Y=812|Color=8388608|FontID=7|IsHidden=T|Text=http://www.yageo.com/documents/recent/UPY-GPHC_X7R_6.3V-to-50V_18.pdf|Name=ComponentLink2URL
|RECORD=41|OwnerIndex=1535|IndexInSheet=17|OwnerPartId=-1|Location.X=1179|Location.Y=812|Color=8388608|FontID=1|IsHidden=T|Text=CC0603-DA|Name=Package
|RECORD=41|OwnerIndex=1535|IndexInSheet=18|OwnerPartId=-1|Location.X=1179|Location.Y=812|Color=8388608|FontID=1|IsHidden=T|Text=-55°C to +125°C|Name=Temperature
|RECORD=41|OwnerIndex=1535|IndexInSheet=19|OwnerPartId=-1|Location.X=1179|Location.Y=812|Color=8388608|FontID=1|IsHidden=T|Text=15%|Name=Temperature Coefficient
|RECORD=41|OwnerIndex=1535|IndexInSheet=20|OwnerPartId=-1|Location.X=1179|Location.Y=812|Color=8388608|FontID=1|IsHidden=T|Text=50 V|Name=Voltage Rating
|RECORD=41|OwnerIndex=1535|IndexInSheet=21|OwnerPartId=-1|Location.X=1179|Location.Y=812|Color=8388608|FontID=1|IsHidden=T|Text=X7R|Name=Temperature Characteristic
|RECORD=41|OwnerIndex=1535|IndexInSheet=22|OwnerPartId=-1|Location.X=1179|Location.Y=812|Color=8388608|FontID=1|IsHidden=T|Text=Passive Components|Name=Device Class L1
|RECORD=41|OwnerIndex=1535|IndexInSheet=23|OwnerPartId=-1|Location.X=1179|Location.Y=812|Color=8388608|FontID=1|IsHidden=T|Text=-55°C|Name=Temperature Range Low
|RECORD=41|OwnerIndex=1535|IndexInSheet=24|OwnerPartId=-1|Location.X=1179|Location.Y=812|Color=8388608|FontID=1|IsHidden=T|Text=CC0603KRX7R9BB104|Name=Manufacturer Part Number
|RECORD=41|OwnerIndex=1535|IndexInSheet=25|OwnerPartId=-1|Location.X=1179|Location.Y=812|Color=8388608|FontID=1|IsHidden=T|Text=TRUE|Name=RoHS
|RECORD=41|OwnerIndex=1535|IndexInSheet=26|OwnerPartId=-1|Location.X=1179|Location.Y=812|Color=8388608|FontID=1|IsHidden=T|Text=0.1|Name=Tolerance
|RECORD=41|OwnerIndex=1535|IndexInSheet=27|OwnerPartId=-1|Location.X=1179|Location.Y=812|Color=8388608|FontID=1|IsHidden=T|Text=No|Name=Automotive
|RECORD=41|OwnerIndex=1535|IndexInSheet=28|OwnerPartId=-1|Location.X=1179|Location.Y=812|Color=8388608|FontID=1|IsHidden=T|Text=100 nF|Name=Value
|RECORD=41|OwnerIndex=1535|IndexInSheet=29|OwnerPartId=-1|Location.X=1179|Location.Y=812|Color=8388608|FontID=1|IsHidden=T|Text=Ceramic Capacitors|Name=Device Class L3
|RECORD=41|OwnerIndex=1535|IndexInSheet=30|OwnerPartId=-1|Location.X=1179|Location.Y=812|Color=8388608|FontID=7|IsHidden=T|Text=https://octopart.com/cc0603krx7r9bb104-yageo-42244635|Name=Octopart
|RECORD=41|OwnerIndex=1535|IndexInSheet=31|OwnerPartId=-1|Location.X=1179|Location.Y=812|Color=8388608|FontID=1|IsHidden=T|Text=Multilayer Ceramic Capacitor, CC Series, 0.1 - F, - 10%, X7R, 50 V, 0603 [1608 Metric]|Name=Mouser Description
|RECORD=41|OwnerIndex=1535|IndexInSheet=32|OwnerPartId=-1|Location.X=1179|Location.Y=812|Color=8388608|FontID=1|IsHidden=T|Text=Yes|Name=Lead Free
|RECORD=41|OwnerIndex=1535|IndexInSheet=33|OwnerPartId=-1|Location.X=1179|Location.Y=812|Color=8388608|FontID=1|IsHidden=T|Text=CAP CER 0.1UF 50V X7R 0603|Name=Digikey Description
|RECORD=34|OwnerIndex=1535|IndexInSheet=-1|OwnerPartId=-1|Location.X=1180|Location.Y=795|Orientation=1|Color=8388608|FontID=2|Text=C9|Name=Designator|ReadOnlyState=1
|RECORD=41|OwnerIndex=1535|IndexInSheet=-1|OwnerPartId=1|Location.X=1210|Location.Y=750|Orientation=1|Color=8388608|FontID=2|Text=0.1uF_50V_0603|Name=Comment
|RECORD=44|OwnerIndex=1535
|RECORD=45|OwnerIndex=1574|IndexInSheet=-1|UseComponentLibrary=T|ModelName=FP-CC0603-DA-MFG|ModelType=PCBLIB|DatafileCount=1|ModelDatafileEntity0=FP-CC0603-DA-MFG|ModelDatafileKind0=PCBLib|IsCurrent=T|DatalinksLocked=T|DatabaseDatalinksLocked=T
|RECORD=46|OwnerIndex=1575
|RECORD=48|OwnerIndex=1575
|RECORD=45|OwnerIndex=1574|IndexInSheet=-1|UseComponentLibrary=T|ModelName=FP-CC0603-DA-IPC_C|ModelType=PCBLIB|DatafileCount=1|ModelDatafileEntity0=FP-CC0603-DA-IPC_C|ModelDatafileKind0=PCBLib|DatalinksLocked=T|DatabaseDatalinksLocked=T
|RECORD=46|OwnerIndex=1578
|RECORD=48|OwnerIndex=1578
|RECORD=45|OwnerIndex=1574|IndexInSheet=-1|UseComponentLibrary=T|ModelName=FP-CC0603-DA-IPC_B|ModelType=PCBLIB|DatafileCount=1|ModelDatafileEntity0=FP-CC0603-DA-IPC_B|ModelDatafileKind0=PCBLib|DatalinksLocked=T|DatabaseDatalinksLocked=T
|RECORD=46|OwnerIndex=1581
|RECORD=48|OwnerIndex=1581
|RECORD=45|OwnerIndex=1574|IndexInSheet=-1|UseComponentLibrary=T|ModelName=FP-CC0603-DA-IPC_A|ModelType=PCBLIB|DatafileCount=1|ModelDatafileEntity0=FP-CC0603-DA-IPC_A|ModelDatafileKind0=PCBLib|DatalinksLocked=T|DatabaseDatalinksLocked=T
|RECORD=46|OwnerIndex=1584
|RECORD=48|OwnerIndex=1584
|RECORD=1|LibReference=RES|PartCount=2|DisplayModeCount=2|IndexInSheet=97|OwnerPartId=-1|Location.X=1180|Location.Y=835|Orientation=1|CurrentPartId=1|SourceLibraryName=Altium Content Vault|TargetFileName=*|AreaColor=11599871|Color=128|PartIDLocked=F|DesignItemId=CMP-2002-07443-1|AllPinCount=2
|RECORD=2|OwnerIndex=1587|OwnerPartId=1|OwnerPartDisplayMode=1|FormalType=1|Electrical=4|PinConglomerate=33|PinLength=10|Location.X=1190|Location.Y=855|Name=2|Designator=2|PinPropagationDelay=0.000000E+000
|RECORD=2|OwnerIndex=1587|OwnerPartId=1|OwnerPartDisplayMode=1|FormalType=1|Electrical=4|PinConglomerate=35|PinLength=10|Location.X=1190|Location.Y=835|Name=1|Designator=1|PinPropagationDelay=0.000000E+000
|RECORD=14|OwnerIndex=1587|IsNotAccesible=T|IndexInSheet=2|OwnerPartId=1|OwnerPartDisplayMode=1|Location.X=1186|Location.Y=835|Corner.X=1194|Corner.Y=855|LineWidth=1|Color=16711680|AreaColor=11599871
|RECORD=2|OwnerIndex=1587|OwnerPartId=1|FormalType=1|Electrical=4|PinConglomerate=33|PinLength=10|Location.X=1190|Location.Y=855|Name=2|Designator=2|PinPropagationDelay=0.000000E+000
|RECORD=2|OwnerIndex=1587|OwnerPartId=1|FormalType=1|Electrical=4|PinConglomerate=35|PinLength=10|Location.X=1190|Location.Y=835|Name=1|Designator=1|PinPropagationDelay=0.000000E+000
|RECORD=6|OwnerIndex=1587|IsNotAccesible=T|IndexInSheet=5|OwnerPartId=1|LineWidth=1|Color=16711680|LocationCount=10|X1=1190|Y1=855|X2=1190|Y2=851|X3=1192|Y3=850|X4=1188|Y4=848|X5=1192|Y5=846|X6=1188|Y6=844|X7=1192|Y7=842|X8=1188|Y8=840|X9=1190|Y9=839|X10=1190|Y10=835
|RECORD=41|OwnerIndex=1587|IndexInSheet=6|OwnerPartId=-1|Location.X=1187|Location.Y=867|Color=8388608|FontID=1|IsHidden=T|Text=RC0402FR-0719K6L|Name=Part Number
|RECORD=41|OwnerIndex=1587|IndexInSheet=7|OwnerPartId=-1|Location.X=1187|Location.Y=867|Color=8388608|FontID=1|IsHidden=T|Text=Yageo|Name=Manufacturer
|RECORD=34|OwnerIndex=1587|IndexInSheet=-1|OwnerPartId=-1|Location.X=1185|Location.Y=830|Orientation=1|Color=8388608|FontID=2|Text=R60|Name=Designator|ReadOnlyState=1
|RECORD=41|OwnerIndex=1587|IndexInSheet=-1|OwnerPartId=-1|Location.X=1205|Location.Y=820|Orientation=1|Color=8388608|FontID=2|Text=19.6K_1%_0402|Name=Comment
|RECORD=44|OwnerIndex=1587
|RECORD=45|OwnerIndex=1602|IndexInSheet=-1|Description=Chip Resistor, 2-Leads, Body 1.00x0.50mm, IPC Medium Density|UseComponentLibrary=T|ModelName=RESC1005X40X25NL05T10|ModelType=PCBLIB|DatafileCount=1|ModelDatafileEntity0=RESC1005X40X25NL05T10|ModelDatafileKind0=PCBLib|IsCurrent=T|DatalinksLocked=T|DatabaseDatalinksLocked=T
|RECORD=46|OwnerIndex=1603
|RECORD=48|OwnerIndex=1603
|RECORD=41|OwnerIndex=1605|IndexInSheet=-1|OwnerPartId=-1|Color=8388608|FontID=1|IsHidden=T|Text=2D|Name=Available Preview Images
|RECORD=45|OwnerIndex=1602|IndexInSheet=-1|Description=Chip Resistor, 2-Leads, Body 1.00x0.50mm, IPC Low Density|UseComponentLibrary=T|ModelName=RESC1005X40X25ML05T10|ModelType=PCBLIB|DatafileCount=1|ModelDatafileEntity0=RESC1005X40X25ML05T10|ModelDatafileKind0=PCBLib|DatalinksLocked=T|DatabaseDatalinksLocked=T
|RECORD=46|OwnerIndex=1607
|RECORD=48|OwnerIndex=1607
|RECORD=41|OwnerIndex=1609|IndexInSheet=-1|OwnerPartId=-1|Color=8388608|FontID=1|IsHidden=T|Text=2D|Name=Available Preview Images
|RECORD=45|OwnerIndex=1602|IndexInSheet=-1|Description=Chip Resistor, 2-Leads, Body 1.00x0.50mm, IPC High Density|UseComponentLibrary=T|ModelName=RESC1005X40X25LL05T10|ModelType=PCBLIB|DatafileCount=1|ModelDatafileEntity0=RESC1005X40X25LL05T10|ModelDatafileKind0=PCBLib|DatalinksLocked=T|DatabaseDatalinksLocked=T
|RECORD=46|OwnerIndex=1611
|RECORD=48|OwnerIndex=1611
|RECORD=41|OwnerIndex=1613|IndexInSheet=-1|OwnerPartId=-1|Color=8388608|FontID=1|IsHidden=T|Text=2D|Name=Available Preview Images
|RECORD=25|IndexInSheet=98|OwnerPartId=-1|Location.X=790|Location.Y=955|Color=128|FontID=1|Text=P5V_FB
|RECORD=25|IndexInSheet=99|OwnerPartId=-1|Location.X=1095|Location.Y=745|Color=128|FontID=1|Text=P5V_FB
|RECORD=1|LibReference=RES|PartCount=2|DisplayModeCount=2|IndexInSheet=100|OwnerPartId=-1|Location.X=1270|Location.Y=820|Orientation=1|CurrentPartId=1|SourceLibraryName=Altium Content Vault|TargetFileName=*|AreaColor=11599871|Color=128|PartIDLocked=F|DesignItemId=CMP-2002-07571-1|AllPinCount=2
|RECORD=2|OwnerIndex=1617|OwnerPartId=1|OwnerPartDisplayMode=1|FormalType=1|Electrical=4|PinConglomerate=33|PinLength=10|Location.X=1280|Location.Y=840|Name=2|Designator=2|PinPropagationDelay=0.000000E+000
|RECORD=2|OwnerIndex=1617|OwnerPartId=1|OwnerPartDisplayMode=1|FormalType=1|Electrical=4|PinConglomerate=35|PinLength=10|Location.X=1280|Location.Y=820|Name=1|Designator=1|PinPropagationDelay=0.000000E+000
|RECORD=14|OwnerIndex=1617|IsNotAccesible=T|IndexInSheet=2|OwnerPartId=1|OwnerPartDisplayMode=1|Location.X=1276|Location.Y=820|Corner.X=1284|Corner.Y=840|LineWidth=1|Color=16711680|AreaColor=11599871
|RECORD=2|OwnerIndex=1617|OwnerPartId=1|FormalType=1|Electrical=4|PinConglomerate=33|PinLength=10|Location.X=1280|Location.Y=840|Name=2|Designator=2|PinPropagationDelay=0.000000E+000
|RECORD=2|OwnerIndex=1617|OwnerPartId=1|FormalType=1|Electrical=4|PinConglomerate=35|PinLength=10|Location.X=1280|Location.Y=820|Name=1|Designator=1|PinPropagationDelay=0.000000E+000
|RECORD=6|OwnerIndex=1617|IsNotAccesible=T|IndexInSheet=5|OwnerPartId=1|LineWidth=1|Color=16711680|LocationCount=10|X1=1280|Y1=840|X2=1280|Y2=836|X3=1282|Y3=835|X4=1278|Y4=833|X5=1282|Y5=831|X6=1278|Y6=829|X7=1282|Y7=827|X8=1278|Y8=825|X9=1280|Y9=824|X10=1280|Y10=820
|RECORD=41|OwnerIndex=1617|IndexInSheet=6|OwnerPartId=-1|Location.X=1277|Location.Y=852|Color=8388608|FontID=1|IsHidden=T|Text=RC0402FR-072K49L|Name=Part Number
|RECORD=41|OwnerIndex=1617|IndexInSheet=7|OwnerPartId=-1|Location.X=1277|Location.Y=852|Color=8388608|FontID=1|IsHidden=T|Text=Yageo|Name=Manufacturer
|RECORD=34|OwnerIndex=1617|IndexInSheet=-1|OwnerPartId=-1|Location.X=1275|Location.Y=820|Orientation=1|Color=8388608|FontID=2|Text=R61|Name=Designator|ReadOnlyState=1
|RECORD=41|OwnerIndex=1617|IndexInSheet=-1|OwnerPartId=-1|Location.X=1295|Location.Y=800|Orientation=1|Color=8388608|FontID=2|Text=2.49K_1%_0402|Name=Comment
|RECORD=44|OwnerIndex=1617
|RECORD=45|OwnerIndex=1632|IndexInSheet=-1|Description=Chip Resistor, 2-Leads, Body 1.00x0.50mm, IPC Medium Density|UseComponentLibrary=T|ModelName=RESC1005X40X25NL05T10|ModelType=PCBLIB|DatafileCount=1|ModelDatafileEntity0=RESC1005X40X25NL05T10|ModelDatafileKind0=PCBLib|IsCurrent=T|DatalinksLocked=T|DatabaseDatalinksLocked=T
|RECORD=46|OwnerIndex=1633
|RECORD=48|OwnerIndex=1633
|RECORD=41|OwnerIndex=1635|IndexInSheet=-1|OwnerPartId=-1|Color=8388608|FontID=1|IsHidden=T|Text=2D|Name=Available Preview Images
|RECORD=45|OwnerIndex=1632|IndexInSheet=-1|Description=Chip Resistor, 2-Leads, Body 1.00x0.50mm, IPC High Density|UseComponentLibrary=T|ModelName=RESC1005X40X25LL05T10|ModelType=PCBLIB|DatafileCount=1|ModelDatafileEntity0=RESC1005X40X25LL05T10|ModelDatafileKind0=PCBLib|DatalinksLocked=T|DatabaseDatalinksLocked=T
|RECORD=46|OwnerIndex=1637
|RECORD=48|OwnerIndex=1637
|RECORD=41|OwnerIndex=1639|IndexInSheet=-1|OwnerPartId=-1|Color=8388608|FontID=1|IsHidden=T|Text=2D|Name=Available Preview Images
|RECORD=45|OwnerIndex=1632|IndexInSheet=-1|Description=Chip Resistor, 2-Leads, Body 1.00x0.50mm, IPC Low Density|UseComponentLibrary=T|ModelName=RESC1005X40X25ML05T10|ModelType=PCBLIB|DatafileCount=1|ModelDatafileEntity0=RESC1005X40X25ML05T10|ModelDatafileKind0=PCBLib|DatalinksLocked=T|DatabaseDatalinksLocked=T
|RECORD=46|OwnerIndex=1641
|RECORD=48|OwnerIndex=1641
|RECORD=41|OwnerIndex=1643|IndexInSheet=-1|OwnerPartId=-1|Color=8388608|FontID=1|IsHidden=T|Text=2D|Name=Available Preview Images
|RECORD=1|LibReference=11868f565c42a9108669ba33697ecf6|ComponentDescription=CAP CER 4700PF 50V X7R 0402|PartCount=2|DisplayModeCount=1|IndexInSheet=101|OwnerPartId=-1|Location.X=1245|Location.Y=835|CurrentPartId=1|LibraryPath=*|SourceLibraryName=Altium Content Vault|TargetFileName=*|AreaColor=11599871|Color=128|PartIDLocked=T|DesignItemId=CMP-03422-001290-1|AllPinCount=2
|RECORD=2|OwnerIndex=1645|OwnerPartId=1|Electrical=4|PinConglomerate=49|PinLength=7|Location.X=1245|Location.Y=828|Name=1|Designator=1|PinPropagationDelay=0.000000E+000
|RECORD=2|OwnerIndex=1645|OwnerPartId=1|Electrical=4|PinConglomerate=51|PinLength=6|Location.X=1245|Location.Y=821|Name=2|Designator=2|PinPropagationDelay=0.000000E+000
|RECORD=13|OwnerIndex=1645|IsNotAccesible=T|IndexInSheet=2|OwnerPartId=1|Location.X=1255|Location.Y=828|Corner.X=1235|Corner.Y=828|LineWidth=1|Color=16711680
|RECORD=13|OwnerIndex=1645|IsNotAccesible=T|IndexInSheet=3|OwnerPartId=1|Location.X=1255|Location.Y=822|Corner.X=1235|Corner.Y=822|LineWidth=1|Color=16711680
|RECORD=13|OwnerIndex=1645|IsNotAccesible=T|IndexInSheet=4|OwnerPartId=1|Location.X=1245|Location.Y=828|Corner.X=1245|Corner.Y=831|LineWidth=1|Color=16711680
|RECORD=13|OwnerIndex=1645|IsNotAccesible=T|IndexInSheet=5|OwnerPartId=1|Location.X=1245|Location.Y=821|Corner.X=1245|Corner.Y=820|LineWidth=1|Color=16711680
|RECORD=41|OwnerIndex=1645|IndexInSheet=6|OwnerPartId=-1|Location.X=1234|Location.Y=837|Color=8388608|FontID=7|IsHidden=T|Text=http://www.yageo.com/documents/recent/UPY-GP_NP0_16V-to-50V_16.pdf|Name=ComponentLink2URL
|RECORD=41|OwnerIndex=1645|IndexInSheet=7|OwnerPartId=-1|Location.X=1234|Location.Y=837|Color=8388608|FontID=1|IsHidden=T|Text=Ceramic|Name=Material
|RECORD=41|OwnerIndex=1645|IndexInSheet=8|OwnerPartId=-1|Location.X=1234|Location.Y=837|Color=8388608|FontID=1|IsHidden=T|Text=Ceramic Capacitors|Name=Device Class L3
|RECORD=41|OwnerIndex=1645|IndexInSheet=9|OwnerPartId=-1|Location.X=1234|Location.Y=837|Color=8388608|FontID=1|IsHidden=T|Text=0.55mm|Name=Height
|RECORD=41|OwnerIndex=1645|IndexInSheet=10|OwnerPartId=-1|Location.X=1234|Location.Y=837|Color=8388608|FontID=1|IsHidden=T|Text=TRUE|Name=RoHS
|RECORD=41|OwnerIndex=1645|IndexInSheet=11|OwnerPartId=-1|Location.X=1234|Location.Y=837|Color=8388608|FontID=1|IsHidden=T|Text=Multilayer Ceramic Capacitors MLCC - SMD/SMT 4.7nF 50V X7R 10%|Name=Mouser Description
|RECORD=41|OwnerIndex=1645|IndexInSheet=12|OwnerPartId=-1|Location.X=1234|Location.Y=837|Color=8388608|FontID=1|IsHidden=T|Text=Cap|Name=Category
|RECORD=41|OwnerIndex=1645|IndexInSheet=13|OwnerPartId=-1|Location.X=1234|Location.Y=837|Color=8388608|FontID=1|IsHidden=T|Text=YAGEO|Name=Manufacturer
|RECORD=41|OwnerIndex=1645|IndexInSheet=14|OwnerPartId=-1|Location.X=1234|Location.Y=837|Color=8388608|FontID=1|IsHidden=T|Text=-55°C to +125°C|Name=Temperature
|RECORD=41|OwnerIndex=1645|IndexInSheet=15|OwnerPartId=-1|Location.X=1234|Location.Y=837|Color=8388608|FontID=7|IsHidden=T|Text=http://www.yageo.com/exep/pages/download/literatures/UPY-C_GEN_24.pdf|Name=Footprint Url
|RECORD=41|OwnerIndex=1645|IndexInSheet=16|OwnerPartId=-1|Location.X=1234|Location.Y=837|Color=8388608|FontID=1|IsHidden=T|Text=Capacitors|Name=Device Class L2
|RECORD=41|OwnerIndex=1645|IndexInSheet=17|OwnerPartId=-1|Location.X=1234|Location.Y=837|Color=8388608|FontID=1|IsHidden=T|Text=No|Name=Automotive
|RECORD=41|OwnerIndex=1645|IndexInSheet=18|OwnerPartId=-1|Location.X=1234|Location.Y=837|Color=8388608|FontID=1|IsHidden=T|Text=30ppm/°C|Name=Temperature Coefficient
|RECORD=41|OwnerIndex=1645|IndexInSheet=19|OwnerPartId=-1|Location.X=1234|Location.Y=837|Color=8388608|FontID=7|IsHidden=T|Text=https://octopart.com/cc0402krx7r9bb472-yageo-9288149|Name=Octopart
|RECORD=41|OwnerIndex=1645|IndexInSheet=20|OwnerPartId=-1|Location.X=1234|Location.Y=837|Color=8388608|FontID=1|IsHidden=T|Text=CAP CER 4700PF 50V X7R 0402|Name=Digikey Description
|RECORD=41|OwnerIndex=1645|IndexInSheet=21|OwnerPartId=-1|Location.X=1234|Location.Y=837|Color=8388608|FontID=1|IsHidden=T|Text=Yes|Name=Lead Free
|RECORD=41|OwnerIndex=1645|IndexInSheet=22|OwnerPartId=-1|Location.X=1234|Location.Y=837|Color=8388608|FontID=1|IsHidden=T|Text=CAPC10050X50|Name=Ipc Land Pattern Name
|RECORD=41|OwnerIndex=1645|IndexInSheet=23|OwnerPartId=-1|Location.X=1234|Location.Y=837|Color=8388608|FontID=1|IsHidden=T|Text=Passive Components|Name=Device Class L1
|RECORD=41|OwnerIndex=1645|IndexInSheet=24|OwnerPartId=-1|Location.X=1234|Location.Y=837|Color=8388608|FontID=1|IsHidden=T|Text=Datasheet|Name=ComponentLink2Description
|RECORD=41|OwnerIndex=1645|IndexInSheet=25|OwnerPartId=-1|Location.X=1234|Location.Y=837|Color=8388608|FontID=1|IsHidden=T|Text=CC0402KRX7R9BB472|Name=Manufacturer Part Number
|RECORD=41|OwnerIndex=1645|IndexInSheet=26|OwnerPartId=-1|Location.X=1234|Location.Y=837|Color=8388608|FontID=1|IsHidden=T|Text=4.7 nF|Name=Capacitance
|RECORD=41|OwnerIndex=1645|IndexInSheet=27|OwnerPartId=-1|Location.X=1234|Location.Y=837|Color=8388608|FontID=1|IsHidden=T|Text=X7R|Name=Temperature Characteristic
|RECORD=41|OwnerIndex=1645|IndexInSheet=28|OwnerPartId=-1|Location.X=1234|Location.Y=837|Color=8388608|FontID=1|IsHidden=T|Text=50 V|Name=Voltage Rating
|RECORD=41|OwnerIndex=1645|IndexInSheet=29|OwnerPartId=-1|Location.X=1234|Location.Y=837|Color=8388608|FontID=1|IsHidden=T|Text=0.1|Name=Tolerance
|RECORD=41|OwnerIndex=1645|IndexInSheet=30|OwnerPartId=-1|Location.X=1234|Location.Y=837|Color=8388608|FontID=1|IsHidden=T|Text=NA|Name=Automotive Grade
|RECORD=41|OwnerIndex=1645|IndexInSheet=31|OwnerPartId=-1|Location.X=1234|Location.Y=837|Color=8388608|FontID=1|IsHidden=T|Text=-55°C|Name=Temperature Range Low
|RECORD=41|OwnerIndex=1645|IndexInSheet=32|OwnerPartId=-1|Location.X=1234|Location.Y=837|Color=8388608|FontID=1|IsHidden=T|Text=4.7 nF|Name=Value
|RECORD=41|OwnerIndex=1645|IndexInSheet=33|OwnerPartId=-1|Location.X=1234|Location.Y=837|Color=8388608|FontID=1|IsHidden=T|Text=+125°C|Name=Temperature Range High
|RECORD=41|OwnerIndex=1645|IndexInSheet=34|OwnerPartId=-1|Location.X=1234|Location.Y=837|Color=8388608|FontID=1|IsHidden=T|Text=CC0402|Name=Package
|RECORD=34|OwnerIndex=1645|IndexInSheet=-1|OwnerPartId=-1|Location.X=1230|Location.Y=820|Orientation=1|Color=8388608|FontID=2|Text=C8|Name=Designator|ReadOnlyState=1
|RECORD=41|OwnerIndex=1645|IndexInSheet=-1|OwnerPartId=1|Location.X=1265|Location.Y=795|Orientation=1|Color=8388608|FontID=2|Text=4.7nF_50V_0402|Name=Comment
|RECORD=44|OwnerIndex=1645
|RECORD=45|OwnerIndex=1685|IndexInSheet=-1|UseComponentLibrary=T|ModelName=FP-CC0402-MFG|ModelType=PCBLIB|DatafileCount=1|ModelDatafileEntity0=FP-CC0402-MFG|ModelDatafileKind0=PCBLib|IsCurrent=T|DatalinksLocked=T|DatabaseDatalinksLocked=T
|RECORD=46|OwnerIndex=1686
|RECORD=48|OwnerIndex=1686
|RECORD=45|OwnerIndex=1685|IndexInSheet=-1|UseComponentLibrary=T|ModelName=FP-CC0402-IPC_C|ModelType=PCBLIB|DatafileCount=1|ModelDatafileEntity0=FP-CC0402-IPC_C|ModelDatafileKind0=PCBLib|DatalinksLocked=T|DatabaseDatalinksLocked=T
|RECORD=46|OwnerIndex=1689
|RECORD=48|OwnerIndex=1689
|RECORD=45|OwnerIndex=1685|IndexInSheet=-1|UseComponentLibrary=T|ModelName=FP-CC0402-IPC_B|ModelType=PCBLIB|DatafileCount=1|ModelDatafileEntity0=FP-CC0402-IPC_B|ModelDatafileKind0=PCBLib|DatalinksLocked=T|DatabaseDatalinksLocked=T
|RECORD=46|OwnerIndex=1692
|RECORD=48|OwnerIndex=1692
|RECORD=45|OwnerIndex=1685|IndexInSheet=-1|UseComponentLibrary=T|ModelName=FP-CC0402-IPC_A|ModelType=PCBLIB|DatafileCount=1|ModelDatafileEntity0=FP-CC0402-IPC_A|ModelDatafileKind0=PCBLib|DatalinksLocked=T|DatabaseDatalinksLocked=T
|RECORD=46|OwnerIndex=1695
|RECORD=48|OwnerIndex=1695
|RECORD=1|LibReference=RES|PartCount=2|DisplayModeCount=2|IndexInSheet=102|OwnerPartId=-1|Location.X=1270|Location.Y=705|Orientation=1|CurrentPartId=1|SourceLibraryName=Altium Content Vault|TargetFileName=*|AreaColor=11599871|Color=128|PartIDLocked=F|DesignItemId=CMP-2002-07697-1|AllPinCount=2
|RECORD=2|OwnerIndex=1698|OwnerPartId=1|OwnerPartDisplayMode=1|FormalType=1|Electrical=4|PinConglomerate=33|PinLength=10|Location.X=1280|Location.Y=725|Name=2|Designator=2|PinPropagationDelay=0.000000E+000
|RECORD=2|OwnerIndex=1698|OwnerPartId=1|OwnerPartDisplayMode=1|FormalType=1|Electrical=4|PinConglomerate=35|PinLength=10|Location.X=1280|Location.Y=705|Name=1|Designator=1|PinPropagationDelay=0.000000E+000
|RECORD=14|OwnerIndex=1698|IsNotAccesible=T|IndexInSheet=2|OwnerPartId=1|OwnerPartDisplayMode=1|Location.X=1276|Location.Y=705|Corner.X=1284|Corner.Y=725|LineWidth=1|Color=16711680|AreaColor=11599871
|RECORD=2|OwnerIndex=1698|OwnerPartId=1|FormalType=1|Electrical=4|PinConglomerate=33|PinLength=10|Location.X=1280|Location.Y=725|Name=2|Designator=2|PinPropagationDelay=0.000000E+000
|RECORD=2|OwnerIndex=1698|OwnerPartId=1|FormalType=1|Electrical=4|PinConglomerate=35|PinLength=10|Location.X=1280|Location.Y=705|Name=1|Designator=1|PinPropagationDelay=0.000000E+000
|RECORD=6|OwnerIndex=1698|IsNotAccesible=T|IndexInSheet=5|OwnerPartId=1|LineWidth=1|Color=16711680|LocationCount=10|X1=1280|Y1=725|X2=1280|Y2=721|X3=1282|Y3=720|X4=1278|Y4=718|X5=1282|Y5=716|X6=1278|Y6=714|X7=1282|Y7=712|X8=1278|Y8=710|X9=1280|Y9=709|X10=1280|Y10=705
|RECORD=41|OwnerIndex=1698|IndexInSheet=6|OwnerPartId=-1|Location.X=1277|Location.Y=737|Color=8388608|FontID=1|IsHidden=T|Text=RC0402FR-07470RL|Name=Part Number
|RECORD=41|OwnerIndex=1698|IndexInSheet=7|OwnerPartId=-1|Location.X=1277|Location.Y=737|Color=8388608|FontID=1|IsHidden=T|Text=Yageo / Phycomp|Name=Manufacturer
|RECORD=34|OwnerIndex=1698|IndexInSheet=-1|OwnerPartId=-1|Location.X=1283|Location.Y=716|Color=8388608|FontID=1|Text=R63|Name=Designator|ReadOnlyState=1
|RECORD=41|OwnerIndex=1698|IndexInSheet=-1|OwnerPartId=-1|Location.X=1283|Location.Y=706|Color=8388608|FontID=1|Text=470_1%_0402|Name=Comment
|RECORD=44|OwnerIndex=1698
|RECORD=45|OwnerIndex=1713|IndexInSheet=-1|Description=Chip Resistor, 2-Leads, Body 1.00x0.50mm, IPC Low Density|UseComponentLibrary=T|ModelName=RESC1005X40X25ML05T10|ModelType=PCBLIB|DatafileCount=1|ModelDatafileEntity0=RESC1005X40X25ML05T10|ModelDatafileKind0=PCBLib|IsCurrent=T|DatalinksLocked=T|DatabaseDatalinksLocked=T
|RECORD=46|OwnerIndex=1714
|RECORD=48|OwnerIndex=1714
|RECORD=41|OwnerIndex=1716|IndexInSheet=-1|OwnerPartId=-1|Color=8388608|FontID=1|IsHidden=T|Text=2D|Name=Available Preview Images
|RECORD=45|OwnerIndex=1713|IndexInSheet=-1|Description=Chip Resistor, 2-Leads, Body 1.00x0.50mm, IPC Medium Density|UseComponentLibrary=T|ModelName=RESC1005X40X25NL05T10|ModelType=PCBLIB|DatafileCount=1|ModelDatafileEntity0=RESC1005X40X25NL05T10|ModelDatafileKind0=PCBLib|DatalinksLocked=T|DatabaseDatalinksLocked=T
|RECORD=46|OwnerIndex=1718
|RECORD=48|OwnerIndex=1718
|RECORD=41|OwnerIndex=1720|IndexInSheet=-1|OwnerPartId=-1|Color=8388608|FontID=1|IsHidden=T|Text=2D|Name=Available Preview Images
|RECORD=45|OwnerIndex=1713|IndexInSheet=-1|Description=Chip Resistor, 2-Leads, Body 1.00x0.50mm, IPC High Density|UseComponentLibrary=T|ModelName=RESC1005X40X25LL05T10|ModelType=PCBLIB|DatafileCount=1|ModelDatafileEntity0=RESC1005X40X25LL05T10|ModelDatafileKind0=PCBLib|DatalinksLocked=T|DatabaseDatalinksLocked=T
|RECORD=46|OwnerIndex=1722
|RECORD=48|OwnerIndex=1722
|RECORD=41|OwnerIndex=1724|IndexInSheet=-1|OwnerPartId=-1|Color=8388608|FontID=1|IsHidden=T|Text=2D|Name=Available Preview Images
|RECORD=17|IndexInSheet=103|OwnerPartId=-1|Style=4|ShowNetName=T|Location.X=1280|Location.Y=690|Orientation=3|Color=128|FontID=1|Text=GND
|RECORD=17|IndexInSheet=104|OwnerPartId=-1|ShowNetName=T|Location.X=1280|Location.Y=910|Orientation=1|Color=128|FontID=1|Text=P5V_SENSE
|RECORD=1|LibReference=RES|PartCount=2|DisplayModeCount=2|IndexInSheet=105|OwnerPartId=-1|Location.X=1305|Location.Y=905|CurrentPartId=1|SourceLibraryName=Altium Content Vault|TargetFileName=*|AreaColor=11599871|Color=128|PartIDLocked=F|DesignItemId=CMP-2003-04334-1|AllPinCount=2
|RECORD=2|OwnerIndex=1728|OwnerPartId=1|OwnerPartDisplayMode=1|FormalType=1|Electrical=4|PinConglomerate=32|PinLength=10|Location.X=1325|Location.Y=895|Name=2|Designator=2|PinPropagationDelay=0.000000E+000
|RECORD=2|OwnerIndex=1728|OwnerPartId=1|OwnerPartDisplayMode=1|FormalType=1|Electrical=4|PinConglomerate=34|PinLength=10|Location.X=1305|Location.Y=895|Name=1|Designator=1|PinPropagationDelay=0.000000E+000
|RECORD=14|OwnerIndex=1728|IsNotAccesible=T|IndexInSheet=2|OwnerPartId=1|OwnerPartDisplayMode=1|Location.X=1305|Location.Y=891|Corner.X=1325|Corner.Y=899|LineWidth=1|Color=16711680|AreaColor=11599871
|RECORD=2|OwnerIndex=1728|OwnerPartId=1|FormalType=1|Electrical=4|PinConglomerate=32|PinLength=10|Location.X=1325|Location.Y=895|Name=2|Designator=2|PinPropagationDelay=0.000000E+000
|RECORD=2|OwnerIndex=1728|OwnerPartId=1|FormalType=1|Electrical=4|PinConglomerate=34|PinLength=10|Location.X=1305|Location.Y=895|Name=1|Designator=1|PinPropagationDelay=0.000000E+000
|RECORD=6|OwnerIndex=1728|IsNotAccesible=T|IndexInSheet=5|OwnerPartId=1|LineWidth=1|Color=16711680|LocationCount=10|X1=1325|Y1=895|X2=1321|Y2=895|X3=1320|Y3=893|X4=1318|Y4=897|X5=1316|Y5=893|X6=1314|Y6=897|X7=1312|Y7=893|X8=1310|Y8=897|X9=1309|Y9=895|X10=1305|Y10=895
|RECORD=41|OwnerIndex=1728|IndexInSheet=6|OwnerPartId=-1|Location.X=1293|Location.Y=908|Color=8388608|FontID=1|IsHidden=T|Text=Vishay Dale|Name=Manufacturer
|RECORD=41|OwnerIndex=1728|IndexInSheet=7|OwnerPartId=-1|Location.X=1293|Location.Y=908|Color=8388608|FontID=1|IsHidden=T|Text=WSL12062L000FEA18|Name=Part Number
|RECORD=34|OwnerIndex=1728|IndexInSheet=-1|OwnerPartId=-1|Location.X=1304|Location.Y=898|Color=8388608|FontID=1|Text=R8|Name=Designator|ReadOnlyState=1
|RECORD=41|OwnerIndex=1728|IndexInSheet=-1|OwnerPartId=-1|Location.X=1304|Location.Y=882|Color=8388608|FontID=1|Text=2mOhm_1%_1206|Name=Comment
|RECORD=44|OwnerIndex=1728
|RECORD=45|OwnerIndex=1743|IndexInSheet=-1|Description=Chip Resistor, 2-Leads, Body 3.20x1.60mm, IPC Medium Density|UseComponentLibrary=T|ModelName=RESC3216X89X64NL25T25|ModelType=PCBLIB|DatafileCount=1|ModelDatafileEntity0=RESC3216X89X64NL25T25|ModelDatafileKind0=PCBLib|IsCurrent=T|DatalinksLocked=T|DatabaseDatalinksLocked=T
|RECORD=46|OwnerIndex=1744
|RECORD=48|OwnerIndex=1744
|RECORD=41|OwnerIndex=1746|IndexInSheet=-1|OwnerPartId=-1|Color=8388608|FontID=1|IsHidden=T|Text=2D|Name=Available Preview Images
|RECORD=45|OwnerIndex=1743|IndexInSheet=-1|Description=Chip Resistor, 2-Leads, Body 3.20x1.60mm, IPC High Density|UseComponentLibrary=T|ModelName=RESC3216X89X64LL25T25|ModelType=PCBLIB|DatafileCount=1|ModelDatafileEntity0=RESC3216X89X64LL25T25|ModelDatafileKind0=PCBLib|DatalinksLocked=T|DatabaseDatalinksLocked=T
|RECORD=46|OwnerIndex=1748
|RECORD=48|OwnerIndex=1748
|RECORD=41|OwnerIndex=1750|IndexInSheet=-1|OwnerPartId=-1|Color=8388608|FontID=1|IsHidden=T|Text=2D|Name=Available Preview Images
|RECORD=45|OwnerIndex=1743|IndexInSheet=-1|Description=Chip Resistor, 2-Leads, Body 3.20x1.60mm, IPC Low Density|UseComponentLibrary=T|ModelName=RESC3216X89X64ML25T25|ModelType=PCBLIB|DatafileCount=1|ModelDatafileEntity0=RESC3216X89X64ML25T25|ModelDatafileKind0=PCBLib|DatalinksLocked=T|DatabaseDatalinksLocked=T
|RECORD=46|OwnerIndex=1752
|RECORD=48|OwnerIndex=1752
|RECORD=41|OwnerIndex=1754|IndexInSheet=-1|OwnerPartId=-1|Color=8388608|FontID=1|IsHidden=T|Text=2D|Name=Available Preview Images
|RECORD=1|LibReference=b4654b650e69147ec39a6b967a45e02|ComponentDescription=Multilayer Ceramic Capacitor 10uF 16V X5R 20% SMD 0603 T/R|PartCount=2|DisplayModeCount=1|IndexInSheet=106|OwnerPartId=-1|Location.X=1430|Location.Y=755|CurrentPartId=1|LibraryPath=*|SourceLibraryName=Altium Content Vault|TargetFileName=*|AreaColor=11599871|Color=128|PartIDLocked=T|DesignItemId=CMP-2000-06226-4|AllPinCount=2
|RECORD=2|OwnerIndex=1756|OwnerPartId=1|Electrical=4|PinConglomerate=49|PinLength=7|Location.X=1430|Location.Y=748|Name=1|Designator=1|PinPropagationDelay=0.000000E+000
|RECORD=2|OwnerIndex=1756|OwnerPartId=1|Electrical=4|PinConglomerate=51|PinLength=6|Location.X=1430|Location.Y=741|Name=2|Designator=2|PinPropagationDelay=0.000000E+000
|RECORD=13|OwnerIndex=1756|IsNotAccesible=T|IndexInSheet=2|OwnerPartId=1|Location.X=1440|Location.Y=748|Corner.X=1420|Corner.Y=748|LineWidth=1|Color=16711680
|RECORD=13|OwnerIndex=1756|IsNotAccesible=T|IndexInSheet=3|OwnerPartId=1|Location.X=1440|Location.Y=742|Corner.X=1420|Corner.Y=742|LineWidth=1|Color=16711680
|RECORD=13|OwnerIndex=1756|IsNotAccesible=T|IndexInSheet=4|OwnerPartId=1|Location.X=1430|Location.Y=748|Corner.X=1430|Corner.Y=751|LineWidth=1|Color=16711680
|RECORD=13|OwnerIndex=1756|IsNotAccesible=T|IndexInSheet=5|OwnerPartId=1|Location.X=1430|Location.Y=741|Corner.X=1430|Corner.Y=740|LineWidth=1|Color=16711680
|RECORD=41|OwnerIndex=1756|IndexInSheet=6|OwnerPartId=-1|Location.X=1419|Location.Y=757|Color=8388608|FontID=1|IsHidden=T|Text=Tape and Reel|Name=Packaging
|RECORD=41|OwnerIndex=1756|IndexInSheet=7|OwnerPartId=-1|Location.X=1419|Location.Y=757|Color=8388608|FontID=1|IsHidden=T|Text=Flat|Name=Construction
|RECORD=41|OwnerIndex=1756|IndexInSheet=8|OwnerPartId=-1|Location.X=1419|Location.Y=757|Color=8388608|FontID=1|IsHidden=T|Text=0.8mm|Name=Height
|RECORD=41|OwnerIndex=1756|IndexInSheet=9|OwnerPartId=-1|Location.X=1419|Location.Y=757|Color=8388608|FontID=1|IsHidden=T|Text=85°C|Name=Max Operating Temperature
|RECORD=41|OwnerIndex=1756|IndexInSheet=10|OwnerPartId=-1|Location.X=1419|Location.Y=757|Color=8388608|FontID=1|IsHidden=T|Text=X5R|Name=Dielectric
|RECORD=41|OwnerIndex=1756|IndexInSheet=11|OwnerPartId=-1|Location.X=1419|Location.Y=757|Color=8388608|FontID=1|IsHidden=T|Text=1608|Name=Case Code (Metric)
|RECORD=41|OwnerIndex=1756|IndexInSheet=12|OwnerPartId=-1|Location.X=1419|Location.Y=757|Color=8388608|FontID=1|IsHidden=T|Text=16V|Name=Voltage Rating (DC)
|RECORD=41|OwnerIndex=1756|IndexInSheet=13|OwnerPartId=-1|Location.X=1419|Location.Y=757|Color=8388608|FontID=1|IsHidden=T|Text=0.031inch|Name=Width
|RECORD=41|OwnerIndex=1756|IndexInSheet=14|OwnerPartId=-1|Location.X=1419|Location.Y=757|Color=8388608|FontID=1|IsHidden=T|Text=16V|Name=Voltage Rating
|RECORD=41|OwnerIndex=1756|IndexInSheet=15|OwnerPartId=-1|Location.X=1419|Location.Y=757|Color=8388608|FontID=1|IsHidden=T|Text=0.063inch|Name=Length
|RECORD=41|OwnerIndex=1756|IndexInSheet=16|OwnerPartId=-1|Location.X=1419|Location.Y=757|Color=8388608|FontID=1|IsHidden=T|Text=Yes|Name=RoHS Compliant
|RECORD=41|OwnerIndex=1756|IndexInSheet=17|OwnerPartId=-1|Location.X=1419|Location.Y=757|Color=8388608|FontID=1|IsHidden=T|Text=Halogen Free|Name=Halogen Free
|RECORD=41|OwnerIndex=1756|IndexInSheet=18|OwnerPartId=-1|Location.X=1419|Location.Y=757|Color=8388608|FontID=1|IsHidden=T|Text=0603|Name=Case Code (Imperial)
|RECORD=41|OwnerIndex=1756|IndexInSheet=19|OwnerPartId=-1|Location.X=1419|Location.Y=757|Color=8388608|FontID=1|IsHidden=T|Text=10uF|Name=Capacitance
|RECORD=41|OwnerIndex=1756|IndexInSheet=20|OwnerPartId=-1|Location.X=1419|Location.Y=757|Color=8388608|FontID=1|IsHidden=T|Text=Surface Mount|Name=Mount
|RECORD=41|OwnerIndex=1756|IndexInSheet=21|OwnerPartId=-1|Location.X=1419|Location.Y=757|Color=8388608|FontID=1|IsHidden=T|Text=0.031inch|Name=Thickness
|RECORD=41|OwnerIndex=1756|IndexInSheet=22|OwnerPartId=-1|Location.X=1419|Location.Y=757|Color=8388608|FontID=1|IsHidden=T|Text=20%|Name=Tolerance
|RECORD=41|OwnerIndex=1756|IndexInSheet=23|OwnerPartId=-1|Location.X=1419|Location.Y=757|Color=8388608|FontID=1|IsHidden=T|Text=-55°C|Name=Min Operating Temperature
|RECORD=41|OwnerIndex=1756|IndexInSheet=24|OwnerPartId=-1|Location.X=1419|Location.Y=757|Color=8388608|FontID=1|IsHidden=T|Text=M|Name=Series
|RECORD=41|OwnerIndex=1756|IndexInSheet=25|OwnerPartId=-1|Location.X=1419|Location.Y=757|Color=8388608|FontID=1|IsHidden=T|Text=SMD/SMT|Name=Termination
|RECORD=41|OwnerIndex=1756|IndexInSheet=26|OwnerPartId=-1|Location.X=1419|Location.Y=757|Color=8388608|FontID=1|IsHidden=T|Text=0603|Name=Case/Package
|RECORD=41|OwnerIndex=1756|IndexInSheet=27|OwnerPartId=-1|Location.X=1419|Location.Y=757|Color=8388608|FontID=1|IsHidden=T|Text=1|Name=Package Quantity
|RECORD=34|OwnerIndex=1756|IndexInSheet=-1|OwnerPartId=-1|Location.X=1420|Location.Y=735|Orientation=1|Color=8388608|FontID=2|Text=C15|Name=Designator|ReadOnlyState=1
|RECORD=41|OwnerIndex=1756|IndexInSheet=-1|OwnerPartId=1|Location.X=1450|Location.Y=720|Orientation=1|Color=8388608|FontID=2|Text=10uF_16V_0603|Name=Comment
|RECORD=44|OwnerIndex=1756
|RECORD=45|OwnerIndex=1789|IndexInSheet=-1|UseComponentLibrary=T|ModelName=FP-0603-L_1_6_0_2-W_0_8_0-MFG|ModelType=PCBLIB|DatafileCount=1|ModelDatafileEntity0=FP-0603-L_1_6_0_2-W_0_8_0-MFG|ModelDatafileKind0=PCBLib|IsCurrent=T|DatalinksLocked=T|DatabaseDatalinksLocked=T
|RECORD=46|OwnerIndex=1790
|RECORD=48|OwnerIndex=1790
|RECORD=45|OwnerIndex=1789|IndexInSheet=-1|UseComponentLibrary=T|ModelName=FP-0603-L_1_6_0_2-W_0_8_0-IPC_B|ModelType=PCBLIB|DatafileCount=1|ModelDatafileEntity0=FP-0603-L_1_6_0_2-W_0_8_0-IPC_B|ModelDatafileKind0=PCBLib|DatalinksLocked=T|DatabaseDatalinksLocked=T
|RECORD=46|OwnerIndex=1793
|RECORD=48|OwnerIndex=1793
|RECORD=45|OwnerIndex=1789|IndexInSheet=-1|UseComponentLibrary=T|ModelName=FP-0603-L_1_6_0_2-W_0_8_0-IPC_C|ModelType=PCBLIB|DatafileCount=1|ModelDatafileEntity0=FP-0603-L_1_6_0_2-W_0_8_0-IPC_C|ModelDatafileKind0=PCBLib|DatalinksLocked=T|DatabaseDatalinksLocked=T
|RECORD=46|OwnerIndex=1796
|RECORD=48|OwnerIndex=1796
|RECORD=45|OwnerIndex=1789|IndexInSheet=-1|UseComponentLibrary=T|ModelName=FP-0603-L_1_6_0_2-W_0_8_0-IPC_A|ModelType=PCBLIB|DatafileCount=1|ModelDatafileEntity0=FP-0603-L_1_6_0_2-W_0_8_0-IPC_A|ModelDatafileKind0=PCBLib|DatalinksLocked=T|DatabaseDatalinksLocked=T
|RECORD=46|OwnerIndex=1799
|RECORD=48|OwnerIndex=1799
|RECORD=1|LibReference=a00bbbee19879c290e62620ae7e47b1|ComponentDescription=CAP TANT 100UF 10% 16V 2917|PartCount=2|DisplayModeCount=1|IndexInSheet=107|OwnerPartId=-1|Location.X=1345|Location.Y=755|CurrentPartId=1|LibraryPath=*|SourceLibraryName=Altium Content Vault|TargetFileName=*|AreaColor=11599871|Color=128|PartIDLocked=T|DesignItemId=CMP-2000-07207-2|AllPinCount=2
|RECORD=2|OwnerIndex=1802|OwnerPartId=1|Electrical=4|PinConglomerate=51|PinLength=8|Location.X=1345|Location.Y=743|Name=C|Designator=1|PinPropagationDelay=0.000000E+000
|RECORD=2|OwnerIndex=1802|OwnerPartId=1|Electrical=4|PinConglomerate=49|PinLength=8|Location.X=1345|Location.Y=747|Name=A|Designator=2|PinPropagationDelay=0.000000E+000
|RECORD=5|OwnerIndex=1802|IsNotAccesible=T|IndexInSheet=2|OwnerPartId=1|LineWidth=1|Color=16711680|LocationCount=4|X1=1335|Y1=739|X2=1340|Y2=745|X3=1350|Y3=745|X4=1355|Y4=739
|RECORD=13|OwnerIndex=1802|IsNotAccesible=T|IndexInSheet=3|OwnerPartId=1|Location.X=1335|Location.Y=747|Corner.X=1355|Corner.Y=747|LineWidth=1|Color=16711680
|RECORD=13|OwnerIndex=1802|IsNotAccesible=T|IndexInSheet=4|OwnerPartId=1|Location.X=1345|Location.Y=743|Corner.X=1345|Corner.Y=741|LineWidth=1|Color=16711680
|RECORD=13|OwnerIndex=1802|IsNotAccesible=T|IndexInSheet=5|OwnerPartId=1|Location.X=1345|Location.Y=747|Corner.X=1345|Corner.Y=750|LineWidth=1|Color=16711680
|RECORD=4|OwnerIndex=1802|IsNotAccesible=T|IndexInSheet=6|OwnerPartId=1|Location.X=1334|Location.Y=757|Justification=6|Color=8388608|FontID=1|Text=+
|RECORD=41|OwnerIndex=1802|IndexInSheet=7|OwnerPartId=-1|Location.X=1334|Location.Y=757|Color=8388608|FontID=1|IsHidden=T|Text=100uF|Name=Capacitance
|RECORD=41|OwnerIndex=1802|IndexInSheet=8|OwnerPartId=-1|Location.X=1334|Location.Y=757|Color=8388608|FontID=1|IsHidden=T|Text=No|Name=Radiation Hardening
|RECORD=41|OwnerIndex=1802|IndexInSheet=9|OwnerPartId=-1|Location.X=1334|Location.Y=757|Color=8388608|FontID=1|IsHidden=T|Text=Yes|Name=RoHS Compliant
|RECORD=41|OwnerIndex=1802|IndexInSheet=10|OwnerPartId=-1|Location.X=1334|Location.Y=757|Color=8388608|FontID=1|IsHidden=T|Text=7.3mm|Name=Length
|RECORD=41|OwnerIndex=1802|IndexInSheet=11|OwnerPartId=-1|Location.X=1334|Location.Y=757|Color=8388608|FontID=1|IsHidden=T|Text=General Purpose|Name=Features
|RECORD=41|OwnerIndex=1802|IndexInSheet=12|OwnerPartId=-1|Location.X=1334|Location.Y=757|Color=8388608|FontID=1|IsHidden=T|Text=Tape and Reel|Name=Packaging
|RECORD=41|OwnerIndex=1802|IndexInSheet=13|OwnerPartId=-1|Location.X=1334|Location.Y=757|Color=8388608|FontID=1|IsHidden=T|Text=1|Name=Package Quantity
|RECORD=41|OwnerIndex=1802|IndexInSheet=14|OwnerPartId=-1|Location.X=1334|Location.Y=757|Color=8388608|FontID=1|IsHidden=T|Text=0.023634oz|Name=Weight
|RECORD=41|OwnerIndex=1802|IndexInSheet=15|OwnerPartId=-1|Location.X=1334|Location.Y=757|Color=8388608|FontID=1|IsHidden=T|Text=2000Hour|Name=Life (Hours)
|RECORD=41|OwnerIndex=1802|IndexInSheet=16|OwnerPartId=-1|Location.X=1334|Location.Y=757|Color=8388608|FontID=1|IsHidden=T|Text=16V|Name=Voltage Rating
|RECORD=41|OwnerIndex=1802|IndexInSheet=17|OwnerPartId=-1|Location.X=1334|Location.Y=757|Color=8388608|FontID=1|IsHidden=T|Text=0.169inch|Name=Width
|RECORD=41|OwnerIndex=1802|IndexInSheet=18|OwnerPartId=-1|Location.X=1334|Location.Y=757|Color=8388608|FontID=1|IsHidden=T|Text=2917|Name=Case/Package
|RECORD=41|OwnerIndex=1802|IndexInSheet=19|OwnerPartId=-1|Location.X=1334|Location.Y=757|Color=8388608|FontID=1|IsHidden=T|Text=125mR|Name=ESR (Equivalent Series Resistance)
|RECORD=41|OwnerIndex=1802|IndexInSheet=20|OwnerPartId=-1|Location.X=1334|Location.Y=757|Color=8388608|FontID=1|IsHidden=T|Text=Surface Mount|Name=Mount
|RECORD=41|OwnerIndex=1802|IndexInSheet=21|OwnerPartId=-1|Location.X=1334|Location.Y=757|Color=8388608|FontID=1|IsHidden=T|Text=16V|Name=Voltage
|RECORD=41|OwnerIndex=1802|IndexInSheet=22|OwnerPartId=-1|Location.X=1334|Location.Y=757|Color=8388608|FontID=1|IsHidden=T|Text=-55°C|Name=Min Operating Temperature
|RECORD=41|OwnerIndex=1802|IndexInSheet=23|OwnerPartId=-1|Location.X=1334|Location.Y=757|Color=8388608|FontID=1|IsHidden=T|Text=10%|Name=Tolerance
|RECORD=41|OwnerIndex=1802|IndexInSheet=24|OwnerPartId=-1|Location.X=1334|Location.Y=757|Color=8388608|FontID=1|IsHidden=T|Text=No SVHC|Name=REACH SVHC
|RECORD=41|OwnerIndex=1802|IndexInSheet=25|OwnerPartId=-1|Location.X=1334|Location.Y=757|Color=8388608|FontID=1|IsHidden=T|Text=0.122inch|Name=Height - Seated (Max)
|RECORD=41|OwnerIndex=1802|IndexInSheet=26|OwnerPartId=-1|Location.X=1334|Location.Y=757|Color=8388608|FontID=1|IsHidden=T|Text=2|Name=Number of Pins
|RECORD=41|OwnerIndex=1802|IndexInSheet=27|OwnerPartId=-1|Location.X=1334|Location.Y=757|Color=8388608|FontID=1|IsHidden=T|Text=Flat|Name=Construction
|RECORD=41|OwnerIndex=1802|IndexInSheet=28|OwnerPartId=-1|Location.X=1334|Location.Y=757|Color=8388608|FontID=1|IsHidden=T|Text=4.3mm|Name=Depth
|RECORD=41|OwnerIndex=1802|IndexInSheet=29|OwnerPartId=-1|Location.X=1334|Location.Y=757|Color=8388608|FontID=1|IsHidden=T|Text=T495|Name=Series
|RECORD=41|OwnerIndex=1802|IndexInSheet=30|OwnerPartId=-1|Location.X=1334|Location.Y=757|Color=8388608|FontID=1|IsHidden=T|Text=125°C|Name=Max Operating Temperature
|RECORD=41|OwnerIndex=1802|IndexInSheet=31|OwnerPartId=-1|Location.X=1334|Location.Y=757|Color=8388608|FontID=1|IsHidden=T|Text=0.001%|Name=Failure Rate
|RECORD=41|OwnerIndex=1802|IndexInSheet=32|OwnerPartId=-1|Location.X=1334|Location.Y=757|Color=8388608|FontID=1|IsHidden=T|Text=SMD/SMT|Name=Termination
|RECORD=41|OwnerIndex=1802|IndexInSheet=33|OwnerPartId=-1|Location.X=1334|Location.Y=757|Color=8388608|FontID=1|IsHidden=T|Text=Polar|Name=Polarity
|RECORD=41|OwnerIndex=1802|IndexInSheet=34|OwnerPartId=-1|Location.X=1334|Location.Y=757|Color=8388608|FontID=1|IsHidden=T|Text=16V|Name=Voltage Rating (DC)
|RECORD=41|OwnerIndex=1802|IndexInSheet=35|OwnerPartId=-1|Location.X=1334|Location.Y=757|Color=8388608|FontID=1|IsHidden=T|Text=Tantalum|Name=Dielectric Material
|RECORD=41|OwnerIndex=1802|IndexInSheet=36|OwnerPartId=-1|Location.X=1334|Location.Y=757|Color=8388608|FontID=1|IsHidden=T|Text=2917|Name=Case Code (Imperial)
|RECORD=41|OwnerIndex=1802|IndexInSheet=37|OwnerPartId=-1|Location.X=1334|Location.Y=757|Color=8388608|FontID=1|IsHidden=T|Text=7343|Name=Case Code (Metric)
|RECORD=41|OwnerIndex=1802|IndexInSheet=38|OwnerPartId=-1|Location.X=1334|Location.Y=757|Color=8388608|FontID=1|IsHidden=T|Text=2.8mm|Name=Height
|RECORD=41|OwnerIndex=1802|IndexInSheet=39|OwnerPartId=-1|Location.X=1334|Location.Y=757|Color=8388608|FontID=1|IsHidden=T|Text=8%|Name=Dissipation Factor
|RECORD=34|OwnerIndex=1802|IndexInSheet=-1|OwnerPartId=-1|Location.X=1330|Location.Y=735|Orientation=1|Color=8388608|FontID=2|Text=C14|Name=Designator|ReadOnlyState=1
|RECORD=41|OwnerIndex=1802|IndexInSheet=-1|OwnerPartId=1|Location.X=1370|Location.Y=715|Orientation=1|Color=8388608|FontID=2|Text=100uF_16V_2917|Name=Comment
|RECORD=44|OwnerIndex=1802
|RECORD=45|OwnerIndex=1847|IndexInSheet=-1|UseComponentLibrary=T|ModelName=FP-T495D107K016ATE125-MFG|ModelType=PCBLIB|DatafileCount=1|ModelDatafileEntity0=FP-T495D107K016ATE125-MFG|ModelDatafileKind0=PCBLib|IsCurrent=T|DatalinksLocked=T|DatabaseDatalinksLocked=T
|RECORD=46|OwnerIndex=1848
|RECORD=48|OwnerIndex=1848
|RECORD=1|LibReference=b4654b650e69147ec39a6b967a45e02|ComponentDescription=Multilayer Ceramic Capacitors 2.2µF ±10% 16V X5R SMD 0402|PartCount=2|DisplayModeCount=1|IndexInSheet=108|OwnerPartId=-1|Location.X=1475|Location.Y=755|CurrentPartId=1|LibraryPath=*|SourceLibraryName=Altium Content Vault|TargetFileName=*|AreaColor=11599871|Color=128|PartIDLocked=T|DesignItemId=CMP-2000-05998-2|AllPinCount=2
|RECORD=2|OwnerIndex=1851|OwnerPartId=1|Electrical=4|PinConglomerate=49|PinLength=7|Location.X=1475|Location.Y=748|Name=1|Designator=1|PinPropagationDelay=0.000000E+000
|RECORD=2|OwnerIndex=1851|OwnerPartId=1|Electrical=4|PinConglomerate=51|PinLength=6|Location.X=1475|Location.Y=741|Name=2|Designator=2|PinPropagationDelay=0.000000E+000
|RECORD=13|OwnerIndex=1851|IsNotAccesible=T|IndexInSheet=2|OwnerPartId=1|Location.X=1485|Location.Y=748|Corner.X=1465|Corner.Y=748|LineWidth=1|Color=16711680
|RECORD=13|OwnerIndex=1851|IsNotAccesible=T|IndexInSheet=3|OwnerPartId=1|Location.X=1485|Location.Y=742|Corner.X=1465|Corner.Y=742|LineWidth=1|Color=16711680
|RECORD=13|OwnerIndex=1851|IsNotAccesible=T|IndexInSheet=4|OwnerPartId=1|Location.X=1475|Location.Y=748|Corner.X=1475|Corner.Y=751|LineWidth=1|Color=16711680
|RECORD=13|OwnerIndex=1851|IsNotAccesible=T|IndexInSheet=5|OwnerPartId=1|Location.X=1475|Location.Y=741|Corner.X=1475|Corner.Y=740|LineWidth=1|Color=16711680
|RECORD=41|OwnerIndex=1851|IndexInSheet=6|OwnerPartId=-1|Location.X=1464|Location.Y=757|Color=8388608|FontID=1|IsHidden=T|Text=No SVHC|Name=REACH SVHC
|RECORD=41|OwnerIndex=1851|IndexInSheet=7|OwnerPartId=-1|Location.X=1464|Location.Y=757|Color=8388608|FontID=1|IsHidden=T|Text=C|Name=Series
|RECORD=41|OwnerIndex=1851|IndexInSheet=8|OwnerPartId=-1|Location.X=1464|Location.Y=757|Color=8388608|FontID=1|IsHidden=T|Text=SMD/SMT|Name=Termination
|RECORD=41|OwnerIndex=1851|IndexInSheet=9|OwnerPartId=-1|Location.X=1464|Location.Y=757|Color=8388608|FontID=1|IsHidden=T|Text=0402|Name=Case Code (Imperial)
|RECORD=41|OwnerIndex=1851|IndexInSheet=10|OwnerPartId=-1|Location.X=1464|Location.Y=757|Color=8388608|FontID=1|IsHidden=T|Text=0.5mm|Name=Depth
|RECORD=41|OwnerIndex=1851|IndexInSheet=11|OwnerPartId=-1|Location.X=1464|Location.Y=757|Color=8388608|FontID=1|IsHidden=T|Text=Surface Mount|Name=Mount
|RECORD=41|OwnerIndex=1851|IndexInSheet=12|OwnerPartId=-1|Location.X=1464|Location.Y=757|Color=8388608|FontID=1|IsHidden=T|Text=0.02inch|Name=Width
|RECORD=41|OwnerIndex=1851|IndexInSheet=13|OwnerPartId=-1|Location.X=1464|Location.Y=757|Color=8388608|FontID=1|IsHidden=T|Text=1|Name=Package Quantity
|RECORD=41|OwnerIndex=1851|IndexInSheet=14|OwnerPartId=-1|Location.X=1464|Location.Y=757|Color=8388608|FontID=1|IsHidden=T|Text=Ceramic|Name=Dielectric Material
|RECORD=41|OwnerIndex=1851|IndexInSheet=15|OwnerPartId=-1|Location.X=1464|Location.Y=757|Color=8388608|FontID=1|IsHidden=T|Text=1mm|Name=Length
|RECORD=41|OwnerIndex=1851|IndexInSheet=16|OwnerPartId=-1|Location.X=1464|Location.Y=757|Color=8388608|FontID=1|IsHidden=T|Text=Tape and Reel|Name=Packaging
|RECORD=41|OwnerIndex=1851|IndexInSheet=17|OwnerPartId=-1|Location.X=1464|Location.Y=757|Color=8388608|FontID=1|IsHidden=T|Text=1005|Name=Case Code (Metric)
|RECORD=41|OwnerIndex=1851|IndexInSheet=18|OwnerPartId=-1|Location.X=1464|Location.Y=757|Color=8388608|FontID=1|IsHidden=T|Text=Yes|Name=RoHS Compliant
|RECORD=41|OwnerIndex=1851|IndexInSheet=19|OwnerPartId=-1|Location.X=1464|Location.Y=757|Color=8388608|FontID=1|IsHidden=T|Text=X5R|Name=Dielectric
|RECORD=41|OwnerIndex=1851|IndexInSheet=20|OwnerPartId=-1|Location.X=1464|Location.Y=757|Color=8388608|FontID=1|IsHidden=T|Text=85°C|Name=Max Operating Temperature
|RECORD=41|OwnerIndex=1851|IndexInSheet=21|OwnerPartId=-1|Location.X=1464|Location.Y=757|Color=8388608|FontID=1|IsHidden=T|Text=Lead Free|Name=Lead Free
|RECORD=41|OwnerIndex=1851|IndexInSheet=22|OwnerPartId=-1|Location.X=1464|Location.Y=757|Color=8388608|FontID=1|IsHidden=T|Text=2.3E-05oz|Name=Weight
|RECORD=41|OwnerIndex=1851|IndexInSheet=23|OwnerPartId=-1|Location.X=1464|Location.Y=757|Color=8388608|FontID=1|IsHidden=T|Text=0.022inch|Name=Thickness
|RECORD=41|OwnerIndex=1851|IndexInSheet=24|OwnerPartId=-1|Location.X=1464|Location.Y=757|Color=8388608|FontID=1|IsHidden=T|Text=2.2uF|Name=Capacitance
|RECORD=41|OwnerIndex=1851|IndexInSheet=25|OwnerPartId=-1|Location.X=1464|Location.Y=757|Color=8388608|FontID=1|IsHidden=T|Text=16V|Name=Voltage Rating (DC)
|RECORD=41|OwnerIndex=1851|IndexInSheet=26|OwnerPartId=-1|Location.X=1464|Location.Y=757|Color=8388608|FontID=1|IsHidden=T|Text=10%|Name=Tolerance
|RECORD=41|OwnerIndex=1851|IndexInSheet=27|OwnerPartId=-1|Location.X=1464|Location.Y=757|Color=8388608|FontID=1|IsHidden=T|Text=16V|Name=Voltage Rating
|RECORD=41|OwnerIndex=1851|IndexInSheet=28|OwnerPartId=-1|Location.X=1464|Location.Y=757|Color=8388608|FontID=1|IsHidden=T|Text=Ceramic|Name=Resistor Type
|RECORD=41|OwnerIndex=1851|IndexInSheet=29|OwnerPartId=-1|Location.X=1464|Location.Y=757|Color=8388608|FontID=1|IsHidden=T|Text=0.5mm|Name=Height
|RECORD=41|OwnerIndex=1851|IndexInSheet=30|OwnerPartId=-1|Location.X=1464|Location.Y=757|Color=8388608|FontID=1|IsHidden=T|Text=0402|Name=Case/Package
|RECORD=41|OwnerIndex=1851|IndexInSheet=31|OwnerPartId=-1|Location.X=1464|Location.Y=757|Color=8388608|FontID=1|IsHidden=T|Text=-55°C|Name=Min Operating Temperature
|RECORD=34|OwnerIndex=1851|IndexInSheet=-1|OwnerPartId=-1|Location.X=1465|Location.Y=735|Orientation=1|Color=8388608|FontID=2|Text=C16|Name=Designator|ReadOnlyState=1
|RECORD=41|OwnerIndex=1851|IndexInSheet=-1|OwnerPartId=1|Location.X=1495|Location.Y=710|Orientation=1|Color=8388608|FontID=2|Text=2.2uF_16V_0402|Name=Comment
|RECORD=44|OwnerIndex=1851
|RECORD=45|OwnerIndex=1888|IndexInSheet=-1|UseComponentLibrary=T|ModelName=FP-C1005-050-0_05-IPC_A|ModelType=PCBLIB|DatafileCount=1|ModelDatafileEntity0=FP-C1005-050-0_05-IPC_A|ModelDatafileKind0=PCBLib|IsCurrent=T|DatalinksLocked=T|DatabaseDatalinksLocked=T
|RECORD=46|OwnerIndex=1889
|RECORD=48|OwnerIndex=1889
|RECORD=45|OwnerIndex=1888|IndexInSheet=-1|UseComponentLibrary=T|ModelName=FP-C1005-050-0_05-MFG|ModelType=PCBLIB|DatafileCount=1|ModelDatafileEntity0=FP-C1005-050-0_05-MFG|ModelDatafileKind0=PCBLib|DatalinksLocked=T|DatabaseDatalinksLocked=T
|RECORD=46|OwnerIndex=1892
|RECORD=48|OwnerIndex=1892
|RECORD=45|OwnerIndex=1888|IndexInSheet=-1|UseComponentLibrary=T|ModelName=FP-C1005-050-0_05-IPC_C|ModelType=PCBLIB|DatafileCount=1|ModelDatafileEntity0=FP-C1005-050-0_05-IPC_C|ModelDatafileKind0=PCBLib|DatalinksLocked=T|DatabaseDatalinksLocked=T
|RECORD=46|OwnerIndex=1895
|RECORD=48|OwnerIndex=1895
|RECORD=45|OwnerIndex=1888|IndexInSheet=-1|UseComponentLibrary=T|ModelName=FP-C1005-050-0_05-IPC_B|ModelType=PCBLIB|DatafileCount=1|ModelDatafileEntity0=FP-C1005-050-0_05-IPC_B|ModelDatafileKind0=PCBLib|DatalinksLocked=T|DatabaseDatalinksLocked=T
|RECORD=46|OwnerIndex=1898
|RECORD=48|OwnerIndex=1898
|RECORD=1|LibReference=b4654b650e69147ec39a6b967a45e02|ComponentDescription=None|PartCount=2|DisplayModeCount=1|IndexInSheet=109|OwnerPartId=-1|Location.X=1520|Location.Y=755|CurrentPartId=1|LibraryPath=*|SourceLibraryName=Altium Content Vault|TargetFileName=*|AreaColor=11599871|Color=128|PartIDLocked=T|DesignItemId=CMP-14477-000104-2|AllPinCount=2
|RECORD=2|OwnerIndex=1901|OwnerPartId=1|Electrical=4|PinConglomerate=49|PinLength=7|Location.X=1520|Location.Y=748|Name=1|Designator=1|PinPropagationDelay=0.000000E+000
|RECORD=2|OwnerIndex=1901|OwnerPartId=1|Electrical=4|PinConglomerate=51|PinLength=6|Location.X=1520|Location.Y=741|Name=2|Designator=2|PinPropagationDelay=0.000000E+000
|RECORD=13|OwnerIndex=1901|IsNotAccesible=T|IndexInSheet=2|OwnerPartId=1|Location.X=1530|Location.Y=748|Corner.X=1510|Corner.Y=748|LineWidth=1|Color=16711680
|RECORD=13|OwnerIndex=1901|IsNotAccesible=T|IndexInSheet=3|OwnerPartId=1|Location.X=1530|Location.Y=742|Corner.X=1510|Corner.Y=742|LineWidth=1|Color=16711680
|RECORD=13|OwnerIndex=1901|IsNotAccesible=T|IndexInSheet=4|OwnerPartId=1|Location.X=1520|Location.Y=748|Corner.X=1520|Corner.Y=751|LineWidth=1|Color=16711680
|RECORD=13|OwnerIndex=1901|IsNotAccesible=T|IndexInSheet=5|OwnerPartId=1|Location.X=1520|Location.Y=741|Corner.X=1520|Corner.Y=740|LineWidth=1|Color=16711680
|RECORD=41|OwnerIndex=1901|IndexInSheet=6|OwnerPartId=-1|Location.X=1509|Location.Y=757|Color=8388608|FontID=1|IsHidden=T|Text=Tape and Reel|Name=Packaging
|RECORD=41|OwnerIndex=1901|IndexInSheet=7|OwnerPartId=-1|Location.X=1509|Location.Y=757|Color=8388608|FontID=1|IsHidden=T|Text=0.5mm|Name=Depth
|RECORD=41|OwnerIndex=1901|IndexInSheet=8|OwnerPartId=-1|Location.X=1509|Location.Y=757|Color=8388608|FontID=1|IsHidden=T|Text=10%|Name=Tolerance
|RECORD=41|OwnerIndex=1901|IndexInSheet=9|OwnerPartId=-1|Location.X=1509|Location.Y=757|Color=8388608|FontID=1|IsHidden=T|Text=Surface Mount|Name=Mount
|RECORD=41|OwnerIndex=1901|IndexInSheet=10|OwnerPartId=-1|Location.X=1509|Location.Y=757|Color=8388608|FontID=1|IsHidden=T|Text=16V|Name=Voltage Rating
|RECORD=41|OwnerIndex=1901|IndexInSheet=11|OwnerPartId=-1|Location.X=1509|Location.Y=757|Color=8388608|FontID=1|IsHidden=T|Text=0.022inch|Name=Thickness
|RECORD=41|OwnerIndex=1901|IndexInSheet=12|OwnerPartId=-1|Location.X=1509|Location.Y=757|Color=8388608|FontID=1|IsHidden=T|Text=1|Name=Package Quantity
|RECORD=41|OwnerIndex=1901|IndexInSheet=13|OwnerPartId=-1|Location.X=1509|Location.Y=757|Color=8388608|FontID=1|IsHidden=T|Text=-55°C|Name=Min Operating Temperature
|RECORD=41|OwnerIndex=1901|IndexInSheet=14|OwnerPartId=-1|Location.X=1509|Location.Y=757|Color=8388608|FontID=1|IsHidden=T|Text=M|Name=Series
|RECORD=41|OwnerIndex=1901|IndexInSheet=15|OwnerPartId=-1|Location.X=1509|Location.Y=757|Color=8388608|FontID=1|IsHidden=T|Text=16V|Name=Voltage Rating (DC)
|RECORD=41|OwnerIndex=1901|IndexInSheet=16|OwnerPartId=-1|Location.X=1509|Location.Y=757|Color=8388608|FontID=1|IsHidden=T|Text=SMD/SMT|Name=Termination
|RECORD=41|OwnerIndex=1901|IndexInSheet=17|OwnerPartId=-1|Location.X=1509|Location.Y=757|Color=8388608|FontID=1|IsHidden=T|Text=0402|Name=Case/Package
|RECORD=41|OwnerIndex=1901|IndexInSheet=18|OwnerPartId=-1|Location.X=1509|Location.Y=757|Color=8388608|FontID=1|IsHidden=T|Text=X5R|Name=Dielectric
|RECORD=41|OwnerIndex=1901|IndexInSheet=19|OwnerPartId=-1|Location.X=1509|Location.Y=757|Color=8388608|FontID=1|IsHidden=T|Text=2|Name=Number of Pins
|RECORD=41|OwnerIndex=1901|IndexInSheet=20|OwnerPartId=-1|Location.X=1509|Location.Y=757|Color=8388608|FontID=1|IsHidden=T|Text=0402|Name=Case Code (Imperial)
|RECORD=41|OwnerIndex=1901|IndexInSheet=21|OwnerPartId=-1|Location.X=1509|Location.Y=757|Color=8388608|FontID=1|IsHidden=T|Text=1uF|Name=Capacitance
|RECORD=41|OwnerIndex=1901|IndexInSheet=22|OwnerPartId=-1|Location.X=1509|Location.Y=757|Color=8388608|FontID=1|IsHidden=T|Text=1mm|Name=Length
|RECORD=41|OwnerIndex=1901|IndexInSheet=23|OwnerPartId=-1|Location.X=1509|Location.Y=757|Color=8388608|FontID=1|IsHidden=T|Text=Halogen Free|Name=Halogen Free
|RECORD=41|OwnerIndex=1901|IndexInSheet=24|OwnerPartId=-1|Location.X=1509|Location.Y=757|Color=8388608|FontID=1|IsHidden=T|Text=1005|Name=Case Code (Metric)
|RECORD=41|OwnerIndex=1901|IndexInSheet=25|OwnerPartId=-1|Location.X=1509|Location.Y=757|Color=8388608|FontID=1|IsHidden=T|Text=0.02inch|Name=Width
|RECORD=41|OwnerIndex=1901|IndexInSheet=26|OwnerPartId=-1|Location.X=1509|Location.Y=757|Color=8388608|FontID=1|IsHidden=T|Text=Yes|Name=RoHS Compliant
|RECORD=41|OwnerIndex=1901|IndexInSheet=27|OwnerPartId=-1|Location.X=1509|Location.Y=757|Color=8388608|FontID=1|IsHidden=T|Text=No|Name=Radiation Hardening
|RECORD=41|OwnerIndex=1901|IndexInSheet=28|OwnerPartId=-1|Location.X=1509|Location.Y=757|Color=8388608|FontID=1|IsHidden=T|Text=85°C|Name=Max Operating Temperature
|RECORD=41|OwnerIndex=1901|IndexInSheet=29|OwnerPartId=-1|Location.X=1509|Location.Y=757|Color=8388608|FontID=1|IsHidden=T|Text=0.5mm|Name=Height
|RECORD=41|OwnerIndex=1901|IndexInSheet=30|OwnerPartId=-1|Location.X=1509|Location.Y=757|Color=8388608|FontID=1|IsHidden=T|Text=Flat|Name=Construction
|RECORD=34|OwnerIndex=1901|IndexInSheet=-1|OwnerPartId=-1|Location.X=1505|Location.Y=735|Orientation=1|Color=8388608|FontID=2|Text=C17|Name=Designator|ReadOnlyState=1
|RECORD=41|OwnerIndex=1901|IndexInSheet=-1|OwnerPartId=1|Location.X=1540|Location.Y=720|Orientation=1|Color=8388608|FontID=2|Text=1uF_16V_0402|Name=Comment
|RECORD=44|OwnerIndex=1901
|RECORD=45|OwnerIndex=1937|IndexInSheet=-1|UseComponentLibrary=T|ModelName=FP-0402-L_1_0_0_05-W_0_5-IPC_A|ModelType=PCBLIB|DatafileCount=1|ModelDatafileEntity0=FP-0402-L_1_0_0_05-W_0_5-IPC_A|ModelDatafileKind0=PCBLib|IsCurrent=T|DatalinksLocked=T|DatabaseDatalinksLocked=T
|RECORD=46|OwnerIndex=1938
|RECORD=48|OwnerIndex=1938
|RECORD=45|OwnerIndex=1937|IndexInSheet=-1|UseComponentLibrary=T|ModelName=EMK105BJ105_V-F|ModelType=SIM|IsCurrent=T|DatalinksLocked=T|DatabaseDatalinksLocked=T
|RECORD=46|OwnerIndex=1941
|RECORD=48|OwnerIndex=1941
|RECORD=41|OwnerIndex=1943|IndexInSheet=-1|OwnerPartId=-1|Color=8388608|FontID=1|IsHidden=T|Text=General|Name=Kind
|RECORD=41|OwnerIndex=1943|IndexInSheet=-1|OwnerPartId=-1|Color=8388608|FontID=1|IsHidden=T|Text=Spice Subcircuit|Name=SubKind
|RECORD=41|OwnerIndex=1943|IndexInSheet=-1|OwnerPartId=-1|Color=8388608|FontID=1|IsHidden=T|Name=Spice Prefix
|RECORD=41|OwnerIndex=1943|IndexInSheet=-1|OwnerPartId=-1|Color=8388608|FontID=1|IsHidden=T|Name=Excluded Parts
|RECORD=41|OwnerIndex=1943|IndexInSheet=-1|OwnerPartId=-1|Color=8388608|FontID=1|IsHidden=T|Name=Netlist
|RECORD=41|OwnerIndex=1943|IndexInSheet=-1|OwnerPartId=-1|Color=8388608|FontID=1|IsHidden=T|Text=document_sim_cache\GNEMVTBT\0|Name=SimulationCacheLocation|ReadOnlyState=3
|RECORD=45|OwnerIndex=1937|IndexInSheet=-1|UseComponentLibrary=T|ModelName=FP-0402-L_1_0_0_05-W_0_5-IPC_B|ModelType=PCBLIB|DatafileCount=1|ModelDatafileEntity0=FP-0402-L_1_0_0_05-W_0_5-IPC_B|ModelDatafileKind0=PCBLib|DatalinksLocked=T|DatabaseDatalinksLocked=T
|RECORD=46|OwnerIndex=1950
|RECORD=48|OwnerIndex=1950
|RECORD=45|OwnerIndex=1937|IndexInSheet=-1|UseComponentLibrary=T|ModelName=FP-0402-L_1_0_0_05-W_0_5-IPC_C|ModelType=PCBLIB|DatafileCount=1|ModelDatafileEntity0=FP-0402-L_1_0_0_05-W_0_5-IPC_C|ModelDatafileKind0=PCBLib|DatalinksLocked=T|DatabaseDatalinksLocked=T
|RECORD=46|OwnerIndex=1953
|RECORD=48|OwnerIndex=1953
|RECORD=45|OwnerIndex=1937|IndexInSheet=-1|UseComponentLibrary=T|ModelName=FP-0402-L_1_0_0_05-W_0_5-MFG|ModelType=PCBLIB|DatafileCount=1|ModelDatafileEntity0=FP-0402-L_1_0_0_05-W_0_5-MFG|ModelDatafileKind0=PCBLib|DatalinksLocked=T|DatabaseDatalinksLocked=T
|RECORD=46|OwnerIndex=1956
|RECORD=48|OwnerIndex=1956
|RECORD=1|LibReference=b4654b650e69147ec39a6b967a45e02|ComponentDescription=General Purpose Ceramic Capacitor, 0402, 100nF, 10%, X7R, 15%, 25V|PartCount=2|DisplayModeCount=1|IndexInSheet=110|OwnerPartId=-1|Location.X=1560|Location.Y=755|CurrentPartId=1|LibraryPath=*|SourceLibraryName=Altium Content Vault|TargetFileName=*|AreaColor=11599871|Color=128|PartIDLocked=T|DesignItemId=CMP-2008-02519-2|AllPinCount=2
|RECORD=2|OwnerIndex=1959|OwnerPartId=1|Electrical=4|PinConglomerate=49|PinLength=7|Location.X=1560|Location.Y=748|Name=1|Designator=1|PinPropagationDelay=0.000000E+000
|RECORD=2|OwnerIndex=1959|OwnerPartId=1|Electrical=4|PinConglomerate=51|PinLength=6|Location.X=1560|Location.Y=741|Name=2|Designator=2|PinPropagationDelay=0.000000E+000
|RECORD=13|OwnerIndex=1959|IsNotAccesible=T|IndexInSheet=2|OwnerPartId=1|Location.X=1570|Location.Y=748|Corner.X=1550|Corner.Y=748|LineWidth=1|Color=16711680
|RECORD=13|OwnerIndex=1959|IsNotAccesible=T|IndexInSheet=3|OwnerPartId=1|Location.X=1570|Location.Y=742|Corner.X=1550|Corner.Y=742|LineWidth=1|Color=16711680
|RECORD=13|OwnerIndex=1959|IsNotAccesible=T|IndexInSheet=4|OwnerPartId=1|Location.X=1560|Location.Y=748|Corner.X=1560|Corner.Y=751|LineWidth=1|Color=16711680
|RECORD=13|OwnerIndex=1959|IsNotAccesible=T|IndexInSheet=5|OwnerPartId=1|Location.X=1560|Location.Y=741|Corner.X=1560|Corner.Y=740|LineWidth=1|Color=16711680
|RECORD=41|OwnerIndex=1959|IndexInSheet=6|OwnerPartId=-1|Location.X=1549|Location.Y=757|Color=8388608|FontID=1|IsHidden=T|Text=1|Name=Package Quantity
|RECORD=41|OwnerIndex=1959|IndexInSheet=7|OwnerPartId=-1|Location.X=1549|Location.Y=757|Color=8388608|FontID=1|IsHidden=T|Text=100nF|Name=Capacitance
|RECORD=41|OwnerIndex=1959|IndexInSheet=8|OwnerPartId=-1|Location.X=1549|Location.Y=757|Color=8388608|FontID=1|IsHidden=T|Text=-55°C|Name=Min Operating Temperature
|RECORD=41|OwnerIndex=1959|IndexInSheet=9|OwnerPartId=-1|Location.X=1549|Location.Y=757|Color=8388608|FontID=1|IsHidden=T|Text=25V|Name=Voltage
|RECORD=41|OwnerIndex=1959|IndexInSheet=10|OwnerPartId=-1|Location.X=1549|Location.Y=757|Color=8388608|FontID=1|IsHidden=T|Text=25V|Name=Voltage Rating
|RECORD=41|OwnerIndex=1959|IndexInSheet=11|OwnerPartId=-1|Location.X=1549|Location.Y=757|Color=8388608|FontID=1|IsHidden=T|Text=Flat|Name=Construction
|RECORD=41|OwnerIndex=1959|IndexInSheet=12|OwnerPartId=-1|Location.X=1549|Location.Y=757|Color=8388608|FontID=1|IsHidden=T|Text=125°C|Name=Max Operating Temperature
|RECORD=41|OwnerIndex=1959|IndexInSheet=13|OwnerPartId=-1|Location.X=1549|Location.Y=757|Color=8388608|FontID=1|IsHidden=T|Text=No|Name=Radiation Hardening
|RECORD=41|OwnerIndex=1959|IndexInSheet=14|OwnerPartId=-1|Location.X=1549|Location.Y=757|Color=8388608|FontID=1|IsHidden=T|Text=0.5mm|Name=Depth
|RECORD=41|OwnerIndex=1959|IndexInSheet=15|OwnerPartId=-1|Location.X=1549|Location.Y=757|Color=8388608|FontID=1|IsHidden=T|Text=0.022inch|Name=Thickness
|RECORD=41|OwnerIndex=1959|IndexInSheet=16|OwnerPartId=-1|Location.X=1549|Location.Y=757|Color=8388608|FontID=1|IsHidden=T|Text=25V|Name=Voltage Rating (DC)
|RECORD=41|OwnerIndex=1959|IndexInSheet=17|OwnerPartId=-1|Location.X=1549|Location.Y=757|Color=8388608|FontID=1|IsHidden=T|Text=2|Name=Number of Pins
|RECORD=41|OwnerIndex=1959|IndexInSheet=18|OwnerPartId=-1|Location.X=1549|Location.Y=757|Color=8388608|FontID=1|IsHidden=T|Text=Lead Free|Name=Lead Free
|RECORD=41|OwnerIndex=1959|IndexInSheet=19|OwnerPartId=-1|Location.X=1549|Location.Y=757|Color=8388608|FontID=1|IsHidden=T|Text=-|Name=Series
|RECORD=41|OwnerIndex=1959|IndexInSheet=20|OwnerPartId=-1|Location.X=1549|Location.Y=757|Color=8388608|FontID=1|IsHidden=T|Text=No SVHC|Name=REACH SVHC
|RECORD=41|OwnerIndex=1959|IndexInSheet=21|OwnerPartId=-1|Location.X=1549|Location.Y=757|Color=8388608|FontID=1|IsHidden=T|Text=1mm|Name=Length
|RECORD=41|OwnerIndex=1959|IndexInSheet=22|OwnerPartId=-1|Location.X=1549|Location.Y=757|Color=8388608|FontID=1|IsHidden=T|Text=X7R|Name=Dielectric
|RECORD=41|OwnerIndex=1959|IndexInSheet=23|OwnerPartId=-1|Location.X=1549|Location.Y=757|Color=8388608|FontID=1|IsHidden=T|Text=Yes|Name=RoHS Compliant
|RECORD=41|OwnerIndex=1959|IndexInSheet=24|OwnerPartId=-1|Location.X=1549|Location.Y=757|Color=8388608|FontID=1|IsHidden=T|Text=Surface Mount|Name=Mount
|RECORD=41|OwnerIndex=1959|IndexInSheet=25|OwnerPartId=-1|Location.X=1549|Location.Y=757|Color=8388608|FontID=1|IsHidden=T|Text=Tape and Reel|Name=Packaging
|RECORD=41|OwnerIndex=1959|IndexInSheet=26|OwnerPartId=-1|Location.X=1549|Location.Y=757|Color=8388608|FontID=1|IsHidden=T|Text=0402|Name=Case/Package
|RECORD=41|OwnerIndex=1959|IndexInSheet=27|OwnerPartId=-1|Location.X=1549|Location.Y=757|Color=8388608|FontID=1|IsHidden=T|Text=0402|Name=Case Code (Imperial)
|RECORD=41|OwnerIndex=1959|IndexInSheet=28|OwnerPartId=-1|Location.X=1549|Location.Y=757|Color=8388608|FontID=1|IsHidden=T|Text=SMD/SMT|Name=Termination
|RECORD=41|OwnerIndex=1959|IndexInSheet=29|OwnerPartId=-1|Location.X=1549|Location.Y=757|Color=8388608|FontID=1|IsHidden=T|Text=0.02inch|Name=Width
|RECORD=41|OwnerIndex=1959|IndexInSheet=30|OwnerPartId=-1|Location.X=1549|Location.Y=757|Color=8388608|FontID=1|IsHidden=T|Text=1005|Name=Case Code (Metric)
|RECORD=41|OwnerIndex=1959|IndexInSheet=31|OwnerPartId=-1|Location.X=1549|Location.Y=757|Color=8388608|FontID=1|IsHidden=T|Text=10%|Name=Tolerance
|RECORD=34|OwnerIndex=1959|IndexInSheet=-1|OwnerPartId=-1|Location.X=1550|Location.Y=735|Orientation=1|Color=8388608|FontID=2|Text=C18|Name=Designator|ReadOnlyState=1
|RECORD=41|OwnerIndex=1959|IndexInSheet=-1|OwnerPartId=1|Location.X=1580|Location.Y=720|Orientation=1|Color=8388608|FontID=2|Text=0.1uF_25V_0402|Name=Comment
|RECORD=44|OwnerIndex=1959
|RECORD=45|OwnerIndex=1996|IndexInSheet=-1|UseComponentLibrary=T|ModelName=FP-0402-L_1_0_1-W_0_5_0_1-IPC_C|ModelType=PCBLIB|DatafileCount=1|ModelDatafileEntity0=FP-0402-L_1_0_1-W_0_5_0_1-IPC_C|ModelDatafileKind0=PCBLib|IsCurrent=T|DatalinksLocked=T|DatabaseDatalinksLocked=T
|RECORD=46|OwnerIndex=1997
|RECORD=48|OwnerIndex=1997
|RECORD=45|OwnerIndex=1996|IndexInSheet=-1|UseComponentLibrary=T|ModelName=FP-0402-L_1_0_1-W_0_5_0_1-IPC_B|ModelType=PCBLIB|DatafileCount=1|ModelDatafileEntity0=FP-0402-L_1_0_1-W_0_5_0_1-IPC_B|ModelDatafileKind0=PCBLib|DatalinksLocked=T|DatabaseDatalinksLocked=T
|RECORD=46|OwnerIndex=2000
|RECORD=48|OwnerIndex=2000
|RECORD=45|OwnerIndex=1996|IndexInSheet=-1|UseComponentLibrary=T|ModelName=FP-0402-L_1_0_1-W_0_5_0_1-MFG|ModelType=PCBLIB|DatafileCount=1|ModelDatafileEntity0=FP-0402-L_1_0_1-W_0_5_0_1-MFG|ModelDatafileKind0=PCBLib|DatalinksLocked=T|DatabaseDatalinksLocked=T
|RECORD=46|OwnerIndex=2003
|RECORD=48|OwnerIndex=2003
|RECORD=45|OwnerIndex=1996|IndexInSheet=-1|UseComponentLibrary=T|ModelName=FP-0402-L_1_0_1-W_0_5_0_1-IPC_A|ModelType=PCBLIB|DatafileCount=1|ModelDatafileEntity0=FP-0402-L_1_0_1-W_0_5_0_1-IPC_A|ModelDatafileKind0=PCBLib|DatalinksLocked=T|DatabaseDatalinksLocked=T
|RECORD=46|OwnerIndex=2006
|RECORD=48|OwnerIndex=2006
|RECORD=1|LibReference=11868f565c42a9108669ba33697ecf6|ComponentDescription=Multilayer Ceramic Capacitors 47uF ±20% 16V X5R SMD 1206|PartCount=2|DisplayModeCount=1|IndexInSheet=111|OwnerPartId=-1|Location.X=1390|Location.Y=755|CurrentPartId=1|LibraryPath=*|SourceLibraryName=Altium Content Vault|TargetFileName=*|AreaColor=11599871|Color=128|PartIDLocked=T|DesignItemId=CMP-2000-07442-2|AllPinCount=2
|RECORD=2|OwnerIndex=2009|OwnerPartId=1|Electrical=4|PinConglomerate=49|PinLength=7|Location.X=1390|Location.Y=748|Name=1|Designator=1|PinPropagationDelay=0.000000E+000
|RECORD=2|OwnerIndex=2009|OwnerPartId=1|Electrical=4|PinConglomerate=51|PinLength=6|Location.X=1390|Location.Y=741|Name=2|Designator=2|PinPropagationDelay=0.000000E+000
|RECORD=13|OwnerIndex=2009|IsNotAccesible=T|IndexInSheet=2|OwnerPartId=1|Location.X=1400|Location.Y=748|Corner.X=1380|Corner.Y=748|LineWidth=1|Color=16711680
|RECORD=13|OwnerIndex=2009|IsNotAccesible=T|IndexInSheet=3|OwnerPartId=1|Location.X=1400|Location.Y=742|Corner.X=1380|Corner.Y=742|LineWidth=1|Color=16711680
|RECORD=13|OwnerIndex=2009|IsNotAccesible=T|IndexInSheet=4|OwnerPartId=1|Location.X=1390|Location.Y=748|Corner.X=1390|Corner.Y=751|LineWidth=1|Color=16711680
|RECORD=13|OwnerIndex=2009|IsNotAccesible=T|IndexInSheet=5|OwnerPartId=1|Location.X=1390|Location.Y=741|Corner.X=1390|Corner.Y=740|LineWidth=1|Color=16711680
|RECORD=41|OwnerIndex=2009|IndexInSheet=6|OwnerPartId=-1|Location.X=1379|Location.Y=757|Color=8388608|FontID=1|IsHidden=T|Text=Ceramic|Name=Resistor Type
|RECORD=41|OwnerIndex=2009|IndexInSheet=7|OwnerPartId=-1|Location.X=1379|Location.Y=757|Color=8388608|FontID=1|IsHidden=T|Text=0.063inch|Name=Width
|RECORD=41|OwnerIndex=2009|IndexInSheet=8|OwnerPartId=-1|Location.X=1379|Location.Y=757|Color=8388608|FontID=1|IsHidden=T|Text=1206|Name=Case Code (Imperial)
|RECORD=41|OwnerIndex=2009|IndexInSheet=9|OwnerPartId=-1|Location.X=1379|Location.Y=757|Color=8388608|FontID=1|IsHidden=T|Text=No|Name=Radiation Hardening
|RECORD=41|OwnerIndex=2009|IndexInSheet=10|OwnerPartId=-1|Location.X=1379|Location.Y=757|Color=8388608|FontID=1|IsHidden=T|Text=0.071inch|Name=Thickness
|RECORD=41|OwnerIndex=2009|IndexInSheet=11|OwnerPartId=-1|Location.X=1379|Location.Y=757|Color=8388608|FontID=1|IsHidden=T|Text=X5R|Name=Dielectric
|RECORD=41|OwnerIndex=2009|IndexInSheet=12|OwnerPartId=-1|Location.X=1379|Location.Y=757|Color=8388608|FontID=1|IsHidden=T|Text=0.000571oz|Name=Weight
|RECORD=41|OwnerIndex=2009|IndexInSheet=13|OwnerPartId=-1|Location.X=1379|Location.Y=757|Color=8388608|FontID=1|IsHidden=T|Text=SMD/SMT|Name=Termination
|RECORD=41|OwnerIndex=2009|IndexInSheet=14|OwnerPartId=-1|Location.X=1379|Location.Y=757|Color=8388608|FontID=1|IsHidden=T|Text=Ceramic|Name=Dielectric Material
|RECORD=41|OwnerIndex=2009|IndexInSheet=15|OwnerPartId=-1|Location.X=1379|Location.Y=757|Color=8388608|FontID=1|IsHidden=T|Text=-55°C|Name=Min Operating Temperature
|RECORD=41|OwnerIndex=2009|IndexInSheet=16|OwnerPartId=-1|Location.X=1379|Location.Y=757|Color=8388608|FontID=1|IsHidden=T|Text=1.6mm|Name=Depth
|RECORD=41|OwnerIndex=2009|IndexInSheet=17|OwnerPartId=-1|Location.X=1379|Location.Y=757|Color=8388608|FontID=1|IsHidden=T|Text=3216|Name=Case Code (Metric)
|RECORD=41|OwnerIndex=2009|IndexInSheet=18|OwnerPartId=-1|Location.X=1379|Location.Y=757|Color=8388608|FontID=1|IsHidden=T|Text=85°C|Name=Max Operating Temperature
|RECORD=41|OwnerIndex=2009|IndexInSheet=19|OwnerPartId=-1|Location.X=1379|Location.Y=757|Color=8388608|FontID=1|IsHidden=T|Text=Yes|Name=RoHS Compliant
|RECORD=41|OwnerIndex=2009|IndexInSheet=20|OwnerPartId=-1|Location.X=1379|Location.Y=757|Color=8388608|FontID=1|IsHidden=T|Text=No SVHC|Name=REACH SVHC
|RECORD=41|OwnerIndex=2009|IndexInSheet=21|OwnerPartId=-1|Location.X=1379|Location.Y=757|Color=8388608|FontID=1|IsHidden=T|Text=Surface Mount|Name=Mount
|RECORD=41|OwnerIndex=2009|IndexInSheet=22|OwnerPartId=-1|Location.X=1379|Location.Y=757|Color=8388608|FontID=1|IsHidden=T|Text=Lead Free|Name=Lead Free
|RECORD=41|OwnerIndex=2009|IndexInSheet=23|OwnerPartId=-1|Location.X=1379|Location.Y=757|Color=8388608|FontID=1|IsHidden=T|Text=1.6mm|Name=Height
|RECORD=41|OwnerIndex=2009|IndexInSheet=24|OwnerPartId=-1|Location.X=1379|Location.Y=757|Color=8388608|FontID=1|IsHidden=T|Text=3.2mm|Name=Length
|RECORD=41|OwnerIndex=2009|IndexInSheet=25|OwnerPartId=-1|Location.X=1379|Location.Y=757|Color=8388608|FontID=1|IsHidden=T|Text=20%|Name=Tolerance
|RECORD=41|OwnerIndex=2009|IndexInSheet=26|OwnerPartId=-1|Location.X=1379|Location.Y=757|Color=8388608|FontID=1|IsHidden=T|Text=16V|Name=Voltage Rating (DC)
|RECORD=41|OwnerIndex=2009|IndexInSheet=27|OwnerPartId=-1|Location.X=1379|Location.Y=757|Color=8388608|FontID=1|IsHidden=T|Text=47uF|Name=Capacitance
|RECORD=41|OwnerIndex=2009|IndexInSheet=28|OwnerPartId=-1|Location.X=1379|Location.Y=757|Color=8388608|FontID=1|IsHidden=T|Text=1|Name=Package Quantity
|RECORD=41|OwnerIndex=2009|IndexInSheet=29|OwnerPartId=-1|Location.X=1379|Location.Y=757|Color=8388608|FontID=1|IsHidden=T|Text=Flat|Name=Construction
|RECORD=41|OwnerIndex=2009|IndexInSheet=30|OwnerPartId=-1|Location.X=1379|Location.Y=757|Color=8388608|FontID=1|IsHidden=T|Text=Tape and Reel|Name=Packaging
|RECORD=41|OwnerIndex=2009|IndexInSheet=31|OwnerPartId=-1|Location.X=1379|Location.Y=757|Color=8388608|FontID=1|IsHidden=T|Text=C|Name=Series
|RECORD=41|OwnerIndex=2009|IndexInSheet=32|OwnerPartId=-1|Location.X=1379|Location.Y=757|Color=8388608|FontID=1|IsHidden=T|Text=1206|Name=Case/Package
|RECORD=41|OwnerIndex=2009|IndexInSheet=33|OwnerPartId=-1|Location.X=1379|Location.Y=757|Color=8388608|FontID=1|IsHidden=T|Text=16V|Name=Voltage Rating
|RECORD=34|OwnerIndex=2009|IndexInSheet=-1|OwnerPartId=-1|Location.X=1380|Location.Y=740|Orientation=1|Color=8388608|FontID=2|Text=C13|Name=Designator|ReadOnlyState=1
|RECORD=41|OwnerIndex=2009|IndexInSheet=-1|OwnerPartId=1|Location.X=1410|Location.Y=715|Orientation=1|Color=8388608|FontID=2|Text=47uF_16V_1206|Name=Comment
|RECORD=44|OwnerIndex=2009
|RECORD=45|OwnerIndex=2048|IndexInSheet=-1|UseComponentLibrary=T|ModelName=FP-C3216-160-0_2-MFG|ModelType=PCBLIB|DatafileCount=1|ModelDatafileEntity0=FP-C3216-160-0_2-MFG|ModelDatafileKind0=PCBLib|IsCurrent=T|DatalinksLocked=T|DatabaseDatalinksLocked=T
|RECORD=46|OwnerIndex=2049
|RECORD=48|OwnerIndex=2049
|RECORD=45|OwnerIndex=2048|IndexInSheet=-1|UseComponentLibrary=T|ModelName=FP-C3216-160-0_2-IPC_B|ModelType=PCBLIB|DatafileCount=1|ModelDatafileEntity0=FP-C3216-160-0_2-IPC_B|ModelDatafileKind0=PCBLib|DatalinksLocked=T|DatabaseDatalinksLocked=T
|RECORD=46|OwnerIndex=2052
|RECORD=48|OwnerIndex=2052
|RECORD=45|OwnerIndex=2048|IndexInSheet=-1|UseComponentLibrary=T|ModelName=FP-C3216-160-0_2-IPC_C|ModelType=PCBLIB|DatafileCount=1|ModelDatafileEntity0=FP-C3216-160-0_2-IPC_C|ModelDatafileKind0=PCBLib|DatalinksLocked=T|DatabaseDatalinksLocked=T
|RECORD=46|OwnerIndex=2055
|RECORD=48|OwnerIndex=2055
|RECORD=45|OwnerIndex=2048|IndexInSheet=-1|UseComponentLibrary=T|ModelName=FP-C3216-160-0_2-IPC_A|ModelType=PCBLIB|DatafileCount=1|ModelDatafileEntity0=FP-C3216-160-0_2-IPC_A|ModelDatafileKind0=PCBLib|DatalinksLocked=T|DatabaseDatalinksLocked=T
|RECORD=46|OwnerIndex=2058
|RECORD=48|OwnerIndex=2058
|RECORD=17|IndexInSheet=112|OwnerPartId=-1|Style=4|ShowNetName=T|Location.X=1345|Location.Y=695|Orientation=3|Color=128|FontID=1|Text=GND
|RECORD=1|LibReference=41cc1aee4cbc9fa2660a15773fa0e79|ComponentDescription=IC MONITOR PWR/CURR BIDIR 8-SOIC|PartCount=2|DisplayModeCount=1|IndexInSheet=113|OwnerPartId=-1|Location.X=955|Location.Y=685|CurrentPartId=1|LibraryPath=*|SourceLibraryName=Altium Content Vault|TargetFileName=*|AreaColor=11599871|Color=128|PartIDLocked=T|DesignItemId=CMP-0704-00005-3|AllPinCount=8
|RECORD=14|OwnerIndex=2062|IsNotAccesible=T|OwnerPartId=1|Location.X=975|Location.Y=605|Corner.X=1065|Corner.Y=695|LineWidth=1|Color=128|AreaColor=11599871|IsSolid=T
|RECORD=2|OwnerIndex=2062|OwnerPartId=1|PinConglomerate=58|PinLength=20|Location.X=975|Location.Y=625|Name=VIN+|Designator=8|PinName_PositionConglomerate=16|Name_CustomFontID=1|PinDesignator_PositionConglomerate=16|Designator_CustomFontID=1|PinPropagationDelay=0.000000E+000
|RECORD=2|OwnerIndex=2062|OwnerPartId=1|PinConglomerate=58|PinLength=20|Location.X=975|Location.Y=615|Name=VIN-|Designator=7|PinName_PositionConglomerate=16|Name_CustomFontID=1|PinDesignator_PositionConglomerate=16|Designator_CustomFontID=1|PinPropagationDelay=0.000000E+000
|RECORD=2|OwnerIndex=2062|OwnerPartId=1|PinConglomerate=56|PinLength=20|Location.X=1065|Location.Y=645|Name=A0|Designator=2|PinName_PositionConglomerate=16|Name_CustomFontID=1|PinDesignator_PositionConglomerate=16|Designator_CustomFontID=1|PinPropagationDelay=0.000000E+000
|RECORD=2|OwnerIndex=2062|OwnerPartId=1|PinConglomerate=56|PinLength=20|Location.X=1065|Location.Y=635|Name=A1|Designator=1|PinName_PositionConglomerate=16|Name_CustomFontID=1|PinDesignator_PositionConglomerate=16|Designator_CustomFontID=1|PinPropagationDelay=0.000000E+000
|RECORD=2|OwnerIndex=2062|OwnerPartId=1|SymBol_InnerEdge=3|Electrical=1|PinConglomerate=56|PinLength=20|Location.X=1065|Location.Y=665|Name=SCL|Designator=4|PinName_PositionConglomerate=16|Name_CustomFontID=1|PinDesignator_PositionConglomerate=16|Designator_CustomFontID=1|PinPropagationDelay=0.000000E+000
|RECORD=2|OwnerIndex=2062|OwnerPartId=1|Electrical=1|PinConglomerate=56|PinLength=20|Location.X=1065|Location.Y=685|Name=SDA|Designator=3|PinName_PositionConglomerate=16|Name_CustomFontID=1|PinDesignator_PositionConglomerate=16|Designator_CustomFontID=1|PinPropagationDelay=0.000000E+000
|RECORD=2|OwnerIndex=2062|OwnerPartId=1|Electrical=7|PinConglomerate=58|PinLength=20|Location.X=975|Location.Y=685|Name=VS|Designator=5|PinName_PositionConglomerate=16|Name_CustomFontID=1|PinDesignator_PositionConglomerate=16|Designator_CustomFontID=1|PinPropagationDelay=0.000000E+000
|RECORD=2|OwnerIndex=2062|OwnerPartId=1|Electrical=7|PinConglomerate=56|PinLength=20|Location.X=1065|Location.Y=615|Name=GND|Designator=6|PinName_PositionConglomerate=16|Name_CustomFontID=1|PinDesignator_PositionConglomerate=16|Designator_CustomFontID=1|PinPropagationDelay=0.000000E+000
|RECORD=41|OwnerIndex=2062|IndexInSheet=9|OwnerPartId=-1|Location.X=953|Location.Y=695|Color=8388608|FontID=1|IsHidden=T|Text=3V|Name=Min Supply Voltage
|RECORD=41|OwnerIndex=2062|IndexInSheet=10|OwnerPartId=-1|Location.X=953|Location.Y=695|Color=8388608|FontID=1|IsHidden=T|Text=100dB|Name=Common Mode Rejection Ratio
|RECORD=41|OwnerIndex=2062|IndexInSheet=11|OwnerPartId=-1|Location.X=953|Location.Y=695|Color=8388608|FontID=1|IsHidden=T|Text=Tape and Reel|Name=Packaging
|RECORD=41|OwnerIndex=2062|IndexInSheet=12|OwnerPartId=-1|Location.X=953|Location.Y=695|Color=8388608|FontID=1|IsHidden=T|Text=No SVHC|Name=REACH SVHC
|RECORD=41|OwnerIndex=2062|IndexInSheet=13|OwnerPartId=-1|Location.X=953|Location.Y=695|Color=8388608|FontID=1|IsHidden=T|Text=125°C|Name=Max Operating Temperature
|RECORD=41|OwnerIndex=2062|IndexInSheet=14|OwnerPartId=-1|Location.X=953|Location.Y=695|Color=8388608|FontID=1|IsHidden=T|Text=8|Name=Number of Pins
|RECORD=41|OwnerIndex=2062|IndexInSheet=15|OwnerPartId=-1|Location.X=953|Location.Y=695|Color=8388608|FontID=1|IsHidden=T|Text=10mA|Name=Output Current
|RECORD=41|OwnerIndex=2062|IndexInSheet=16|OwnerPartId=-1|Location.X=953|Location.Y=695|Color=8388608|FontID=1|IsHidden=T|Text=Lead Free|Name=Lead Free
|RECORD=41|OwnerIndex=2062|IndexInSheet=17|OwnerPartId=-1|Location.X=953|Location.Y=695|Color=8388608|FontID=1|IsHidden=T|Text=1|Name=Package Quantity
|RECORD=41|OwnerIndex=2062|IndexInSheet=18|OwnerPartId=-1|Location.X=953|Location.Y=695|Color=8388608|FontID=1|IsHidden=T|Text=No|Name=Radiation Hardening
|RECORD=41|OwnerIndex=2062|IndexInSheet=19|OwnerPartId=-1|Location.X=953|Location.Y=695|Color=8388608|FontID=1|IsHidden=T|Text=SOIC|Name=Case/Package
|RECORD=41|OwnerIndex=2062|IndexInSheet=20|OwnerPartId=-1|Location.X=953|Location.Y=695|Color=8388608|FontID=1|IsHidden=T|Text=1|Name=Number of Amplifiers
|RECORD=41|OwnerIndex=2062|IndexInSheet=21|OwnerPartId=-1|Location.X=953|Location.Y=695|Color=8388608|FontID=1|IsHidden=T|Text=-40°C|Name=Min Operating Temperature
|RECORD=41|OwnerIndex=2062|IndexInSheet=22|OwnerPartId=-1|Location.X=953|Location.Y=695|Color=8388608|FontID=1|IsHidden=T|Text=0.5%|Name=Accuracy
|RECORD=41|OwnerIndex=2062|IndexInSheet=23|OwnerPartId=-1|Location.X=953|Location.Y=695|Color=8388608|FontID=1|IsHidden=T|Text=1mA|Name=Supply Current
|RECORD=41|OwnerIndex=2062|IndexInSheet=24|OwnerPartId=-1|Location.X=953|Location.Y=695|Color=8388608|FontID=1|IsHidden=T|Text=Gold|Name=Contact Plating
|RECORD=41|OwnerIndex=2062|IndexInSheet=25|OwnerPartId=-1|Location.X=953|Location.Y=695|Color=8388608|FontID=1|IsHidden=T|Text=700uA|Name=Quiescent Current
|RECORD=41|OwnerIndex=2062|IndexInSheet=26|OwnerPartId=-1|Location.X=953|Location.Y=695|Color=8388608|FontID=1|IsHidden=T|Text=Zero-Drift|Name=Series
|RECORD=41|OwnerIndex=2062|IndexInSheet=27|OwnerPartId=-1|Location.X=953|Location.Y=695|Color=8388608|FontID=1|IsHidden=T|Text=1mA|Name=Nominal Supply Current
|RECORD=41|OwnerIndex=2062|IndexInSheet=28|OwnerPartId=-1|Location.X=953|Location.Y=695|Color=8388608|FontID=1|IsHidden=T|Text=11kHz|Name=Bandwidth
|RECORD=41|OwnerIndex=2062|IndexInSheet=29|OwnerPartId=-1|Location.X=953|Location.Y=695|Color=8388608|FontID=1|IsHidden=T|Text=40uV|Name=Input Offset Voltage (Vos)
|RECORD=41|OwnerIndex=2062|IndexInSheet=30|OwnerPartId=-1|Location.X=953|Location.Y=695|Color=8388608|FontID=1|IsHidden=T|Text=5.5V|Name=Max Supply Voltage
|RECORD=41|OwnerIndex=2062|IndexInSheet=31|OwnerPartId=-1|Location.X=953|Location.Y=695|Color=8388608|FontID=1|IsHidden=T|Text=Yes|Name=RoHS Compliant
|RECORD=34|OwnerIndex=2062|IndexInSheet=-1|OwnerPartId=-1|Location.X=975|Location.Y=695|Color=8388608|FontID=1|Text=U17|Name=Designator|ReadOnlyState=1
|RECORD=41|OwnerIndex=2062|IndexInSheet=-1|OwnerPartId=1|Location.X=975|Location.Y=595|Color=8388608|FontID=1|Text=INA219BIDR|Name=Comment
|RECORD=44|OwnerIndex=2062
|RECORD=45|OwnerIndex=2105|IndexInSheet=-1|UseComponentLibrary=T|ModelName=FP-D0008A-MFG|ModelType=PCBLIB|DatafileCount=1|ModelDatafileEntity0=FP-D0008A-MFG|ModelDatafileKind0=PCBLib|IsCurrent=T|DatalinksLocked=T|DatabaseDatalinksLocked=T
|RECORD=46|OwnerIndex=2106
|RECORD=48|OwnerIndex=2106
|RECORD=45|OwnerIndex=2105|IndexInSheet=-1|UseComponentLibrary=T|ModelName=FP-D0008A-IPC_A|ModelType=PCBLIB|DatafileCount=1|ModelDatafileEntity0=FP-D0008A-IPC_A|ModelDatafileKind0=PCBLib|DatalinksLocked=T|DatabaseDatalinksLocked=T
|RECORD=46|OwnerIndex=2109
|RECORD=48|OwnerIndex=2109
|RECORD=45|OwnerIndex=2105|IndexInSheet=-1|UseComponentLibrary=T|ModelName=FP-D0008A-IPC_C|ModelType=PCBLIB|DatafileCount=1|ModelDatafileEntity0=FP-D0008A-IPC_C|ModelDatafileKind0=PCBLib|DatalinksLocked=T|DatabaseDatalinksLocked=T
|RECORD=46|OwnerIndex=2112
|RECORD=48|OwnerIndex=2112
|RECORD=45|OwnerIndex=2105|IndexInSheet=-1|UseComponentLibrary=T|ModelName=FP-D0008A-IPC_B|ModelType=PCBLIB|DatafileCount=1|ModelDatafileEntity0=FP-D0008A-IPC_B|ModelDatafileKind0=PCBLib|DatalinksLocked=T|DatabaseDatalinksLocked=T
|RECORD=46|OwnerIndex=2115
|RECORD=48|OwnerIndex=2115
|RECORD=1|LibReference=CAP|PartCount=2|DisplayModeCount=2|IndexInSheet=114|OwnerPartId=-1|Location.X=845|Location.Y=650|Orientation=1|CurrentPartId=1|SourceLibraryName=Altium Content Vault|TargetFileName=*|AreaColor=11599871|Color=128|PartIDLocked=F|DesignItemId=CMP-2008-00031-1|AllPinCount=2
|RECORD=2|OwnerIndex=2118|OwnerPartId=1|OwnerPartDisplayMode=1|FormalType=1|Electrical=4|PinConglomerate=35|PinLength=10|Location.X=855|Location.Y=650|Name=1|Designator=1|PinPropagationDelay=0.000000E+000
|RECORD=2|OwnerIndex=2118|OwnerPartId=1|OwnerPartDisplayMode=1|FormalType=1|Electrical=4|PinConglomerate=33|PinLength=10|Location.X=855|Location.Y=660|Name=2|Designator=2|PinPropagationDelay=0.000000E+000
|RECORD=13|OwnerIndex=2118|IsNotAccesible=T|IndexInSheet=2|OwnerPartId=1|OwnerPartDisplayMode=1|Location.X=863|Location.Y=650|Corner.X=847|Corner.Y=650|LineWidth=1|Color=16711680
|RECORD=13|OwnerIndex=2118|IsNotAccesible=T|IndexInSheet=3|OwnerPartId=1|OwnerPartDisplayMode=1|Location.X=855|Location.Y=654|Corner.X=855|Corner.Y=660|LineWidth=1|Color=16711680
|RECORD=12|OwnerIndex=2118|IsNotAccesible=T|IndexInSheet=4|OwnerPartId=1|OwnerPartDisplayMode=1|Location.X=855|Location.Y=670|Radius=16|LineWidth=1|StartAngle=241.000|EndAngle=270.000|Color=16711680
|RECORD=12|OwnerIndex=2118|IsNotAccesible=T|IndexInSheet=5|OwnerPartId=1|OwnerPartDisplayMode=1|Location.X=855|Location.Y=670|Radius=16|LineWidth=1|StartAngle=270.000|EndAngle=299.000|Color=16711680
|RECORD=2|OwnerIndex=2118|OwnerPartId=1|FormalType=1|Electrical=4|PinConglomerate=35|PinLength=10|Location.X=855|Location.Y=650|Name=1|Designator=1|PinPropagationDelay=0.000000E+000
|RECORD=2|OwnerIndex=2118|OwnerPartId=1|FormalType=1|Electrical=4|PinConglomerate=33|PinLength=10|Location.X=855|Location.Y=660|Name=2|Designator=2|PinPropagationDelay=0.000000E+000
|RECORD=13|OwnerIndex=2118|IsNotAccesible=T|IndexInSheet=8|OwnerPartId=1|Location.X=847|Location.Y=657|Corner.X=863|Corner.Y=657|LineWidth=1|Color=16711680
|RECORD=13|OwnerIndex=2118|IsNotAccesible=T|IndexInSheet=9|OwnerPartId=1|Location.X=863|Location.Y=653|Corner.X=847|Corner.Y=653|LineWidth=1|Color=16711680
|RECORD=6|OwnerIndex=2118|IsNotAccesible=T|IndexInSheet=10|OwnerPartId=1|LineWidth=1|Color=16711680|LocationCount=2|X1=855|Y1=650|X2=855|Y2=653
|RECORD=6|OwnerIndex=2118|IsNotAccesible=T|IndexInSheet=11|OwnerPartId=1|LineWidth=1|Color=16711680|LocationCount=2|X1=855|Y1=660|X2=855|Y2=657
|RECORD=41|OwnerIndex=2118|IndexInSheet=12|OwnerPartId=-1|Location.X=846|Location.Y=672|Color=8388608|FontID=1|IsHidden=T|Text=LD02YD104KAB2A|Name=Part Number
|RECORD=41|OwnerIndex=2118|IndexInSheet=13|OwnerPartId=-1|Location.X=846|Location.Y=672|Color=8388608|FontID=1|IsHidden=T|Text=AVX Interconnect / Elco|Name=Manufacturer
|RECORD=34|OwnerIndex=2118|IndexInSheet=-1|OwnerPartId=-1|Location.X=855|Location.Y=660|Orientation=1|Color=8388608|FontID=2|Text=C21|Name=Designator|ReadOnlyState=1
|RECORD=41|OwnerIndex=2118|IndexInSheet=-1|OwnerPartId=-1|Location.X=865|Location.Y=665|Orientation=1|Color=8388608|FontID=2|Text=0.1uF_0402|Name=Comment
|RECORD=44|OwnerIndex=2118
|RECORD=45|OwnerIndex=2139|IndexInSheet=-1|Description=Chip Capacitor, 2-Leads, Body 1.00x0.50mm, IPC Medium Density|UseComponentLibrary=T|ModelName=CAPC1005X56X25NL10T15|ModelType=PCBLIB|DatafileCount=1|ModelDatafileEntity0=CAPC1005X56X25NL10T15|ModelDatafileKind0=PCBLib|IsCurrent=T|DatalinksLocked=T|DatabaseDatalinksLocked=T
|RECORD=46|OwnerIndex=2140
|RECORD=48|OwnerIndex=2140
|RECORD=41|OwnerIndex=2142|IndexInSheet=-1|OwnerPartId=-1|Color=8388608|FontID=1|IsHidden=T|Text=2D|Name=Available Preview Images
|RECORD=45|OwnerIndex=2139|IndexInSheet=-1|Description=Chip Capacitor, 2-Leads, Body 1.00x0.50mm, IPC High Density|UseComponentLibrary=T|ModelName=CAPC1005X56X25LL10T15|ModelType=PCBLIB|DatafileCount=1|ModelDatafileEntity0=CAPC1005X56X25LL10T15|ModelDatafileKind0=PCBLib|DatalinksLocked=T|DatabaseDatalinksLocked=T
|RECORD=46|OwnerIndex=2144
|RECORD=48|OwnerIndex=2144
|RECORD=41|OwnerIndex=2146|IndexInSheet=-1|OwnerPartId=-1|Color=8388608|FontID=1|IsHidden=T|Text=2D|Name=Available Preview Images
|RECORD=45|OwnerIndex=2139|IndexInSheet=-1|Description=Chip Capacitor, 2-Leads, Body 1.00x0.50mm, IPC Low Density|UseComponentLibrary=T|ModelName=CAPC1005X56X25ML10T15|ModelType=PCBLIB|DatafileCount=1|ModelDatafileEntity0=CAPC1005X56X25ML10T15|ModelDatafileKind0=PCBLib|DatalinksLocked=T|DatabaseDatalinksLocked=T
|RECORD=46|OwnerIndex=2148
|RECORD=48|OwnerIndex=2148
|RECORD=41|OwnerIndex=2150|IndexInSheet=-1|OwnerPartId=-1|Color=8388608|FontID=1|IsHidden=T|Text=2D|Name=Available Preview Images
|RECORD=1|LibReference=b4654b650e69147ec39a6b967a45e02|ComponentDescription=Multilayer Ceramic Capacitor 10uF 16V X5R 20% SMD 0603 T/R|PartCount=2|DisplayModeCount=1|IndexInSheet=115|OwnerPartId=-1|Location.X=815|Location.Y=665|CurrentPartId=1|LibraryPath=*|SourceLibraryName=Altium Content Vault|TargetFileName=*|AreaColor=11599871|Color=128|PartIDLocked=T|DesignItemId=CMP-2000-06226-4|AllPinCount=2
|RECORD=2|OwnerIndex=2152|OwnerPartId=1|Electrical=4|PinConglomerate=49|PinLength=7|Location.X=815|Location.Y=658|Name=1|Designator=1|PinPropagationDelay=0.000000E+000
|RECORD=2|OwnerIndex=2152|OwnerPartId=1|Electrical=4|PinConglomerate=51|PinLength=6|Location.X=815|Location.Y=651|Name=2|Designator=2|PinPropagationDelay=0.000000E+000
|RECORD=13|OwnerIndex=2152|IsNotAccesible=T|IndexInSheet=2|OwnerPartId=1|Location.X=825|Location.Y=658|Corner.X=805|Corner.Y=658|LineWidth=1|Color=16711680
|RECORD=13|OwnerIndex=2152|IsNotAccesible=T|IndexInSheet=3|OwnerPartId=1|Location.X=825|Location.Y=652|Corner.X=805|Corner.Y=652|LineWidth=1|Color=16711680
|RECORD=13|OwnerIndex=2152|IsNotAccesible=T|IndexInSheet=4|OwnerPartId=1|Location.X=815|Location.Y=658|Corner.X=815|Corner.Y=661|LineWidth=1|Color=16711680
|RECORD=13|OwnerIndex=2152|IsNotAccesible=T|IndexInSheet=5|OwnerPartId=1|Location.X=815|Location.Y=651|Corner.X=815|Corner.Y=650|LineWidth=1|Color=16711680
|RECORD=41|OwnerIndex=2152|IndexInSheet=6|OwnerPartId=-1|Location.X=804|Location.Y=667|Color=8388608|FontID=1|IsHidden=T|Text=Tape and Reel|Name=Packaging
|RECORD=41|OwnerIndex=2152|IndexInSheet=7|OwnerPartId=-1|Location.X=804|Location.Y=667|Color=8388608|FontID=1|IsHidden=T|Text=Flat|Name=Construction
|RECORD=41|OwnerIndex=2152|IndexInSheet=8|OwnerPartId=-1|Location.X=804|Location.Y=667|Color=8388608|FontID=1|IsHidden=T|Text=0.8mm|Name=Height
|RECORD=41|OwnerIndex=2152|IndexInSheet=9|OwnerPartId=-1|Location.X=804|Location.Y=667|Color=8388608|FontID=1|IsHidden=T|Text=85°C|Name=Max Operating Temperature
|RECORD=41|OwnerIndex=2152|IndexInSheet=10|OwnerPartId=-1|Location.X=804|Location.Y=667|Color=8388608|FontID=1|IsHidden=T|Text=X5R|Name=Dielectric
|RECORD=41|OwnerIndex=2152|IndexInSheet=11|OwnerPartId=-1|Location.X=804|Location.Y=667|Color=8388608|FontID=1|IsHidden=T|Text=1608|Name=Case Code (Metric)
|RECORD=41|OwnerIndex=2152|IndexInSheet=12|OwnerPartId=-1|Location.X=804|Location.Y=667|Color=8388608|FontID=1|IsHidden=T|Text=16V|Name=Voltage Rating (DC)
|RECORD=41|OwnerIndex=2152|IndexInSheet=13|OwnerPartId=-1|Location.X=804|Location.Y=667|Color=8388608|FontID=1|IsHidden=T|Text=0.031inch|Name=Width
|RECORD=41|OwnerIndex=2152|IndexInSheet=14|OwnerPartId=-1|Location.X=804|Location.Y=667|Color=8388608|FontID=1|IsHidden=T|Text=16V|Name=Voltage Rating
|RECORD=41|OwnerIndex=2152|IndexInSheet=15|OwnerPartId=-1|Location.X=804|Location.Y=667|Color=8388608|FontID=1|IsHidden=T|Text=0.063inch|Name=Length
|RECORD=41|OwnerIndex=2152|IndexInSheet=16|OwnerPartId=-1|Location.X=804|Location.Y=667|Color=8388608|FontID=1|IsHidden=T|Text=Yes|Name=RoHS Compliant
|RECORD=41|OwnerIndex=2152|IndexInSheet=17|OwnerPartId=-1|Location.X=804|Location.Y=667|Color=8388608|FontID=1|IsHidden=T|Text=Halogen Free|Name=Halogen Free
|RECORD=41|OwnerIndex=2152|IndexInSheet=18|OwnerPartId=-1|Location.X=804|Location.Y=667|Color=8388608|FontID=1|IsHidden=T|Text=0603|Name=Case Code (Imperial)
|RECORD=41|OwnerIndex=2152|IndexInSheet=19|OwnerPartId=-1|Location.X=804|Location.Y=667|Color=8388608|FontID=1|IsHidden=T|Text=10uF|Name=Capacitance
|RECORD=41|OwnerIndex=2152|IndexInSheet=20|OwnerPartId=-1|Location.X=804|Location.Y=667|Color=8388608|FontID=1|IsHidden=T|Text=Surface Mount|Name=Mount
|RECORD=41|OwnerIndex=2152|IndexInSheet=21|OwnerPartId=-1|Location.X=804|Location.Y=667|Color=8388608|FontID=1|IsHidden=T|Text=0.031inch|Name=Thickness
|RECORD=41|OwnerIndex=2152|IndexInSheet=22|OwnerPartId=-1|Location.X=804|Location.Y=667|Color=8388608|FontID=1|IsHidden=T|Text=20%|Name=Tolerance
|RECORD=41|OwnerIndex=2152|IndexInSheet=23|OwnerPartId=-1|Location.X=804|Location.Y=667|Color=8388608|FontID=1|IsHidden=T|Text=-55°C|Name=Min Operating Temperature
|RECORD=41|OwnerIndex=2152|IndexInSheet=24|OwnerPartId=-1|Location.X=804|Location.Y=667|Color=8388608|FontID=1|IsHidden=T|Text=M|Name=Series
|RECORD=41|OwnerIndex=2152|IndexInSheet=25|OwnerPartId=-1|Location.X=804|Location.Y=667|Color=8388608|FontID=1|IsHidden=T|Text=SMD/SMT|Name=Termination
|RECORD=41|OwnerIndex=2152|IndexInSheet=26|OwnerPartId=-1|Location.X=804|Location.Y=667|Color=8388608|FontID=1|IsHidden=T|Text=0603|Name=Case/Package
|RECORD=41|OwnerIndex=2152|IndexInSheet=27|OwnerPartId=-1|Location.X=804|Location.Y=667|Color=8388608|FontID=1|IsHidden=T|Text=1|Name=Package Quantity
|RECORD=34|OwnerIndex=2152|IndexInSheet=-1|OwnerPartId=-1|Location.X=805|Location.Y=645|Orientation=1|Color=8388608|FontID=2|Text=C22|Name=Designator|ReadOnlyState=1
|RECORD=41|OwnerIndex=2152|IndexInSheet=-1|OwnerPartId=1|Location.X=835|Location.Y=630|Orientation=1|Color=8388608|FontID=2|Text=10uF_16V_0603|Name=Comment
|RECORD=44|OwnerIndex=2152
|RECORD=45|OwnerIndex=2185|IndexInSheet=-1|UseComponentLibrary=T|ModelName=FP-0603-L_1_6_0_2-W_0_8_0-MFG|ModelType=PCBLIB|DatafileCount=1|ModelDatafileEntity0=FP-0603-L_1_6_0_2-W_0_8_0-MFG|ModelDatafileKind0=PCBLib|IsCurrent=T|DatalinksLocked=T|DatabaseDatalinksLocked=T
|RECORD=46|OwnerIndex=2186
|RECORD=48|OwnerIndex=2186
|RECORD=45|OwnerIndex=2185|IndexInSheet=-1|UseComponentLibrary=T|ModelName=FP-0603-L_1_6_0_2-W_0_8_0-IPC_B|ModelType=PCBLIB|DatafileCount=1|ModelDatafileEntity0=FP-0603-L_1_6_0_2-W_0_8_0-IPC_B|ModelDatafileKind0=PCBLib|DatalinksLocked=T|DatabaseDatalinksLocked=T
|RECORD=46|OwnerIndex=2189
|RECORD=48|OwnerIndex=2189
|RECORD=45|OwnerIndex=2185|IndexInSheet=-1|UseComponentLibrary=T|ModelName=FP-0603-L_1_6_0_2-W_0_8_0-IPC_C|ModelType=PCBLIB|DatafileCount=1|ModelDatafileEntity0=FP-0603-L_1_6_0_2-W_0_8_0-IPC_C|ModelDatafileKind0=PCBLib|DatalinksLocked=T|DatabaseDatalinksLocked=T
|RECORD=46|OwnerIndex=2192
|RECORD=48|OwnerIndex=2192
|RECORD=45|OwnerIndex=2185|IndexInSheet=-1|UseComponentLibrary=T|ModelName=FP-0603-L_1_6_0_2-W_0_8_0-IPC_A|ModelType=PCBLIB|DatafileCount=1|ModelDatafileEntity0=FP-0603-L_1_6_0_2-W_0_8_0-IPC_A|ModelDatafileKind0=PCBLib|DatalinksLocked=T|DatabaseDatalinksLocked=T
|RECORD=46|OwnerIndex=2195
|RECORD=48|OwnerIndex=2195
|RECORD=17|IndexInSheet=116|OwnerPartId=-1|ShowNetName=T|Location.X=815|Location.Y=705|Orientation=1|Color=128|FontID=1|Text=+3.3V
|RECORD=17|IndexInSheet=117|OwnerPartId=-1|Style=4|ShowNetName=T|Location.X=815|Location.Y=635|Orientation=3|Color=128|FontID=1|Text=GND
|RECORD=17|IndexInSheet=118|OwnerPartId=-1|Style=4|ShowNetName=T|Location.X=855|Location.Y=635|Orientation=3|Color=128|FontID=1|Text=GND
|RECORD=17|IndexInSheet=119|OwnerPartId=-1|ShowNetName=T|Location.X=935|Location.Y=650|Orientation=1|Color=128|FontID=1|Text=P5V_SENSE
|RECORD=17|IndexInSheet=120|OwnerPartId=-1|Style=4|ShowNetName=T|Location.X=1095|Location.Y=610|Orientation=3|Color=128|FontID=1|Text=GND
|RECORD=17|IndexInSheet=121|OwnerPartId=-1|ShowNetName=T|Location.X=1130|Location.Y=665|Color=255|FontID=1|Text=SCL|IsCrossSheetConnector=T
|RECORD=17|IndexInSheet=122|OwnerPartId=-1|ShowNetName=T|Location.X=1130|Location.Y=685|Color=255|FontID=1|Text=SDA|IsCrossSheetConnector=T
|RECORD=1|LibReference=RES-2|ComponentDescription=Chip Resistor, 0 Ohm, 0.1 W, -55 to 155 degC, 0402 (1005 Metric), RoHS, Tape and Reel|PartCount=2|DisplayModeCount=1|IndexInSheet=123|OwnerPartId=-1|Location.X=1115|Location.Y=645|CurrentPartId=1|LibraryPath=*|SourceLibraryName=Altium Content Vault|TargetFileName=*|AreaColor=11599871|Color=128|PartIDLocked=T|DesignItemId=CMP-2000-07451-1|AllPinCount=2
|RECORD=2|OwnerIndex=2205|OwnerPartId=1|FormalType=1|Electrical=4|PinConglomerate=32|PinLength=10|Location.X=1135|Location.Y=645|Name=2|Designator=2|PinPropagationDelay=0.000000E+000
|RECORD=2|OwnerIndex=2205|OwnerPartId=1|FormalType=1|Electrical=4|PinConglomerate=34|PinLength=10|Location.X=1115|Location.Y=645|Name=1|Designator=1|PinPropagationDelay=0.000000E+000
|RECORD=6|OwnerIndex=2205|IsNotAccesible=T|IndexInSheet=2|OwnerPartId=1|LineWidth=1|Color=16711680|LocationCount=10|X1=1135|Y1=645|X2=1131|Y2=645|X3=1130|Y3=643|X4=1128|Y4=647|X5=1126|Y5=643|X6=1124|Y6=647|X7=1122|Y7=643|X8=1120|Y8=647|X9=1119|Y9=645|X10=1115|Y10=645
|RECORD=41|OwnerIndex=2205|IndexInSheet=3|OwnerPartId=-1|Location.X=1103|Location.Y=660|Color=8388608|FontID=1|IsHidden=T|Text=50V|Name=Voltage Rating (DC)
|RECORD=41|OwnerIndex=2205|IndexInSheet=4|OwnerPartId=-1|Location.X=1103|Location.Y=660|Color=8388608|FontID=1|IsHidden=T|Text=2|Name=Number of Terminations
|RECORD=41|OwnerIndex=2205|IndexInSheet=5|OwnerPartId=-1|Location.X=1103|Location.Y=660|Color=8388608|FontID=1|IsHidden=T|Text=SurfaceMount|Name=Mount
|RECORD=41|OwnerIndex=2205|IndexInSheet=6|OwnerPartId=-1|Location.X=1103|Location.Y=660|Color=8388608|FontID=1|IsHidden=T|Text=0.35mm|Name=Height
|RECORD=41|OwnerIndex=2205|IndexInSheet=7|OwnerPartId=-1|Location.X=1103|Location.Y=660|Color=8388608|FontID=1|IsHidden=T|Text=TapeandReel|Name=Packaging
|RECORD=41|OwnerIndex=2205|IndexInSheet=8|OwnerPartId=-1|Location.X=1103|Location.Y=660|Color=8388608|FontID=1|IsHidden=T|Text=Tin|Name=Contact Plating
|RECORD=41|OwnerIndex=2205|IndexInSheet=9|OwnerPartId=-1|Location.X=1103|Location.Y=660|Color=8388608|FontID=7|IsHidden=T|Text=http://www.panasonic.com/|Name=Manufacturer URL
|RECORD=41|OwnerIndex=2205|IndexInSheet=10|OwnerPartId=-1|Location.X=1103|Location.Y=660|Color=8388608|FontID=1|IsHidden=T|Text=ThickFilm|Name=Composition
|RECORD=41|OwnerIndex=2205|IndexInSheet=11|OwnerPartId=-1|Location.X=1103|Location.Y=660|Color=8388608|FontID=1|IsHidden=T|Text=155degC|Name=Max Operating Temperature
|RECORD=41|OwnerIndex=2205|IndexInSheet=12|OwnerPartId=-1|Location.X=1103|Location.Y=660|Color=8388608|FontID=1|IsHidden=T|Text=600ppm/??C|Name=Temperature Coefficient
|RECORD=41|OwnerIndex=2205|IndexInSheet=13|OwnerPartId=-1|Location.X=1103|Location.Y=660|Color=8388608|FontID=1|IsHidden=T|Text=NoSVHC|Name=REACH SVHC
|RECORD=41|OwnerIndex=2205|IndexInSheet=14|OwnerPartId=-1|Location.X=1103|Location.Y=660|Color=8388608|FontID=1|IsHidden=T|Text=0402|Name=Case/Package
|RECORD=41|OwnerIndex=2205|IndexInSheet=15|OwnerPartId=-1|Location.X=1103|Location.Y=660|Color=8388608|FontID=1|IsHidden=T|Text=100mW|Name=Max Power Dissipation
|RECORD=41|OwnerIndex=2205|IndexInSheet=16|OwnerPartId=-1|Location.X=1103|Location.Y=660|Color=8388608|FontID=1|IsHidden=T|Text=402|Name=Package Reference
|RECORD=41|OwnerIndex=2205|IndexInSheet=17|OwnerPartId=-1|Location.X=1103|Location.Y=660|Color=8388608|FontID=1|IsHidden=T|Text=0.5mm|Name=Depth
|RECORD=41|OwnerIndex=2205|IndexInSheet=18|OwnerPartId=-1|Location.X=1103|Location.Y=660|Color=8388608|FontID=1|IsHidden=T|Text=Panasonic|Name=Manufacturer
|RECORD=41|OwnerIndex=2205|IndexInSheet=19|OwnerPartId=-1|Location.X=1103|Location.Y=660|Color=8388608|FontID=1|IsHidden=T|Text=2-Pin Surface Mount Device, Body 1 x 0.5 mm|Name=Package Description
|RECORD=41|OwnerIndex=2205|IndexInSheet=20|OwnerPartId=-1|Location.X=1103|Location.Y=660|Color=8388608|FontID=7|IsHidden=T|Text=https://industrial.panasonic.com/cdbs/www-data/pdf/RDA0000/AOA0000C301.pdf|Name=Datasheet URL
|RECORD=41|OwnerIndex=2205|IndexInSheet=21|OwnerPartId=-1|Location.X=1103|Location.Y=660|Color=8388608|FontID=1|IsHidden=T|Text=True|Name=RoHSCompliant
|RECORD=41|OwnerIndex=2205|IndexInSheet=22|OwnerPartId=-1|Location.X=1103|Location.Y=660|Color=8388608|FontID=1|IsHidden=T|Text=0402|Name=Case Code (Imperial)
|RECORD=41|OwnerIndex=2205|IndexInSheet=23|OwnerPartId=-1|Location.X=1103|Location.Y=660|Color=8388608|FontID=1|IsHidden=T|Text=0mOhm|Name=Resistance
|RECORD=41|OwnerIndex=2205|IndexInSheet=24|OwnerPartId=-1|Location.X=1103|Location.Y=660|Color=8388608|FontID=1|IsHidden=T|Text=Not|Name=Military Standard
|RECORD=41|OwnerIndex=2205|IndexInSheet=25|OwnerPartId=-1|Location.X=1103|Location.Y=660|Color=8388608|FontID=1|IsHidden=T|Text=5%|Name=Tolerance
|RECORD=41|OwnerIndex=2205|IndexInSheet=26|OwnerPartId=-1|Location.X=1103|Location.Y=660|Color=8388608|FontID=1|IsHidden=T|Text=-55degC|Name=Min Operating Temperature
|RECORD=41|OwnerIndex=2205|IndexInSheet=27|OwnerPartId=-1|Location.X=1103|Location.Y=660|Color=8388608|FontID=1|IsHidden=T|Text=100mW|Name=Power Rating
|RECORD=41|OwnerIndex=2205|IndexInSheet=28|OwnerPartId=-1|Location.X=1103|Location.Y=660|Color=8388608|FontID=1|IsHidden=T|Text=03/2015|Name=Datasheet Version
|RECORD=41|OwnerIndex=2205|IndexInSheet=29|OwnerPartId=-1|Location.X=1103|Location.Y=660|Color=8388608|FontID=1|IsHidden=T|Text=1mm|Name=Length
|RECORD=41|OwnerIndex=2205|IndexInSheet=30|OwnerPartId=-1|Location.X=1103|Location.Y=660|Color=8388608|FontID=1|IsHidden=T|Text=1005|Name=Case Code (Metric)
|RECORD=41|OwnerIndex=2205|IndexInSheet=31|OwnerPartId=-1|Location.X=1103|Location.Y=660|Color=8388608|FontID=1|IsHidden=T|Text=SMD/SMT|Name=Termination
|RECORD=41|OwnerIndex=2205|IndexInSheet=32|OwnerPartId=-1|Location.X=1103|Location.Y=660|Color=8388608|FontID=1|IsHidden=T|Text=SurfaceMount|Name=Mounting Technology
|RECORD=41|OwnerIndex=2205|IndexInSheet=33|OwnerPartId=-1|Location.X=1103|Location.Y=660|Color=8388608|FontID=1|IsHidden=T|Text=50V|Name=Voltage Rating
|RECORD=41|OwnerIndex=2205|IndexInSheet=34|OwnerPartId=-1|Location.X=1103|Location.Y=660|Color=8388608|FontID=1|IsHidden=T|Text=0.02inch|Name=Width
|RECORD=41|OwnerIndex=2205|IndexInSheet=35|OwnerPartId=-1|Location.X=1103|Location.Y=660|Color=8388608|FontID=1|IsHidden=T|Text=1|Name=Package Quantity
|RECORD=41|OwnerIndex=2205|IndexInSheet=36|OwnerPartId=-1|Location.X=1103|Location.Y=660|Color=8388608|FontID=1|IsHidden=T|Text=LeadFree|Name=Lead Free
|RECORD=41|OwnerIndex=2205|IndexInSheet=37|OwnerPartId=-1|Location.X=1103|Location.Y=660|Color=8388608|FontID=1|IsHidden=T|Text=No|Name=Radiation Hardening
|RECORD=34|OwnerIndex=2205|IndexInSheet=-1|OwnerPartId=-1|Location.X=1095|Location.Y=645|Color=8388608|FontID=1|Text=R65|Name=Designator|ReadOnlyState=1
|RECORD=41|OwnerIndex=2205|IndexInSheet=-1|OwnerPartId=-1|Location.X=1135|Location.Y=645|Color=8388608|FontID=1|Text=0_1%_0402|Name=Comment
|RECORD=44|OwnerIndex=2205
|RECORD=45|OwnerIndex=2248|IndexInSheet=-1|Description=Chip Resistor, 2-Leads, Body 1.05x0.55mm, IPC High Density|UseComponentLibrary=T|ModelName=RESC1005X40X25LL05T05|ModelType=PCBLIB|DatafileCount=1|ModelDatafileEntity0=RESC1005X40X25LL05T05|ModelDatafileKind0=PCBLib|IsCurrent=T|DatalinksLocked=T|DatabaseDatalinksLocked=T
|RECORD=46|OwnerIndex=2249
|RECORD=48|OwnerIndex=2249
|RECORD=41|OwnerIndex=2251|IndexInSheet=-1|OwnerPartId=-1|Color=8388608|FontID=1|IsHidden=T|Text=2D|Name=Available Preview Images
|RECORD=45|OwnerIndex=2248|IndexInSheet=-1|Description=Chip Resistor, 2-Leads, Body 1.05x0.55mm, IPC Low Density|UseComponentLibrary=T|ModelName=RESC1005X40X25ML05T05|ModelType=PCBLIB|DatafileCount=1|ModelDatafileEntity0=RESC1005X40X25ML05T05|ModelDatafileKind0=PCBLib|DatalinksLocked=T|DatabaseDatalinksLocked=T
|RECORD=46|OwnerIndex=2253
|RECORD=48|OwnerIndex=2253
|RECORD=41|OwnerIndex=2255|IndexInSheet=-1|OwnerPartId=-1|Color=8388608|FontID=1|IsHidden=T|Text=2D|Name=Available Preview Images
|RECORD=45|OwnerIndex=2248|IndexInSheet=-1|Description=Chip Resistor, 2-Leads, Body 1.05x0.55mm, IPC Medium Density|UseComponentLibrary=T|ModelName=RESC1005X40X25NL05T05|ModelType=PCBLIB|DatafileCount=1|ModelDatafileEntity0=RESC1005X40X25NL05T05|ModelDatafileKind0=PCBLib|DatalinksLocked=T|DatabaseDatalinksLocked=T
|RECORD=46|OwnerIndex=2257
|RECORD=48|OwnerIndex=2257
|RECORD=41|OwnerIndex=2259|IndexInSheet=-1|OwnerPartId=-1|Color=8388608|FontID=1|IsHidden=T|Text=2D|Name=Available Preview Images
|RECORD=1|LibReference=RES-2|ComponentDescription=Chip Resistor, 0 Ohm, 0.1 W, -55 to 155 degC, 0402 (1005 Metric), RoHS, Tape and Reel|PartCount=2|DisplayModeCount=1|IndexInSheet=124|OwnerPartId=-1|Location.X=1115|Location.Y=635|CurrentPartId=1|LibraryPath=*|SourceLibraryName=Altium Content Vault|TargetFileName=*|AreaColor=11599871|Color=128|PartIDLocked=T|DesignItemId=CMP-2000-07451-1|AllPinCount=2
|RECORD=2|OwnerIndex=2261|OwnerPartId=1|FormalType=1|Electrical=4|PinConglomerate=32|PinLength=10|Location.X=1135|Location.Y=635|Name=2|Designator=2|PinPropagationDelay=0.000000E+000
|RECORD=2|OwnerIndex=2261|OwnerPartId=1|FormalType=1|Electrical=4|PinConglomerate=34|PinLength=10|Location.X=1115|Location.Y=635|Name=1|Designator=1|PinPropagationDelay=0.000000E+000
|RECORD=6|OwnerIndex=2261|IsNotAccesible=T|IndexInSheet=2|OwnerPartId=1|LineWidth=1|Color=16711680|LocationCount=10|X1=1135|Y1=635|X2=1131|Y2=635|X3=1130|Y3=633|X4=1128|Y4=637|X5=1126|Y5=633|X6=1124|Y6=637|X7=1122|Y7=633|X8=1120|Y8=637|X9=1119|Y9=635|X10=1115|Y10=635
|RECORD=41|OwnerIndex=2261|IndexInSheet=3|OwnerPartId=-1|Location.X=1103|Location.Y=650|Color=8388608|FontID=1|IsHidden=T|Text=50V|Name=Voltage Rating (DC)
|RECORD=41|OwnerIndex=2261|IndexInSheet=4|OwnerPartId=-1|Location.X=1103|Location.Y=650|Color=8388608|FontID=1|IsHidden=T|Text=2|Name=Number of Terminations
|RECORD=41|OwnerIndex=2261|IndexInSheet=5|OwnerPartId=-1|Location.X=1103|Location.Y=650|Color=8388608|FontID=1|IsHidden=T|Text=SurfaceMount|Name=Mount
|RECORD=41|OwnerIndex=2261|IndexInSheet=6|OwnerPartId=-1|Location.X=1103|Location.Y=650|Color=8388608|FontID=1|IsHidden=T|Text=0.35mm|Name=Height
|RECORD=41|OwnerIndex=2261|IndexInSheet=7|OwnerPartId=-1|Location.X=1103|Location.Y=650|Color=8388608|FontID=1|IsHidden=T|Text=TapeandReel|Name=Packaging
|RECORD=41|OwnerIndex=2261|IndexInSheet=8|OwnerPartId=-1|Location.X=1103|Location.Y=650|Color=8388608|FontID=1|IsHidden=T|Text=Tin|Name=Contact Plating
|RECORD=41|OwnerIndex=2261|IndexInSheet=9|OwnerPartId=-1|Location.X=1103|Location.Y=650|Color=8388608|FontID=7|IsHidden=T|Text=http://www.panasonic.com/|Name=Manufacturer URL
|RECORD=41|OwnerIndex=2261|IndexInSheet=10|OwnerPartId=-1|Location.X=1103|Location.Y=650|Color=8388608|FontID=1|IsHidden=T|Text=ThickFilm|Name=Composition
|RECORD=41|OwnerIndex=2261|IndexInSheet=11|OwnerPartId=-1|Location.X=1103|Location.Y=650|Color=8388608|FontID=1|IsHidden=T|Text=155degC|Name=Max Operating Temperature
|RECORD=41|OwnerIndex=2261|IndexInSheet=12|OwnerPartId=-1|Location.X=1103|Location.Y=650|Color=8388608|FontID=1|IsHidden=T|Text=600ppm/??C|Name=Temperature Coefficient
|RECORD=41|OwnerIndex=2261|IndexInSheet=13|OwnerPartId=-1|Location.X=1103|Location.Y=650|Color=8388608|FontID=1|IsHidden=T|Text=NoSVHC|Name=REACH SVHC
|RECORD=41|OwnerIndex=2261|IndexInSheet=14|OwnerPartId=-1|Location.X=1103|Location.Y=650|Color=8388608|FontID=1|IsHidden=T|Text=0402|Name=Case/Package
|RECORD=41|OwnerIndex=2261|IndexInSheet=15|OwnerPartId=-1|Location.X=1103|Location.Y=650|Color=8388608|FontID=1|IsHidden=T|Text=100mW|Name=Max Power Dissipation
|RECORD=41|OwnerIndex=2261|IndexInSheet=16|OwnerPartId=-1|Location.X=1103|Location.Y=650|Color=8388608|FontID=1|IsHidden=T|Text=402|Name=Package Reference
|RECORD=41|OwnerIndex=2261|IndexInSheet=17|OwnerPartId=-1|Location.X=1103|Location.Y=650|Color=8388608|FontID=1|IsHidden=T|Text=0.5mm|Name=Depth
|RECORD=41|OwnerIndex=2261|IndexInSheet=18|OwnerPartId=-1|Location.X=1103|Location.Y=650|Color=8388608|FontID=1|IsHidden=T|Text=Panasonic|Name=Manufacturer
|RECORD=41|OwnerIndex=2261|IndexInSheet=19|OwnerPartId=-1|Location.X=1103|Location.Y=650|Color=8388608|FontID=1|IsHidden=T|Text=2-Pin Surface Mount Device, Body 1 x 0.5 mm|Name=Package Description
|RECORD=41|OwnerIndex=2261|IndexInSheet=20|OwnerPartId=-1|Location.X=1103|Location.Y=650|Color=8388608|FontID=7|IsHidden=T|Text=https://industrial.panasonic.com/cdbs/www-data/pdf/RDA0000/AOA0000C301.pdf|Name=Datasheet URL
|RECORD=41|OwnerIndex=2261|IndexInSheet=21|OwnerPartId=-1|Location.X=1103|Location.Y=650|Color=8388608|FontID=1|IsHidden=T|Text=True|Name=RoHSCompliant
|RECORD=41|OwnerIndex=2261|IndexInSheet=22|OwnerPartId=-1|Location.X=1103|Location.Y=650|Color=8388608|FontID=1|IsHidden=T|Text=0402|Name=Case Code (Imperial)
|RECORD=41|OwnerIndex=2261|IndexInSheet=23|OwnerPartId=-1|Location.X=1103|Location.Y=650|Color=8388608|FontID=1|IsHidden=T|Text=0mOhm|Name=Resistance
|RECORD=41|OwnerIndex=2261|IndexInSheet=24|OwnerPartId=-1|Location.X=1103|Location.Y=650|Color=8388608|FontID=1|IsHidden=T|Text=Not|Name=Military Standard
|RECORD=41|OwnerIndex=2261|IndexInSheet=25|OwnerPartId=-1|Location.X=1103|Location.Y=650|Color=8388608|FontID=1|IsHidden=T|Text=5%|Name=Tolerance
|RECORD=41|OwnerIndex=2261|IndexInSheet=26|OwnerPartId=-1|Location.X=1103|Location.Y=650|Color=8388608|FontID=1|IsHidden=T|Text=-55degC|Name=Min Operating Temperature
|RECORD=41|OwnerIndex=2261|IndexInSheet=27|OwnerPartId=-1|Location.X=1103|Location.Y=650|Color=8388608|FontID=1|IsHidden=T|Text=100mW|Name=Power Rating
|RECORD=41|OwnerIndex=2261|IndexInSheet=28|OwnerPartId=-1|Location.X=1103|Location.Y=650|Color=8388608|FontID=1|IsHidden=T|Text=03/2015|Name=Datasheet Version
|RECORD=41|OwnerIndex=2261|IndexInSheet=29|OwnerPartId=-1|Location.X=1103|Location.Y=650|Color=8388608|FontID=1|IsHidden=T|Text=1mm|Name=Length
|RECORD=41|OwnerIndex=2261|IndexInSheet=30|OwnerPartId=-1|Location.X=1103|Location.Y=650|Color=8388608|FontID=1|IsHidden=T|Text=1005|Name=Case Code (Metric)
|RECORD=41|OwnerIndex=2261|IndexInSheet=31|OwnerPartId=-1|Location.X=1103|Location.Y=650|Color=8388608|FontID=1|IsHidden=T|Text=SMD/SMT|Name=Termination
|RECORD=41|OwnerIndex=2261|IndexInSheet=32|OwnerPartId=-1|Location.X=1103|Location.Y=650|Color=8388608|FontID=1|IsHidden=T|Text=SurfaceMount|Name=Mounting Technology
|RECORD=41|OwnerIndex=2261|IndexInSheet=33|OwnerPartId=-1|Location.X=1103|Location.Y=650|Color=8388608|FontID=1|IsHidden=T|Text=50V|Name=Voltage Rating
|RECORD=41|OwnerIndex=2261|IndexInSheet=34|OwnerPartId=-1|Location.X=1103|Location.Y=650|Color=8388608|FontID=1|IsHidden=T|Text=0.02inch|Name=Width
|RECORD=41|OwnerIndex=2261|IndexInSheet=35|OwnerPartId=-1|Location.X=1103|Location.Y=650|Color=8388608|FontID=1|IsHidden=T|Text=1|Name=Package Quantity
|RECORD=41|OwnerIndex=2261|IndexInSheet=36|OwnerPartId=-1|Location.X=1103|Location.Y=650|Color=8388608|FontID=1|IsHidden=T|Text=LeadFree|Name=Lead Free
|RECORD=41|OwnerIndex=2261|IndexInSheet=37|OwnerPartId=-1|Location.X=1103|Location.Y=650|Color=8388608|FontID=1|IsHidden=T|Text=No|Name=Radiation Hardening
|RECORD=34|OwnerIndex=2261|IndexInSheet=-1|OwnerPartId=-1|Location.X=1095|Location.Y=635|Color=8388608|FontID=1|Text=R66|Name=Designator|ReadOnlyState=1
|RECORD=41|OwnerIndex=2261|IndexInSheet=-1|OwnerPartId=-1|Location.X=1135|Location.Y=635|Color=8388608|FontID=1|Text=0_1%_0402|Name=Comment
|RECORD=44|OwnerIndex=2261
|RECORD=45|OwnerIndex=2304|IndexInSheet=-1|Description=Chip Resistor, 2-Leads, Body 1.05x0.55mm, IPC High Density|UseComponentLibrary=T|ModelName=RESC1005X40X25LL05T05|ModelType=PCBLIB|DatafileCount=1|ModelDatafileEntity0=RESC1005X40X25LL05T05|ModelDatafileKind0=PCBLib|IsCurrent=T|DatalinksLocked=T|DatabaseDatalinksLocked=T
|RECORD=46|OwnerIndex=2305
|RECORD=48|OwnerIndex=2305
|RECORD=41|OwnerIndex=2307|IndexInSheet=-1|OwnerPartId=-1|Color=8388608|FontID=1|IsHidden=T|Text=2D|Name=Available Preview Images
|RECORD=45|OwnerIndex=2304|IndexInSheet=-1|Description=Chip Resistor, 2-Leads, Body 1.05x0.55mm, IPC Low Density|UseComponentLibrary=T|ModelName=RESC1005X40X25ML05T05|ModelType=PCBLIB|DatafileCount=1|ModelDatafileEntity0=RESC1005X40X25ML05T05|ModelDatafileKind0=PCBLib|DatalinksLocked=T|DatabaseDatalinksLocked=T
|RECORD=46|OwnerIndex=2309
|RECORD=48|OwnerIndex=2309
|RECORD=41|OwnerIndex=2311|IndexInSheet=-1|OwnerPartId=-1|Color=8388608|FontID=1|IsHidden=T|Text=2D|Name=Available Preview Images
|RECORD=45|OwnerIndex=2304|IndexInSheet=-1|Description=Chip Resistor, 2-Leads, Body 1.05x0.55mm, IPC Medium Density|UseComponentLibrary=T|ModelName=RESC1005X40X25NL05T05|ModelType=PCBLIB|DatafileCount=1|ModelDatafileEntity0=RESC1005X40X25NL05T05|ModelDatafileKind0=PCBLib|DatalinksLocked=T|DatabaseDatalinksLocked=T
|RECORD=46|OwnerIndex=2313
|RECORD=48|OwnerIndex=2313
|RECORD=41|OwnerIndex=2315|IndexInSheet=-1|OwnerPartId=-1|Color=8388608|FontID=1|IsHidden=T|Text=2D|Name=Available Preview Images
|RECORD=4|IndexInSheet=125|OwnerPartId=-1|Location.X=995|Location.Y=715|Color=8388608|FontID=1|Text=Address 0x41
|RECORD=17|IndexInSheet=126|OwnerPartId=-1|ShowNetName=T|Location.X=1190|Location.Y=700|Orientation=1|Color=128|FontID=1|Text=+3.3V
|RECORD=27|IndexInSheet=127|OwnerPartId=-1|LineWidth=1|Color=8388608|LocationCount=2|X1=602|Y1=917|X2=602|Y2=937
|RECORD=27|IndexInSheet=128|OwnerPartId=-1|LineWidth=1|Color=8388608|LocationCount=2|X1=1425|Y1=270|X2=1425|Y2=250
|RECORD=27|IndexInSheet=129|OwnerPartId=-1|LineWidth=1|Color=8388608|LocationCount=2|X1=1425|Y1=360|X2=1425|Y2=340
|RECORD=27|IndexInSheet=130|OwnerPartId=-1|LineWidth=1|Color=8388608|LocationCount=2|X1=1425|Y1=420|X2=1425|Y2=430
|RECORD=27|IndexInSheet=131|OwnerPartId=-1|LineWidth=1|Color=8388608|LocationCount=5|X1=195|Y1=830|X2=202|Y2=830|X3=202|Y3=829|X4=285|Y4=829|X5=285|Y5=915
|RECORD=27|IndexInSheet=132|OwnerPartId=-1|LineWidth=1|Color=8388608|LocationCount=3|X1=135|Y1=830|X2=82|Y2=830|X3=82|Y3=839
|RECORD=27|IndexInSheet=133|OwnerPartId=-1|LineWidth=1|Color=8388608|LocationCount=2|X1=325|Y1=955|X2=285|Y2=955
|RECORD=27|IndexInSheet=134|OwnerPartId=-1|LineWidth=1|Color=8388608|LocationCount=3|X1=105|Y1=910|X2=170|Y2=910|X3=170|Y3=900
|RECORD=27|IndexInSheet=135|OwnerPartId=-1|LineWidth=1|Color=8388608|LocationCount=3|X1=105|Y1=930|X2=170|Y2=930|X3=170|Y3=910
|RECORD=27|IndexInSheet=136|OwnerPartId=-1|LineWidth=1|Color=8388608|LocationCount=4|X1=105|Y1=990|X2=210|Y2=990|X3=210|Y3=1000|X4=220|Y4=1000
|RECORD=27|IndexInSheet=137|OwnerPartId=-1|LineWidth=1|Color=8388608|LocationCount=3|X1=105|Y1=1010|X2=210|Y2=1010|X3=210|Y3=1000
|RECORD=27|IndexInSheet=138|OwnerPartId=-1|LineWidth=1|Color=8388608|LocationCount=5|X1=320|Y1=915|X2=285|Y2=915|X3=285|Y3=955|X4=285|Y4=1000|X5=280|Y5=1000
|RECORD=27|IndexInSheet=139|OwnerPartId=-1|LineWidth=1|Color=8388608|LocationCount=4|X1=380|Y1=915|X2=405|Y2=915|X3=405|Y3=955|X4=365|Y4=955
|RECORD=27|IndexInSheet=140|OwnerPartId=-1|LineWidth=1|Color=8388608|LocationCount=3|X1=405|Y1=915|X2=425|Y2=915|X3=430|Y3=915
|RECORD=27|IndexInSheet=141|OwnerPartId=-1|LineWidth=1|Color=8388608|LocationCount=2|X1=552|Y1=877|X2=552|Y2=915
|RECORD=27|IndexInSheet=142|OwnerPartId=-1|LineWidth=1|Color=8388608|LocationCount=2|X1=405|Y1=955|X2=405|Y2=980
|RECORD=27|IndexInSheet=143|OwnerPartId=-1|LineWidth=1|Color=8388608|LocationCount=5|X1=470|Y1=915|X2=552|Y2=915|X3=552|Y3=917|X4=602|Y4=917|X5=602|Y5=877
|RECORD=27|IndexInSheet=144|OwnerPartId=-1|LineWidth=1|Color=8388608|LocationCount=2|X1=200|Y1=735|X2=200|Y2=755
|RECORD=27|IndexInSheet=145|OwnerPartId=-1|LineWidth=1|Color=8388608|LocationCount=2|X1=240|Y1=740|X2=240|Y2=755
|RECORD=27|IndexInSheet=146|OwnerPartId=-1|LineWidth=1|Color=8388608|LocationCount=2|X1=240|Y1=705|X2=240|Y2=710
|RECORD=27|IndexInSheet=147|OwnerPartId=-1|LineWidth=1|Color=8388608|LocationCount=2|X1=200|Y1=705|X2=200|Y2=715
|RECORD=27|IndexInSheet=148|OwnerPartId=-1|LineWidth=1|Color=8388608|LocationCount=3|X1=340|Y1=695|X2=320|Y2=695|X3=320|Y3=720
|RECORD=27|IndexInSheet=149|OwnerPartId=-1|LineWidth=1|Color=8388608|LocationCount=3|X1=340|Y1=685|X2=280|Y2=685|X3=280|Y3=720
|RECORD=27|IndexInSheet=150|OwnerPartId=-1|LineWidth=1|Color=8388608|LocationCount=3|X1=470|Y1=685|X2=480|Y2=685|X3=480|Y3=680
|RECORD=27|IndexInSheet=151|OwnerPartId=-1|LineWidth=1|Color=8388608|LocationCount=2|X1=470|Y1=755|X2=515|Y2=755
|RECORD=27|IndexInSheet=152|OwnerPartId=-1|LineWidth=1|Color=8388608|LocationCount=2|X1=470|Y1=735|X2=515|Y2=735
|RECORD=27|IndexInSheet=153|OwnerPartId=-1|LineWidth=1|Color=8388608|LocationCount=2|X1=470|Y1=715|X2=490|Y2=715
|RECORD=27|IndexInSheet=154|OwnerPartId=-1|LineWidth=1|Color=8388608|LocationCount=2|X1=490|Y1=705|X2=470|Y2=705
|RECORD=27|IndexInSheet=155|OwnerPartId=-1|LineWidth=1|Color=8388608|LocationCount=2|X1=530|Y1=705|X2=575|Y2=705
|RECORD=27|IndexInSheet=156|OwnerPartId=-1|LineWidth=1|Color=8388608|LocationCount=4|X1=200|Y1=775|X2=200|Y2=755|X3=240|Y3=755|X4=340|Y4=755
|RECORD=27|IndexInSheet=157|OwnerPartId=-1|LineWidth=1|Color=8388608|LocationCount=5|X1=530|Y1=715|X2=575|Y2=715|X3=575|Y3=705|X4=575|Y4=685|X5=480|Y5=685
|RECORD=27|IndexInSheet=158|OwnerPartId=-1|LineWidth=1|Color=8388608|LocationCount=2|X1=1540|Y1=915|X2=1530|Y2=915
|RECORD=27|IndexInSheet=159|OwnerPartId=-1|LineWidth=1|Color=8388608|LocationCount=2|X1=1540|Y1=905|X2=1530|Y2=905
|RECORD=27|IndexInSheet=160|OwnerPartId=-1|LineWidth=1|Color=8388608|LocationCount=2|X1=1540|Y1=895|X2=1530|Y2=895
|RECORD=27|IndexInSheet=161|OwnerPartId=-1|LineWidth=1|Color=8388608|LocationCount=2|X1=1540|Y1=885|X2=1530|Y2=885
|RECORD=27|IndexInSheet=162|OwnerPartId=-1|LineWidth=1|Color=8388608|LocationCount=2|X1=1540|Y1=875|X2=1530|Y2=875
|RECORD=27|IndexInSheet=163|OwnerPartId=-1|LineWidth=1|Color=8388608|LocationCount=2|X1=1540|Y1=855|X2=1530|Y2=855
|RECORD=27|IndexInSheet=164|OwnerPartId=-1|LineWidth=1|Color=8388608|LocationCount=2|X1=885|Y1=885|X2=875|Y2=885
|RECORD=27|IndexInSheet=165|OwnerPartId=-1|LineWidth=1|Color=8388608|LocationCount=2|X1=885|Y1=895|X2=875|Y2=895
|RECORD=27|IndexInSheet=166|OwnerPartId=-1|LineWidth=1|Color=8388608|LocationCount=2|X1=885|Y1=905|X2=875|Y2=905
|RECORD=27|IndexInSheet=167|OwnerPartId=-1|LineWidth=1|Color=8388608|LocationCount=2|X1=885|Y1=915|X2=875|Y2=915
|RECORD=27|IndexInSheet=168|OwnerPartId=-1|LineWidth=1|Color=8388608|LocationCount=2|X1=885|Y1=925|X2=875|Y2=925
|RECORD=27|IndexInSheet=169|OwnerPartId=-1|LineWidth=1|Color=8388608|LocationCount=3|X1=1045|Y1=965|X2=1080|Y2=965|X3=1080|Y3=990
|RECORD=27|IndexInSheet=170|OwnerPartId=-1|LineWidth=1|Color=8388608|LocationCount=2|X1=1080|Y1=1030|X2=1080|Y2=1045
|RECORD=27|IndexInSheet=171|OwnerPartId=-1|LineWidth=1|Color=8388608|LocationCount=3|X1=885|Y1=965|X2=765|Y2=965|X3=765|Y3=995
|RECORD=27|IndexInSheet=172|OwnerPartId=-1|LineWidth=1|Color=8388608|LocationCount=3|X1=765|Y1=1035|X2=765|Y2=1045|X3=750|Y3=1045
|RECORD=27|IndexInSheet=173|OwnerPartId=-1|LineWidth=1|Color=8388608|LocationCount=2|X1=1045|Y1=975|X2=1100|Y2=975
|RECORD=27|IndexInSheet=174|OwnerPartId=-1|LineWidth=1|Color=8388608|LocationCount=2|X1=830|Y1=835|X2=830|Y2=855
|RECORD=27|IndexInSheet=175|OwnerPartId=-1|LineWidth=1|Color=8388608|LocationCount=3|X1=870|Y1=790|X2=830|Y2=790|X3=830|Y3=815
|RECORD=27|IndexInSheet=176|OwnerPartId=-1|LineWidth=1|Color=8388608|LocationCount=3|X1=1140|Y1=975|X2=1180|Y2=975|X3=1180|Y3=965
|RECORD=27|IndexInSheet=177|OwnerPartId=-1|LineWidth=1|Color=8388608|LocationCount=2|X1=1045|Y1=935|X2=1055|Y2=935
|RECORD=27|IndexInSheet=178|OwnerPartId=-1|LineWidth=1|Color=8388608|LocationCount=2|X1=1045|Y1=925|X2=1055|Y2=925
|RECORD=27|IndexInSheet=179|OwnerPartId=-1|LineWidth=1|Color=8388608|LocationCount=2|X1=1045|Y1=915|X2=1055|Y2=915
|RECORD=27|IndexInSheet=180|OwnerPartId=-1|LineWidth=1|Color=8388608|LocationCount=2|X1=1045|Y1=905|X2=1055|Y2=905
|RECORD=27|IndexInSheet=181|OwnerPartId=-1|LineWidth=1|Color=8388608|LocationCount=3|X1=1105|Y1=925|X2=1085|Y2=925|X3=1085|Y3=895
|RECORD=27|IndexInSheet=182|OwnerPartId=-1|LineWidth=1|Color=8388608|LocationCount=7|X1=885|Y1=975|X2=880|Y2=975|X3=880|Y3=1010|X4=1065|Y4=1010|X5=1065|Y5=940|X6=1160|Y6=940|X7=1160|Y7=925
|RECORD=27|IndexInSheet=183|OwnerPartId=-1|LineWidth=1|Color=8388608|LocationCount=3|X1=1540|Y1=935|X2=1460|Y2=935|X3=1460|Y3=985
|RECORD=27|IndexInSheet=184|OwnerPartId=-1|LineWidth=1|Color=8388608|LocationCount=3|X1=1540|Y1=945|X2=1525|Y2=945|X3=1525|Y3=985
|RECORD=27|IndexInSheet=185|OwnerPartId=-1|LineWidth=1|Color=8388608|LocationCount=3|X1=1225|Y1=990|X2=1225|Y2=965|X3=1250|Y3=965
|RECORD=27|IndexInSheet=186|OwnerPartId=-1|LineWidth=1|Color=8388608|LocationCount=3|X1=1290|Y1=965|X2=1340|Y2=965|X3=1340|Y3=990
|RECORD=27|IndexInSheet=187|OwnerPartId=-1|LineWidth=1|Color=8388608|LocationCount=2|X1=1400|Y1=875|X2=1400|Y2=900
|RECORD=27|IndexInSheet=188|OwnerPartId=-1|LineWidth=1|Color=8388608|LocationCount=2|X1=1400|Y1=835|X2=1400|Y2=855
|RECORD=27|IndexInSheet=189|OwnerPartId=-1|LineWidth=1|Color=8388608|LocationCount=2|X1=1465|Y1=875|X2=1465|Y2=900
|RECORD=27|IndexInSheet=190|OwnerPartId=-1|LineWidth=1|Color=8388608|LocationCount=2|X1=1465|Y1=835|X2=1465|Y2=855
|RECORD=27|IndexInSheet=191|OwnerPartId=-1|LineWidth=1|Color=8388608|LocationCount=2|X1=1095|Y1=885|X2=1095|Y2=895
|RECORD=27|IndexInSheet=192|OwnerPartId=-1|LineWidth=1|Color=8388608|LocationCount=2|X1=1095|Y1=845|X2=1095|Y2=835
|RECORD=27|IndexInSheet=193|OwnerPartId=-1|LineWidth=1|Color=8388608|LocationCount=2|X1=1095|Y1=795|X2=1095|Y2=815
|RECORD=27|IndexInSheet=194|OwnerPartId=-1|LineWidth=1|Color=8388608|LocationCount=2|X1=740|Y1=810|X2=740|Y2=855
|RECORD=27|IndexInSheet=195|OwnerPartId=-1|LineWidth=1|Color=8388608|LocationCount=4|X1=780|Y1=810|X2=780|Y2=845|X3=770|Y3=845|X4=770|Y4=855
|RECORD=27|IndexInSheet=196|OwnerPartId=-1|LineWidth=1|Color=8388608|LocationCount=2|X1=740|Y1=790|X2=740|Y2=770
|RECORD=27|IndexInSheet=197|OwnerPartId=-1|LineWidth=1|Color=8388608|LocationCount=2|X1=780|Y1=790|X2=780|Y2=770
|RECORD=27|IndexInSheet=198|OwnerPartId=-1|LineWidth=1|Color=8388608|LocationCount=2|X1=1190|Y1=865|X2=1190|Y2=895
|RECORD=27|IndexInSheet=199|OwnerPartId=-1|LineWidth=1|Color=8388608|LocationCount=2|X1=1190|Y1=810|X2=1190|Y2=825
|RECORD=27|IndexInSheet=200|OwnerPartId=-1|LineWidth=1|Color=8388608|LocationCount=2|X1=885|Y1=955|X2=775|Y2=955
|RECORD=27|IndexInSheet=201|OwnerPartId=-1|LineWidth=1|Color=8388608|LocationCount=3|X1=1190|Y1=790|X2=1190|Y2=745|X3=1080|Y3=745
|RECORD=27|IndexInSheet=202|OwnerPartId=-1|LineWidth=1|Color=8388608|LocationCount=4|X1=1245|Y1=835|X2=1245|Y2=865|X3=1280|Y3=865|X4=1280|Y4=850
|RECORD=27|IndexInSheet=203|OwnerPartId=-1|LineWidth=1|Color=8388608|LocationCount=4|X1=1280|Y1=810|X2=1280|Y2=780|X3=1245|Y3=780|X4=1245|Y4=815
|RECORD=27|IndexInSheet=204|OwnerPartId=-1|LineWidth=1|Color=8388608|LocationCount=3|X1=1190|Y1=745|X2=1280|Y2=745|X3=1280|Y3=780
|RECORD=27|IndexInSheet=205|OwnerPartId=-1|LineWidth=1|Color=8388608|LocationCount=3|X1=1240|Y1=895|X2=1280|Y2=895|X3=1280|Y3=865
|RECORD=27|IndexInSheet=206|OwnerPartId=-1|LineWidth=1|Color=8388608|LocationCount=2|X1=1280|Y1=735|X2=1280|Y2=745
|RECORD=27|IndexInSheet=207|OwnerPartId=-1|LineWidth=1|Color=8388608|LocationCount=2|X1=1280|Y1=690|X2=1280|Y2=695
|RECORD=27|IndexInSheet=208|OwnerPartId=-1|LineWidth=1|Color=8388608|LocationCount=2|X1=1280|Y1=895|X2=1280|Y2=910
|RECORD=27|IndexInSheet=209|OwnerPartId=-1|LineWidth=1|Color=8388608|LocationCount=2|X1=1280|Y1=895|X2=1295|Y2=895
|RECORD=27|IndexInSheet=210|OwnerPartId=-1|LineWidth=1|Color=8388608|LocationCount=2|X1=1390|Y1=755|X2=1390|Y2=785
|RECORD=27|IndexInSheet=211|OwnerPartId=-1|LineWidth=1|Color=8388608|LocationCount=2|X1=1430|Y1=755|X2=1430|Y2=785
|RECORD=27|IndexInSheet=212|OwnerPartId=-1|LineWidth=1|Color=8388608|LocationCount=2|X1=1475|Y1=755|X2=1475|Y2=785
|RECORD=27|IndexInSheet=213|OwnerPartId=-1|LineWidth=1|Color=8388608|LocationCount=2|X1=1520|Y1=755|X2=1520|Y2=785
|RECORD=27|IndexInSheet=214|OwnerPartId=-1|LineWidth=1|Color=8388608|LocationCount=2|X1=1390|Y1=735|X2=1390|Y2=705
|RECORD=27|IndexInSheet=215|OwnerPartId=-1|LineWidth=1|Color=8388608|LocationCount=2|X1=1430|Y1=735|X2=1430|Y2=705
|RECORD=27|IndexInSheet=216|OwnerPartId=-1|LineWidth=1|Color=8388608|LocationCount=2|X1=1475|Y1=735|X2=1475|Y2=705
|RECORD=27|IndexInSheet=217|OwnerPartId=-1|LineWidth=1|Color=8388608|LocationCount=2|X1=1520|Y1=735|X2=1520|Y2=705
|RECORD=27|IndexInSheet=218|OwnerPartId=-1|LineWidth=1|Color=8388608|LocationCount=2|X1=815|Y1=665|X2=815|Y2=685
|RECORD=27|IndexInSheet=219|OwnerPartId=-1|LineWidth=1|Color=8388608|LocationCount=2|X1=855|Y1=670|X2=855|Y2=685
|RECORD=27|IndexInSheet=220|OwnerPartId=-1|LineWidth=1|Color=8388608|LocationCount=2|X1=855|Y1=635|X2=855|Y2=640
|RECORD=27|IndexInSheet=221|OwnerPartId=-1|LineWidth=1|Color=8388608|LocationCount=2|X1=815|Y1=635|X2=815|Y2=645
|RECORD=27|IndexInSheet=222|OwnerPartId=-1|LineWidth=1|Color=8388608|LocationCount=3|X1=955|Y1=625|X2=935|Y2=625|X3=935|Y3=650
|RECORD=27|IndexInSheet=223|OwnerPartId=-1|LineWidth=1|Color=8388608|LocationCount=3|X1=955|Y1=615|X2=895|Y2=615|X3=895|Y3=650
|RECORD=27|IndexInSheet=224|OwnerPartId=-1|LineWidth=1|Color=8388608|LocationCount=3|X1=1085|Y1=615|X2=1095|Y2=615|X3=1095|Y3=610
|RECORD=27|IndexInSheet=225|OwnerPartId=-1|LineWidth=1|Color=8388608|LocationCount=2|X1=1085|Y1=685|X2=1130|Y2=685
|RECORD=27|IndexInSheet=226|OwnerPartId=-1|LineWidth=1|Color=8388608|LocationCount=2|X1=1085|Y1=665|X2=1130|Y2=665
|RECORD=27|IndexInSheet=227|OwnerPartId=-1|LineWidth=1|Color=8388608|LocationCount=2|X1=1085|Y1=645|X2=1105|Y2=645
|RECORD=27|IndexInSheet=228|OwnerPartId=-1|LineWidth=1|Color=8388608|LocationCount=2|X1=1105|Y1=635|X2=1085|Y2=635
|RECORD=27|IndexInSheet=229|OwnerPartId=-1|LineWidth=1|Color=8388608|LocationCount=4|X1=1145|Y1=635|X2=1190|Y2=635|X3=1190|Y3=615|X4=1095|Y4=615
|RECORD=27|IndexInSheet=230|OwnerPartId=-1|LineWidth=1|Color=8388608|LocationCount=3|X1=1145|Y1=645|X2=1190|Y2=645|X3=1190|Y3=700
|RECORD=1|LibReference=MIC24052YJL-TR|ComponentDescription=No Description Available|PartCount=3|DisplayModeCount=1|IndexInSheet=231|OwnerPartId=-1|Location.X=620|Location.Y=455|CurrentPartId=1|LibraryPath=*|SourceLibraryName=MIC24052YJL-TR.SchLib|TargetFileName=*|AreaColor=11599871|Color=128|PartIDLocked=T|DesignItemId=MIC24052YJL-TR|AllPinCount=30
|RECORD=41|OwnerIndex=2423|OwnerPartId=1|Location.X=620|Location.Y=455|FontID=1|IsHidden=T|Text=Copyright (C) 2023 Ultra Librarian. All rights reserved.|Name=Copyright
|RECORD=41|OwnerIndex=2423|IndexInSheet=1|OwnerPartId=1|Location.X=620|Location.Y=455|FontID=1|IsHidden=T|Text=Microchip|Name=Mfr_Name
|RECORD=41|OwnerIndex=2423|IndexInSheet=2|OwnerPartId=1|Location.X=620|Location.Y=455|FontID=1|IsHidden=T|Text=MIC24052YJL-TR|Name=Manufacturer_Part_Number
|RECORD=41|OwnerIndex=2423|IndexInSheet=3|OwnerPartId=1|Location.X=700|Location.Y=495|FontID=1|IsHidden=T|Text=RefDes|Name=RefDes
|RECORD=41|OwnerIndex=2423|IndexInSheet=4|OwnerPartId=1|Location.X=700|Location.Y=485|FontID=1|IsHidden=T|Text=DEV|Name=Type
|RECORD=2|OwnerIndex=2423|OwnerPartId=2|FormalType=1|Electrical=4|PinConglomerate=58|PinLength=30|Location.X=650|Location.Y=455|Name=NC|Designator=3|SwapIdPin=0|SwapIDPart=0Ž&Ž1|PinPropagationDelay=0.000000E+000
|RECORD=2|OwnerIndex=2423|OwnerPartId=2|FormalType=1|Electrical=7|PinConglomerate=58|PinLength=30|Location.X=650|Location.Y=445|Name=PVDD|Designator=1|SwapIdPin=0|SwapIDPart=0Ž&Ž2|PinPropagationDelay=0.000000E+000
|RECORD=2|OwnerIndex=2423|OwnerPartId=2|FormalType=1|Electrical=7|PinConglomerate=58|PinLength=30|Location.X=650|Location.Y=435|Name=VDD|Designator=28|SwapIdPin=0|SwapIDPart=0Ž&Ž3|PinPropagationDelay=0.000000E+000
|RECORD=2|OwnerIndex=2423|OwnerPartId=2|FormalType=1|Electrical=7|PinConglomerate=58|PinLength=30|Location.X=650|Location.Y=425|Name=PGND|Designator=2|SwapIdPin=0|SwapIDPart=0Ž&Ž4|PinPropagationDelay=0.000000E+000
|RECORD=2|OwnerIndex=2423|OwnerPartId=2|FormalType=1|Electrical=7|PinConglomerate=58|PinLength=30|Location.X=650|Location.Y=415|Name=PGND|Designator=5|SwapIdPin=0|SwapIDPart=0Ž&Ž5|PinPropagationDelay=0.000000E+000
|RECORD=2|OwnerIndex=2423|OwnerPartId=2|FormalType=1|Electrical=7|PinConglomerate=58|PinLength=30|Location.X=650|Location.Y=405|Name=PGND|Designator=6|SwapIdPin=0|SwapIDPart=0Ž&Ž6|PinPropagationDelay=0.000000E+000
|RECORD=2|OwnerIndex=2423|OwnerPartId=2|FormalType=1|Electrical=7|PinConglomerate=58|PinLength=30|Location.X=650|Location.Y=395|Name=PGND|Designator=7|SwapIdPin=0|SwapIDPart=0Ž&Ž7|PinPropagationDelay=0.000000E+000
|RECORD=2|OwnerIndex=2423|OwnerPartId=2|FormalType=1|Electrical=7|PinConglomerate=58|PinLength=30|Location.X=650|Location.Y=385|Name=PGND|Designator=8|SwapIdPin=0|SwapIDPart=0Ž&Ž8|PinPropagationDelay=0.000000E+000
|RECORD=2|OwnerIndex=2423|OwnerPartId=2|FormalType=1|Electrical=7|PinConglomerate=58|PinLength=30|Location.X=650|Location.Y=375|Name=PGND|Designator=21|SwapIdPin=0|SwapIDPart=0Ž&Ž9|PinPropagationDelay=0.000000E+000
|RECORD=2|OwnerIndex=2423|OwnerPartId=2|FormalType=1|Electrical=7|PinConglomerate=58|PinLength=30|Location.X=650|Location.Y=355|Name=SGND|Designator=23|SwapIdPin=0|SwapIDPart=0Ž&Ž10|PinPropagationDelay=0.000000E+000
|RECORD=14|OwnerIndex=2423|IsNotAccesible=T|IndexInSheet=15|OwnerPartId=2|Location.X=650|Location.Y=335|Corner.X=750|Corner.Y=475|LineWidth=1|AreaColor=11599871|IsSolid=T|Transparent=T
|RECORD=4|OwnerIndex=2423|IsNotAccesible=T|IndexInSheet=16|OwnerPartId=2|Location.X=700|Location.Y=465|Justification=4|FontID=1|Text=2 of 2
|RECORD=2|OwnerIndex=2423|OwnerPartId=1|FormalType=1|PinConglomerate=58|PinLength=30|Location.X=650|Location.Y=455|Name=CS|Designator=22|SwapIdPin=0|SwapIDPart=0Ž&Ž1|PinPropagationDelay=0.000000E+000
|RECORD=2|OwnerIndex=2423|OwnerPartId=1|FormalType=1|PinConglomerate=58|PinLength=30|Location.X=650|Location.Y=445|Name=EN|Designator=26|SwapIdPin=0|SwapIDPart=0Ž&Ž2|PinPropagationDelay=0.000000E+000
|RECORD=2|OwnerIndex=2423|OwnerPartId=1|FormalType=1|PinConglomerate=58|PinLength=30|Location.X=650|Location.Y=435|Name=FB|Designator=24|SwapIdPin=0|SwapIDPart=0Ž&Ž3|PinPropagationDelay=0.000000E+000
|RECORD=2|OwnerIndex=2423|OwnerPartId=1|FormalType=1|PinConglomerate=58|PinLength=30|Location.X=650|Location.Y=415|Name=PVIN|Designator=13|SwapIdPin=0|SwapIDPart=0Ž&Ž4|PinPropagationDelay=0.000000E+000
|RECORD=2|OwnerIndex=2423|OwnerPartId=1|FormalType=1|PinConglomerate=58|PinLength=30|Location.X=650|Location.Y=405|Name=PVIN|Designator=14|SwapIdPin=0|SwapIDPart=0Ž&Ž5|PinPropagationDelay=0.000000E+000
|RECORD=2|OwnerIndex=2423|OwnerPartId=1|FormalType=1|PinConglomerate=58|PinLength=30|Location.X=650|Location.Y=395|Name=PVIN|Designator=15|SwapIdPin=0|SwapIDPart=0Ž&Ž6|PinPropagationDelay=0.000000E+000
|RECORD=2|OwnerIndex=2423|OwnerPartId=1|FormalType=1|PinConglomerate=58|PinLength=30|Location.X=650|Location.Y=385|Name=PVIN|Designator=16|SwapIdPin=0|SwapIDPart=0Ž&Ž7|PinPropagationDelay=0.000000E+000
|RECORD=2|OwnerIndex=2423|OwnerPartId=1|FormalType=1|PinConglomerate=58|PinLength=30|Location.X=650|Location.Y=375|Name=PVIN|Designator=17|SwapIdPin=0|SwapIDPart=0Ž&Ž8|PinPropagationDelay=0.000000E+000
|RECORD=2|OwnerIndex=2423|OwnerPartId=1|FormalType=1|PinConglomerate=58|PinLength=30|Location.X=650|Location.Y=365|Name=PVIN|Designator=18|SwapIdPin=0|SwapIDPart=0Ž&Ž9|PinPropagationDelay=0.000000E+000
|RECORD=2|OwnerIndex=2423|OwnerPartId=1|FormalType=1|PinConglomerate=58|PinLength=30|Location.X=650|Location.Y=355|Name=PVIN|Designator=19|SwapIdPin=0|SwapIDPart=0Ž&Ž10|PinPropagationDelay=0.000000E+000
|RECORD=2|OwnerIndex=2423|OwnerPartId=1|FormalType=1|PinConglomerate=58|PinLength=30|Location.X=650|Location.Y=335|Name=VIN|Designator=27|SwapIdPin=0|SwapIDPart=0Ž&Ž11|PinPropagationDelay=0.000000E+000
|RECORD=2|OwnerIndex=2423|OwnerPartId=1|FormalType=1|Electrical=4|PinConglomerate=58|PinLength=30|Location.X=650|Location.Y=315|Name=EPAD|Designator=29|SwapIdPin=0|SwapIDPart=0Ž&Ž12|PinPropagationDelay=0.000000E+000
|RECORD=2|OwnerIndex=2423|OwnerPartId=1|FormalType=1|Electrical=2|PinConglomerate=56|PinLength=30|Location.X=750|Location.Y=455|Name=BST|Designator=20|SwapIdPin=0|SwapIDPart=0Ž&Ž13|PinPropagationDelay=0.000000E+000
|RECORD=2|OwnerIndex=2423|OwnerPartId=1|FormalType=1|Electrical=2|PinConglomerate=56|PinLength=30|Location.X=750|Location.Y=445|Name=PG|Designator=25|SwapIdPin=0|SwapIDPart=0Ž&Ž14|PinPropagationDelay=0.000000E+000
|RECORD=2|OwnerIndex=2423|OwnerPartId=1|FormalType=1|Electrical=2|PinConglomerate=56|PinLength=30|Location.X=750|Location.Y=425|Name=SW|Designator=4|SwapIdPin=0|SwapIDPart=0Ž&Ž15|PinPropagationDelay=0.000000E+000
|RECORD=2|OwnerIndex=2423|OwnerPartId=1|FormalType=1|Electrical=2|PinConglomerate=56|PinLength=30|Location.X=750|Location.Y=415|Name=SW|Designator=9|SwapIdPin=0|SwapIDPart=0Ž&Ž16|PinPropagationDelay=0.000000E+000
|RECORD=2|OwnerIndex=2423|OwnerPartId=1|FormalType=1|Electrical=2|PinConglomerate=56|PinLength=30|Location.X=750|Location.Y=405|Name=SW|Designator=10|SwapIdPin=0|SwapIDPart=0Ž&Ž17|PinPropagationDelay=0.000000E+000
|RECORD=2|OwnerIndex=2423|OwnerPartId=1|FormalType=1|Electrical=2|PinConglomerate=56|PinLength=30|Location.X=750|Location.Y=395|Name=SW|Designator=11|SwapIdPin=0|SwapIDPart=0Ž&Ž18|PinPropagationDelay=0.000000E+000
|RECORD=2|OwnerIndex=2423|OwnerPartId=1|FormalType=1|Electrical=2|PinConglomerate=56|PinLength=30|Location.X=750|Location.Y=385|Name=SW|Designator=12|SwapIdPin=0|SwapIDPart=0Ž&Ž19|PinPropagationDelay=0.000000E+000
|RECORD=14|OwnerIndex=2423|IsNotAccesible=T|IndexInSheet=36|OwnerPartId=1|Location.X=650|Location.Y=295|Corner.X=750|Corner.Y=475|LineWidth=1|AreaColor=11599871|IsSolid=T|Transparent=T
|RECORD=4|OwnerIndex=2423|IsNotAccesible=T|IndexInSheet=37|OwnerPartId=1|Location.X=700|Location.Y=465|Justification=4|FontID=1|Text=1 of 2
|RECORD=2|OwnerIndex=2423|OwnerPartId=1|FormalType=1|Electrical=2|PinConglomerate=56|PinLength=30|Location.X=750|Location.Y=375|Name=SW|Designator=30|SwapIdPin=0|SwapIDPart=0Ž&Ž19|PinPropagationDelay=0.000000E+000
|RECORD=34|OwnerIndex=2423|IndexInSheet=-1|OwnerPartId=-1|Location.X=650|Location.Y=475|Color=8388608|FontID=1|Text=U18|Name=Designator|ReadOnlyState=1
|RECORD=41|OwnerIndex=2423|IndexInSheet=-1|OwnerPartId=-1|Location.X=650|Location.Y=285|Color=8388608|FontID=1|Text=MIC24052YJL-TR|Name=Comment
|RECORD=44|OwnerIndex=2423
|RECORD=45|OwnerIndex=2495|IndexInSheet=-1|ModelName=QFN28_5X6_MCH|ModelType=PCBLIB|DatafileCount=1|ModelDatafileEntity0=QFN28_5X6_MCH|ModelDatafileKind0=PCBLIB|IsCurrent=T
|RECORD=46|OwnerIndex=2496
|RECORD=48|OwnerIndex=2496
|RECORD=1|LibReference=MIC24052YJL-TR|ComponentDescription=No Description Available|PartCount=3|DisplayModeCount=1|IndexInSheet=232|OwnerPartId=-1|Location.X=1210|Location.Y=435|CurrentPartId=2|LibraryPath=*|SourceLibraryName=MIC24052YJL-TR.SchLib|TargetFileName=*|AreaColor=11599871|Color=128|PartIDLocked=T|DesignItemId=MIC24052YJL-TR|AllPinCount=30
|RECORD=41|OwnerIndex=2499|OwnerPartId=1|Location.X=1210|Location.Y=435|FontID=1|IsHidden=T|Text=Copyright (C) 2023 Ultra Librarian. All rights reserved.|Name=Copyright
|RECORD=41|OwnerIndex=2499|IndexInSheet=1|OwnerPartId=1|Location.X=1210|Location.Y=435|FontID=1|IsHidden=T|Text=Microchip|Name=Mfr_Name
|RECORD=41|OwnerIndex=2499|IndexInSheet=2|OwnerPartId=1|Location.X=1210|Location.Y=435|FontID=1|IsHidden=T|Text=MIC24052YJL-TR|Name=Manufacturer_Part_Number
|RECORD=41|OwnerIndex=2499|IndexInSheet=3|OwnerPartId=1|Location.X=1290|Location.Y=475|FontID=1|IsHidden=T|Text=RefDes|Name=RefDes
|RECORD=41|OwnerIndex=2499|IndexInSheet=4|OwnerPartId=1|Location.X=1290|Location.Y=465|FontID=1|IsHidden=T|Text=DEV|Name=Type
|RECORD=2|OwnerIndex=2499|OwnerPartId=2|FormalType=1|Electrical=4|PinConglomerate=58|PinLength=30|Location.X=1240|Location.Y=435|Name=NC|Designator=3|SwapIdPin=0|SwapIDPart=0Ž&Ž1|PinPropagationDelay=0.000000E+000
|RECORD=2|OwnerIndex=2499|OwnerPartId=2|FormalType=1|Electrical=7|PinConglomerate=58|PinLength=30|Location.X=1240|Location.Y=425|Name=PVDD|Designator=1|SwapIdPin=0|SwapIDPart=0Ž&Ž2|PinPropagationDelay=0.000000E+000
|RECORD=2|OwnerIndex=2499|OwnerPartId=2|FormalType=1|Electrical=7|PinConglomerate=58|PinLength=30|Location.X=1240|Location.Y=415|Name=VDD|Designator=28|SwapIdPin=0|SwapIDPart=0Ž&Ž3|PinPropagationDelay=0.000000E+000
|RECORD=2|OwnerIndex=2499|OwnerPartId=2|FormalType=1|Electrical=7|PinConglomerate=58|PinLength=30|Location.X=1240|Location.Y=405|Name=PGND|Designator=2|SwapIdPin=0|SwapIDPart=0Ž&Ž4|PinPropagationDelay=0.000000E+000
|RECORD=2|OwnerIndex=2499|OwnerPartId=2|FormalType=1|Electrical=7|PinConglomerate=58|PinLength=30|Location.X=1240|Location.Y=395|Name=PGND|Designator=5|SwapIdPin=0|SwapIDPart=0Ž&Ž5|PinPropagationDelay=0.000000E+000
|RECORD=2|OwnerIndex=2499|OwnerPartId=2|FormalType=1|Electrical=7|PinConglomerate=58|PinLength=30|Location.X=1240|Location.Y=385|Name=PGND|Designator=6|SwapIdPin=0|SwapIDPart=0Ž&Ž6|PinPropagationDelay=0.000000E+000
|RECORD=2|OwnerIndex=2499|OwnerPartId=2|FormalType=1|Electrical=7|PinConglomerate=58|PinLength=30|Location.X=1240|Location.Y=375|Name=PGND|Designator=7|SwapIdPin=0|SwapIDPart=0Ž&Ž7|PinPropagationDelay=0.000000E+000
|RECORD=2|OwnerIndex=2499|OwnerPartId=2|FormalType=1|Electrical=7|PinConglomerate=58|PinLength=30|Location.X=1240|Location.Y=365|Name=PGND|Designator=8|SwapIdPin=0|SwapIDPart=0Ž&Ž8|PinPropagationDelay=0.000000E+000
|RECORD=2|OwnerIndex=2499|OwnerPartId=2|FormalType=1|Electrical=7|PinConglomerate=58|PinLength=30|Location.X=1240|Location.Y=355|Name=PGND|Designator=21|SwapIdPin=0|SwapIDPart=0Ž&Ž9|PinPropagationDelay=0.000000E+000
|RECORD=2|OwnerIndex=2499|OwnerPartId=2|FormalType=1|Electrical=7|PinConglomerate=58|PinLength=30|Location.X=1240|Location.Y=335|Name=SGND|Designator=23|SwapIdPin=0|SwapIDPart=0Ž&Ž10|PinPropagationDelay=0.000000E+000
|RECORD=14|OwnerIndex=2499|IsNotAccesible=T|IndexInSheet=15|OwnerPartId=2|Location.X=1240|Location.Y=315|Corner.X=1340|Corner.Y=455|LineWidth=1|AreaColor=11599871|IsSolid=T|Transparent=T
|RECORD=4|OwnerIndex=2499|IsNotAccesible=T|IndexInSheet=16|OwnerPartId=2|Location.X=1290|Location.Y=445|Justification=4|FontID=1|Text=2 of 2
|RECORD=2|OwnerIndex=2499|OwnerPartId=1|FormalType=1|PinConglomerate=58|PinLength=30|Location.X=1240|Location.Y=435|Name=CS|Designator=22|SwapIdPin=0|SwapIDPart=0Ž&Ž1|PinPropagationDelay=0.000000E+000
|RECORD=2|OwnerIndex=2499|OwnerPartId=1|FormalType=1|PinConglomerate=58|PinLength=30|Location.X=1240|Location.Y=425|Name=EN|Designator=26|SwapIdPin=0|SwapIDPart=0Ž&Ž2|PinPropagationDelay=0.000000E+000
|RECORD=2|OwnerIndex=2499|OwnerPartId=1|FormalType=1|PinConglomerate=58|PinLength=30|Location.X=1240|Location.Y=415|Name=FB|Designator=24|SwapIdPin=0|SwapIDPart=0Ž&Ž3|PinPropagationDelay=0.000000E+000
|RECORD=2|OwnerIndex=2499|OwnerPartId=1|FormalType=1|PinConglomerate=58|PinLength=30|Location.X=1240|Location.Y=395|Name=PVIN|Designator=13|SwapIdPin=0|SwapIDPart=0Ž&Ž4|PinPropagationDelay=0.000000E+000
|RECORD=2|OwnerIndex=2499|OwnerPartId=1|FormalType=1|PinConglomerate=58|PinLength=30|Location.X=1240|Location.Y=385|Name=PVIN|Designator=14|SwapIdPin=0|SwapIDPart=0Ž&Ž5|PinPropagationDelay=0.000000E+000
|RECORD=2|OwnerIndex=2499|OwnerPartId=1|FormalType=1|PinConglomerate=58|PinLength=30|Location.X=1240|Location.Y=375|Name=PVIN|Designator=15|SwapIdPin=0|SwapIDPart=0Ž&Ž6|PinPropagationDelay=0.000000E+000
|RECORD=2|OwnerIndex=2499|OwnerPartId=1|FormalType=1|PinConglomerate=58|PinLength=30|Location.X=1240|Location.Y=365|Name=PVIN|Designator=16|SwapIdPin=0|SwapIDPart=0Ž&Ž7|PinPropagationDelay=0.000000E+000
|RECORD=2|OwnerIndex=2499|OwnerPartId=1|FormalType=1|PinConglomerate=58|PinLength=30|Location.X=1240|Location.Y=355|Name=PVIN|Designator=17|SwapIdPin=0|SwapIDPart=0Ž&Ž8|PinPropagationDelay=0.000000E+000
|RECORD=2|OwnerIndex=2499|OwnerPartId=1|FormalType=1|PinConglomerate=58|PinLength=30|Location.X=1240|Location.Y=345|Name=PVIN|Designator=18|SwapIdPin=0|SwapIDPart=0Ž&Ž9|PinPropagationDelay=0.000000E+000
|RECORD=2|OwnerIndex=2499|OwnerPartId=1|FormalType=1|PinConglomerate=58|PinLength=30|Location.X=1240|Location.Y=335|Name=PVIN|Designator=19|SwapIdPin=0|SwapIDPart=0Ž&Ž10|PinPropagationDelay=0.000000E+000
|RECORD=2|OwnerIndex=2499|OwnerPartId=1|FormalType=1|PinConglomerate=58|PinLength=30|Location.X=1240|Location.Y=315|Name=VIN|Designator=27|SwapIdPin=0|SwapIDPart=0Ž&Ž11|PinPropagationDelay=0.000000E+000
|RECORD=2|OwnerIndex=2499|OwnerPartId=1|FormalType=1|Electrical=4|PinConglomerate=58|PinLength=30|Location.X=1240|Location.Y=295|Name=EPAD|Designator=29|SwapIdPin=0|SwapIDPart=0Ž&Ž12|PinPropagationDelay=0.000000E+000
|RECORD=2|OwnerIndex=2499|OwnerPartId=1|FormalType=1|Electrical=2|PinConglomerate=56|PinLength=30|Location.X=1340|Location.Y=435|Name=BST|Designator=20|SwapIdPin=0|SwapIDPart=0Ž&Ž13|PinPropagationDelay=0.000000E+000
|RECORD=2|OwnerIndex=2499|OwnerPartId=1|FormalType=1|Electrical=2|PinConglomerate=56|PinLength=30|Location.X=1340|Location.Y=425|Name=PG|Designator=25|SwapIdPin=0|SwapIDPart=0Ž&Ž14|PinPropagationDelay=0.000000E+000
|RECORD=2|OwnerIndex=2499|OwnerPartId=1|FormalType=1|Electrical=2|PinConglomerate=56|PinLength=30|Location.X=1340|Location.Y=405|Name=SW|Designator=4|SwapIdPin=0|SwapIDPart=0Ž&Ž15|PinPropagationDelay=0.000000E+000
|RECORD=2|OwnerIndex=2499|OwnerPartId=1|FormalType=1|Electrical=2|PinConglomerate=56|PinLength=30|Location.X=1340|Location.Y=395|Name=SW|Designator=9|SwapIdPin=0|SwapIDPart=0Ž&Ž16|PinPropagationDelay=0.000000E+000
|RECORD=2|OwnerIndex=2499|OwnerPartId=1|FormalType=1|Electrical=2|PinConglomerate=56|PinLength=30|Location.X=1340|Location.Y=385|Name=SW|Designator=10|SwapIdPin=0|SwapIDPart=0Ž&Ž17|PinPropagationDelay=0.000000E+000
|RECORD=2|OwnerIndex=2499|OwnerPartId=1|FormalType=1|Electrical=2|PinConglomerate=56|PinLength=30|Location.X=1340|Location.Y=375|Name=SW|Designator=11|SwapIdPin=0|SwapIDPart=0Ž&Ž18|PinPropagationDelay=0.000000E+000
|RECORD=2|OwnerIndex=2499|OwnerPartId=1|FormalType=1|Electrical=2|PinConglomerate=56|PinLength=30|Location.X=1340|Location.Y=365|Name=SW|Designator=12|SwapIdPin=0|SwapIDPart=0Ž&Ž19|PinPropagationDelay=0.000000E+000
|RECORD=14|OwnerIndex=2499|IsNotAccesible=T|IndexInSheet=36|OwnerPartId=1|Location.X=1240|Location.Y=275|Corner.X=1340|Corner.Y=455|LineWidth=1|AreaColor=11599871|IsSolid=T|Transparent=T
|RECORD=4|OwnerIndex=2499|IsNotAccesible=T|IndexInSheet=37|OwnerPartId=1|Location.X=1290|Location.Y=445|Justification=4|FontID=1|Text=1 of 2
|RECORD=2|OwnerIndex=2499|OwnerPartId=1|FormalType=1|Electrical=2|PinConglomerate=56|PinLength=30|Location.X=1340|Location.Y=355|Name=SW|Designator=30|SwapIdPin=0|SwapIDPart=0Ž&Ž19|PinPropagationDelay=0.000000E+000
|RECORD=34|OwnerIndex=2499|IndexInSheet=-1|OwnerPartId=-1|Location.X=1240|Location.Y=455|Color=8388608|FontID=1|Text=U18|Name=Designator|ReadOnlyState=1
|RECORD=41|OwnerIndex=2499|IndexInSheet=-1|OwnerPartId=-1|Location.X=1240|Location.Y=305|Color=8388608|FontID=1|Text=MIC24052YJL-TR|Name=Comment
|RECORD=44|OwnerIndex=2499
|RECORD=45|OwnerIndex=2571|IndexInSheet=-1|ModelName=QFN28_5X6_MCH|ModelType=PCBLIB|DatafileCount=1|ModelDatafileEntity0=QFN28_5X6_MCH|ModelDatafileKind0=PCBLIB|IsCurrent=T
|RECORD=46|OwnerIndex=2572
|RECORD=48|OwnerIndex=2572
|RECORD=17|IndexInSheet=233|OwnerPartId=-1|Style=4|ShowNetName=T|Location.X=1200|Location.Y=315|Orientation=3|Color=128|FontID=1|Text=GND
|RECORD=1|LibReference=RES-2|ComponentDescription=Chip Resistor, 4.7 KOhm, +/- 1%, 0.1 W, -55 to 155 degC, 0402 (1005 Metric), RoHS, Tape and Reel|PartCount=2|DisplayModeCount=1|IndexInSheet=234|OwnerPartId=-1|Location.X=815|Location.Y=500|Orientation=3|CurrentPartId=1|LibraryPath=*|SourceLibraryName=Altium Content Vault|TargetFileName=*|AreaColor=11599871|Color=128|PartIDLocked=T|DesignItemId=CMP-2002-01154-4|AllPinCount=2
|RECORD=2|OwnerIndex=2576|OwnerPartId=1|FormalType=1|Electrical=4|PinConglomerate=35|PinLength=10|Location.X=815|Location.Y=480|Name=2|Designator=2|PinPropagationDelay=0.000000E+000
|RECORD=2|OwnerIndex=2576|OwnerPartId=1|FormalType=1|Electrical=4|PinConglomerate=33|PinLength=10|Location.X=815|Location.Y=500|Name=1|Designator=1|PinPropagationDelay=0.000000E+000
|RECORD=6|OwnerIndex=2576|IsNotAccesible=T|IndexInSheet=2|OwnerPartId=1|LineWidth=1|Color=16711680|LocationCount=10|X1=815|Y1=480|X2=815|Y2=484|X3=813|Y3=485|X4=817|Y4=487|X5=813|Y5=489|X6=817|Y6=491|X7=813|Y7=493|X8=817|Y8=495|X9=815|Y9=496|X10=815|Y10=500
|RECORD=41|OwnerIndex=2576|IndexInSheet=3|OwnerPartId=-1|Location.X=812|Location.Y=512|Color=8388608|FontID=1|IsHidden=T|Text=0.35 mm|Name=Height
|RECORD=41|OwnerIndex=2576|IndexInSheet=4|OwnerPartId=-1|Location.X=812|Location.Y=512|Color=8388608|FontID=1|IsHidden=T|Text=Surface Mount|Name=Mounting Technology
|RECORD=41|OwnerIndex=2576|IndexInSheet=5|OwnerPartId=-1|Location.X=812|Location.Y=512|Color=8388608|FontID=1|IsHidden=T|Text=Yes|Name=REACH SVHC
|RECORD=41|OwnerIndex=2576|IndexInSheet=6|OwnerPartId=-1|Location.X=812|Location.Y=512|Color=8388608|FontID=1|IsHidden=T|Text=4.7 KOhm|Name=Resistance
|RECORD=41|OwnerIndex=2576|IndexInSheet=7|OwnerPartId=-1|Location.X=812|Location.Y=512|Color=8388608|FontID=1|IsHidden=T|Text=155 degC|Name=Max Operating Temperature
|RECORD=41|OwnerIndex=2576|IndexInSheet=8|OwnerPartId=-1|Location.X=812|Location.Y=512|Color=8388608|FontID=1|IsHidden=T|Text=Manufacturer URL|Name=ComponentLink1Description
|RECORD=41|OwnerIndex=2576|IndexInSheet=9|OwnerPartId=-1|Location.X=812|Location.Y=512|Color=8388608|FontID=1|IsHidden=T|Text=Datasheet|Name=ComponentLink2Description
|RECORD=41|OwnerIndex=2576|IndexInSheet=10|OwnerPartId=-1|Location.X=812|Location.Y=512|Color=8388608|FontID=1|IsHidden=T|Text=2|Name=Pins
|RECORD=41|OwnerIndex=2576|IndexInSheet=11|OwnerPartId=-1|Location.X=812|Location.Y=512|Color=8388608|FontID=1|IsHidden=T|Text=0402|Name=PackageReference
|RECORD=41|OwnerIndex=2576|IndexInSheet=12|OwnerPartId=-1|Location.X=812|Location.Y=512|Color=8388608|FontID=1|IsHidden=T|Text=1%|Name=Tolerance
|RECORD=41|OwnerIndex=2576|IndexInSheet=13|OwnerPartId=-1|Location.X=812|Location.Y=512|Color=8388608|FontID=1|IsHidden=T|Text=0402|Name=Case Code (Imperial)
|RECORD=41|OwnerIndex=2576|IndexInSheet=14|OwnerPartId=-1|Location.X=812|Location.Y=512|Color=8388608|FontID=1|IsHidden=T|Text=1 mm|Name=Length
|RECORD=41|OwnerIndex=2576|IndexInSheet=15|OwnerPartId=-1|Location.X=812|Location.Y=512|Color=8388608|FontID=1|IsHidden=T|Text=2-Pin Surface Mount Device, Body 1 x 0.5 mm|Name=PackageDescription
|RECORD=41|OwnerIndex=2576|IndexInSheet=16|OwnerPartId=-1|Location.X=812|Location.Y=512|Color=8388608|FontID=1|IsHidden=T|Text=ERJ-2RKF4701X|Name=PartNumber
|RECORD=41|OwnerIndex=2576|IndexInSheet=17|OwnerPartId=-1|Location.X=812|Location.Y=512|Color=8388608|FontID=1|IsHidden=T|Text=true|Name=RoHSCompliant
|RECORD=41|OwnerIndex=2576|IndexInSheet=18|OwnerPartId=-1|Location.X=812|Location.Y=512|Color=8388608|FontID=1|IsHidden=T|Text=1|Name=Package Quantity
|RECORD=41|OwnerIndex=2576|IndexInSheet=19|OwnerPartId=-1|Location.X=812|Location.Y=512|Color=8388608|FontID=1|IsHidden=T|Text=No|Name=Radiation Hardening
|RECORD=41|OwnerIndex=2576|IndexInSheet=20|OwnerPartId=-1|Location.X=812|Location.Y=512|Color=8388608|FontID=1|IsHidden=T|Text=04/2015|Name=DatasheetVersion
|RECORD=41|OwnerIndex=2576|IndexInSheet=21|OwnerPartId=-1|Location.X=812|Location.Y=512|Color=8388608|FontID=1|IsHidden=T|Text=0.5 mm|Name=Width
|RECORD=41|OwnerIndex=2576|IndexInSheet=22|OwnerPartId=-1|Location.X=812|Location.Y=512|Color=8388608|FontID=1|IsHidden=T|Text=1005|Name=Case Code (Metric)
|RECORD=41|OwnerIndex=2576|IndexInSheet=23|OwnerPartId=-1|Location.X=812|Location.Y=512|Color=8388608|FontID=1|IsHidden=T|Text=50 V|Name=Voltage Rating
|RECORD=41|OwnerIndex=2576|IndexInSheet=24|OwnerPartId=-1|Location.X=812|Location.Y=512|Color=8388608|FontID=1|IsHidden=T|Text=0402|Name=Case\/Package
|RECORD=41|OwnerIndex=2576|IndexInSheet=25|OwnerPartId=-1|Location.X=812|Location.Y=512|Color=8388608|FontID=1|IsHidden=T|Text=Surface Mount|Name=Mount
|RECORD=41|OwnerIndex=2576|IndexInSheet=26|OwnerPartId=-1|Location.X=812|Location.Y=512|Color=8388608|FontID=7|IsHidden=T|Text=http://www.panasonic.com/|Name=ComponentLink1URL
|RECORD=41|OwnerIndex=2576|IndexInSheet=27|OwnerPartId=-1|Location.X=812|Location.Y=512|Color=8388608|FontID=1|IsHidden=T|Text=-55 degC|Name=Min Operating Temperature
|RECORD=41|OwnerIndex=2576|IndexInSheet=28|OwnerPartId=-1|Location.X=812|Location.Y=512|Color=8388608|FontID=1|IsHidden=T|Text=100 mW|Name=Power Rating
|RECORD=41|OwnerIndex=2576|IndexInSheet=29|OwnerPartId=-1|Location.X=812|Location.Y=512|Color=8388608|FontID=1|IsHidden=T|Text=Cut Tape|Name=Packaging
|RECORD=41|OwnerIndex=2576|IndexInSheet=30|OwnerPartId=-1|Location.X=812|Location.Y=512|Color=8388608|FontID=7|IsHidden=T|Text=http://industrial.panasonic.com/cdbs/www-data/pdf/RDA0000/AOA0000C86.pdf|Name=ComponentLink2URL
|RECORD=34|OwnerIndex=2576|IndexInSheet=-1|OwnerPartId=-1|Location.X=818|Location.Y=491|Color=8388608|FontID=1|Text=R68|Name=Designator|ReadOnlyState=1
|RECORD=41|OwnerIndex=2576|IndexInSheet=-1|OwnerPartId=-1|Location.X=818|Location.Y=481|Color=8388608|FontID=1|Text=4.7K_0402|Name=Comment
|RECORD=44|OwnerIndex=2576
|RECORD=45|OwnerIndex=2612|IndexInSheet=-1|Description=Chip Resistor, 2-Leads, Body 1.05x0.55mm, IPC High Density|UseComponentLibrary=T|ModelName=RESC1005X40X25LL05T05|ModelType=PCBLIB|DatafileCount=1|ModelDatafileEntity0=RESC1005X40X25LL05T05|ModelDatafileKind0=PCBLib|IsCurrent=T|DatalinksLocked=T|DatabaseDatalinksLocked=T
|RECORD=46|OwnerIndex=2613
|RECORD=48|OwnerIndex=2613
|RECORD=41|OwnerIndex=2615|IndexInSheet=-1|OwnerPartId=-1|Color=8388608|FontID=1|IsHidden=T|Text=2D|Name=Available Preview Images
|RECORD=45|OwnerIndex=2612|IndexInSheet=-1|Description=Chip Resistor, 2-Leads, Body 1.05x0.55mm, IPC Low Density|UseComponentLibrary=T|ModelName=RESC1005X40X25ML05T05|ModelType=PCBLIB|DatafileCount=1|ModelDatafileEntity0=RESC1005X40X25ML05T05|ModelDatafileKind0=PCBLib|DatalinksLocked=T|DatabaseDatalinksLocked=T
|RECORD=46|OwnerIndex=2617
|RECORD=48|OwnerIndex=2617
|RECORD=41|OwnerIndex=2619|IndexInSheet=-1|OwnerPartId=-1|Color=8388608|FontID=1|IsHidden=T|Text=2D|Name=Available Preview Images
|RECORD=45|OwnerIndex=2612|IndexInSheet=-1|Description=Chip Resistor, 2-Leads, Body 1.05x0.55mm, IPC Medium Density|UseComponentLibrary=T|ModelName=RESC1005X40X25NL05T05|ModelType=PCBLIB|DatafileCount=1|ModelDatafileEntity0=RESC1005X40X25NL05T05|ModelDatafileKind0=PCBLib|DatalinksLocked=T|DatabaseDatalinksLocked=T
|RECORD=46|OwnerIndex=2621
|RECORD=48|OwnerIndex=2621
|RECORD=41|OwnerIndex=2623|IndexInSheet=-1|OwnerPartId=-1|Color=8388608|FontID=1|IsHidden=T|Text=2D|Name=Available Preview Images
|RECORD=17|IndexInSheet=235|OwnerPartId=-1|Style=4|ShowNetName=T|Location.X=605|Location.Y=230|Orientation=3|Color=128|FontID=1|Text=GND
|RECORD=1|LibReference=RES|PartCount=2|DisplayModeCount=2|IndexInSheet=236|OwnerPartId=-1|Location.X=525|Location.Y=345|CurrentPartId=1|SourceLibraryName=Altium Content Vault|TargetFileName=*|AreaColor=11599871|Color=128|PartIDLocked=F|DesignItemId=CMP-1011-00208-2|AllPinCount=2
|RECORD=2|OwnerIndex=2626|OwnerPartId=1|OwnerPartDisplayMode=1|FormalType=1|Electrical=4|PinConglomerate=32|PinLength=10|Location.X=545|Location.Y=335|Name=2|Designator=2|PinPropagationDelay=0.000000E+000
|RECORD=2|OwnerIndex=2626|OwnerPartId=1|OwnerPartDisplayMode=1|FormalType=1|Electrical=4|PinConglomerate=34|PinLength=10|Location.X=525|Location.Y=335|Name=1|Designator=1|PinPropagationDelay=0.000000E+000
|RECORD=14|OwnerIndex=2626|IsNotAccesible=T|IndexInSheet=2|OwnerPartId=1|OwnerPartDisplayMode=1|Location.X=525|Location.Y=331|Corner.X=545|Corner.Y=339|LineWidth=1|Color=16711680|AreaColor=11599871
|RECORD=2|OwnerIndex=2626|OwnerPartId=1|FormalType=1|Electrical=4|PinConglomerate=32|PinLength=10|Location.X=545|Location.Y=335|Name=2|Designator=2|PinPropagationDelay=0.000000E+000
|RECORD=2|OwnerIndex=2626|OwnerPartId=1|FormalType=1|Electrical=4|PinConglomerate=34|PinLength=10|Location.X=525|Location.Y=335|Name=1|Designator=1|PinPropagationDelay=0.000000E+000
|RECORD=6|OwnerIndex=2626|IsNotAccesible=T|IndexInSheet=5|OwnerPartId=1|LineWidth=1|Color=16711680|LocationCount=10|X1=545|Y1=335|X2=541|Y2=335|X3=540|Y3=333|X4=538|Y4=337|X5=536|Y5=333|X6=534|Y6=337|X7=532|Y7=333|X8=530|Y8=337|X9=529|Y9=335|X10=525|Y10=335
|RECORD=41|OwnerIndex=2626|IndexInSheet=6|OwnerPartId=-1|Location.X=513|Location.Y=348|Color=8388608|FontID=1|IsHidden=T|Text=RC0402FR-072R21L|Name=Part Number
|RECORD=41|OwnerIndex=2626|IndexInSheet=7|OwnerPartId=-1|Location.X=513|Location.Y=348|Color=8388608|FontID=1|IsHidden=T|Text=Yageo|Name=Manufacturer
|RECORD=34|OwnerIndex=2626|IndexInSheet=-1|OwnerPartId=-1|Location.X=524|Location.Y=338|Color=8388608|FontID=1|Text=R74|Name=Designator|ReadOnlyState=1
|RECORD=41|OwnerIndex=2626|IndexInSheet=-1|OwnerPartId=-1|Location.X=524|Location.Y=322|Color=8388608|FontID=1|Text=2.21_1%_0402|Name=Comment
|RECORD=44|OwnerIndex=2626
|RECORD=45|OwnerIndex=2641|IndexInSheet=-1|Description=Chip Resistor, 2-Leads, Body 1.00x0.50mm, IPC Low Density|UseComponentLibrary=T|ModelName=RESC1005X40X25ML05T10|ModelType=PCBLIB|DatafileCount=1|ModelDatafileEntity0=RESC1005X40X25ML05T10|ModelDatafileKind0=PCBLib|IsCurrent=T|DatalinksLocked=T|DatabaseDatalinksLocked=T
|RECORD=46|OwnerIndex=2642
|RECORD=48|OwnerIndex=2642
|RECORD=41|OwnerIndex=2644|IndexInSheet=-1|OwnerPartId=-1|Color=8388608|FontID=1|IsHidden=T|Text=2D|Name=Available Preview Images
|RECORD=45|OwnerIndex=2641|IndexInSheet=-1|Description=Chip Resistor, 2-Leads, Body 1.00x0.50mm, IPC High Density|UseComponentLibrary=T|ModelName=RESC1005X40X25LL05T10|ModelType=PCBLIB|DatafileCount=1|ModelDatafileEntity0=RESC1005X40X25LL05T10|ModelDatafileKind0=PCBLib|DatalinksLocked=T|DatabaseDatalinksLocked=T
|RECORD=46|OwnerIndex=2646
|RECORD=48|OwnerIndex=2646
|RECORD=41|OwnerIndex=2648|IndexInSheet=-1|OwnerPartId=-1|Color=8388608|FontID=1|IsHidden=T|Text=2D|Name=Available Preview Images
|RECORD=45|OwnerIndex=2641|IndexInSheet=-1|Description=Chip Resistor, 2-Leads, Body 1.00x0.50mm, IPC Medium Density|UseComponentLibrary=T|ModelName=RESC1005X40X25NL05T10|ModelType=PCBLIB|DatafileCount=1|ModelDatafileEntity0=RESC1005X40X25NL05T10|ModelDatafileKind0=PCBLib|DatalinksLocked=T|DatabaseDatalinksLocked=T
|RECORD=46|OwnerIndex=2650
|RECORD=48|OwnerIndex=2650
|RECORD=41|OwnerIndex=2652|IndexInSheet=-1|OwnerPartId=-1|Color=8388608|FontID=1|IsHidden=T|Text=2D|Name=Available Preview Images
|RECORD=17|IndexInSheet=237|OwnerPartId=-1|ShowNetName=T|Location.X=485|Location.Y=535|Orientation=1|Color=128|FontID=1|Text=+12V
|RECORD=17|IndexInSheet=238|OwnerPartId=-1|ShowNetName=T|Location.X=815|Location.Y=525|Orientation=1|Color=128|FontID=1|Text=+3.3V
|RECORD=1|LibReference=RES-2|ComponentDescription=Chip Resistor, 4.7 KOhm, +/- 1%, 0.1 W, -55 to 155 degC, 0402 (1005 Metric), RoHS, Tape and Reel|PartCount=2|DisplayModeCount=1|IndexInSheet=239|OwnerPartId=-1|Location.X=500|Location.Y=505|Orientation=3|CurrentPartId=1|LibraryPath=*|SourceLibraryName=Altium Content Vault|TargetFileName=*|AreaColor=11599871|Color=128|PartIDLocked=T|DesignItemId=CMP-2002-01154-4|AllPinCount=2
|RECORD=2|OwnerIndex=2656|OwnerPartId=1|FormalType=1|Electrical=4|PinConglomerate=35|PinLength=10|Location.X=500|Location.Y=485|Name=2|Designator=2|PinPropagationDelay=0.000000E+000
|RECORD=2|OwnerIndex=2656|OwnerPartId=1|FormalType=1|Electrical=4|PinConglomerate=33|PinLength=10|Location.X=500|Location.Y=505|Name=1|Designator=1|PinPropagationDelay=0.000000E+000
|RECORD=6|OwnerIndex=2656|IsNotAccesible=T|IndexInSheet=2|OwnerPartId=1|LineWidth=1|Color=16711680|LocationCount=10|X1=500|Y1=485|X2=500|Y2=489|X3=498|Y3=490|X4=502|Y4=492|X5=498|Y5=494|X6=502|Y6=496|X7=498|Y7=498|X8=502|Y8=500|X9=500|Y9=501|X10=500|Y10=505
|RECORD=41|OwnerIndex=2656|IndexInSheet=3|OwnerPartId=-1|Location.X=497|Location.Y=517|Color=8388608|FontID=1|IsHidden=T|Text=0.35 mm|Name=Height
|RECORD=41|OwnerIndex=2656|IndexInSheet=4|OwnerPartId=-1|Location.X=497|Location.Y=517|Color=8388608|FontID=1|IsHidden=T|Text=Surface Mount|Name=Mounting Technology
|RECORD=41|OwnerIndex=2656|IndexInSheet=5|OwnerPartId=-1|Location.X=497|Location.Y=517|Color=8388608|FontID=1|IsHidden=T|Text=Yes|Name=REACH SVHC
|RECORD=41|OwnerIndex=2656|IndexInSheet=6|OwnerPartId=-1|Location.X=497|Location.Y=517|Color=8388608|FontID=1|IsHidden=T|Text=4.7 KOhm|Name=Resistance
|RECORD=41|OwnerIndex=2656|IndexInSheet=7|OwnerPartId=-1|Location.X=497|Location.Y=517|Color=8388608|FontID=1|IsHidden=T|Text=155 degC|Name=Max Operating Temperature
|RECORD=41|OwnerIndex=2656|IndexInSheet=8|OwnerPartId=-1|Location.X=497|Location.Y=517|Color=8388608|FontID=1|IsHidden=T|Text=Manufacturer URL|Name=ComponentLink1Description
|RECORD=41|OwnerIndex=2656|IndexInSheet=9|OwnerPartId=-1|Location.X=497|Location.Y=517|Color=8388608|FontID=1|IsHidden=T|Text=Datasheet|Name=ComponentLink2Description
|RECORD=41|OwnerIndex=2656|IndexInSheet=10|OwnerPartId=-1|Location.X=497|Location.Y=517|Color=8388608|FontID=1|IsHidden=T|Text=2|Name=Pins
|RECORD=41|OwnerIndex=2656|IndexInSheet=11|OwnerPartId=-1|Location.X=497|Location.Y=517|Color=8388608|FontID=1|IsHidden=T|Text=0402|Name=PackageReference
|RECORD=41|OwnerIndex=2656|IndexInSheet=12|OwnerPartId=-1|Location.X=497|Location.Y=517|Color=8388608|FontID=1|IsHidden=T|Text=1%|Name=Tolerance
|RECORD=41|OwnerIndex=2656|IndexInSheet=13|OwnerPartId=-1|Location.X=497|Location.Y=517|Color=8388608|FontID=1|IsHidden=T|Text=0402|Name=Case Code (Imperial)
|RECORD=41|OwnerIndex=2656|IndexInSheet=14|OwnerPartId=-1|Location.X=497|Location.Y=517|Color=8388608|FontID=1|IsHidden=T|Text=1 mm|Name=Length
|RECORD=41|OwnerIndex=2656|IndexInSheet=15|OwnerPartId=-1|Location.X=497|Location.Y=517|Color=8388608|FontID=1|IsHidden=T|Text=2-Pin Surface Mount Device, Body 1 x 0.5 mm|Name=PackageDescription
|RECORD=41|OwnerIndex=2656|IndexInSheet=16|OwnerPartId=-1|Location.X=497|Location.Y=517|Color=8388608|FontID=1|IsHidden=T|Text=ERJ-2RKF4701X|Name=PartNumber
|RECORD=41|OwnerIndex=2656|IndexInSheet=17|OwnerPartId=-1|Location.X=497|Location.Y=517|Color=8388608|FontID=1|IsHidden=T|Text=true|Name=RoHSCompliant
|RECORD=41|OwnerIndex=2656|IndexInSheet=18|OwnerPartId=-1|Location.X=497|Location.Y=517|Color=8388608|FontID=1|IsHidden=T|Text=1|Name=Package Quantity
|RECORD=41|OwnerIndex=2656|IndexInSheet=19|OwnerPartId=-1|Location.X=497|Location.Y=517|Color=8388608|FontID=1|IsHidden=T|Text=No|Name=Radiation Hardening
|RECORD=41|OwnerIndex=2656|IndexInSheet=20|OwnerPartId=-1|Location.X=497|Location.Y=517|Color=8388608|FontID=1|IsHidden=T|Text=04/2015|Name=DatasheetVersion
|RECORD=41|OwnerIndex=2656|IndexInSheet=21|OwnerPartId=-1|Location.X=497|Location.Y=517|Color=8388608|FontID=1|IsHidden=T|Text=0.5 mm|Name=Width
|RECORD=41|OwnerIndex=2656|IndexInSheet=22|OwnerPartId=-1|Location.X=497|Location.Y=517|Color=8388608|FontID=1|IsHidden=T|Text=1005|Name=Case Code (Metric)
|RECORD=41|OwnerIndex=2656|IndexInSheet=23|OwnerPartId=-1|Location.X=497|Location.Y=517|Color=8388608|FontID=1|IsHidden=T|Text=50 V|Name=Voltage Rating
|RECORD=41|OwnerIndex=2656|IndexInSheet=24|OwnerPartId=-1|Location.X=497|Location.Y=517|Color=8388608|FontID=1|IsHidden=T|Text=0402|Name=Case\/Package
|RECORD=41|OwnerIndex=2656|IndexInSheet=25|OwnerPartId=-1|Location.X=497|Location.Y=517|Color=8388608|FontID=1|IsHidden=T|Text=Surface Mount|Name=Mount
|RECORD=41|OwnerIndex=2656|IndexInSheet=26|OwnerPartId=-1|Location.X=497|Location.Y=517|Color=8388608|FontID=7|IsHidden=T|Text=http://www.panasonic.com/|Name=ComponentLink1URL
|RECORD=41|OwnerIndex=2656|IndexInSheet=27|OwnerPartId=-1|Location.X=497|Location.Y=517|Color=8388608|FontID=1|IsHidden=T|Text=-55 degC|Name=Min Operating Temperature
|RECORD=41|OwnerIndex=2656|IndexInSheet=28|OwnerPartId=-1|Location.X=497|Location.Y=517|Color=8388608|FontID=1|IsHidden=T|Text=100 mW|Name=Power Rating
|RECORD=41|OwnerIndex=2656|IndexInSheet=29|OwnerPartId=-1|Location.X=497|Location.Y=517|Color=8388608|FontID=1|IsHidden=T|Text=Cut Tape|Name=Packaging
|RECORD=41|OwnerIndex=2656|IndexInSheet=30|OwnerPartId=-1|Location.X=497|Location.Y=517|Color=8388608|FontID=7|IsHidden=T|Text=http://industrial.panasonic.com/cdbs/www-data/pdf/RDA0000/AOA0000C86.pdf|Name=ComponentLink2URL
|RECORD=34|OwnerIndex=2656|IndexInSheet=-1|OwnerPartId=-1|Location.X=503|Location.Y=496|Color=8388608|FontID=1|Text=R67|Name=Designator|ReadOnlyState=1
|RECORD=41|OwnerIndex=2656|IndexInSheet=-1|OwnerPartId=-1|Location.X=503|Location.Y=486|Color=8388608|FontID=1|Text=4.7K_0402|Name=Comment
|RECORD=44|OwnerIndex=2656
|RECORD=45|OwnerIndex=2692|IndexInSheet=-1|Description=Chip Resistor, 2-Leads, Body 1.05x0.55mm, IPC High Density|UseComponentLibrary=T|ModelName=RESC1005X40X25LL05T05|ModelType=PCBLIB|DatafileCount=1|ModelDatafileEntity0=RESC1005X40X25LL05T05|ModelDatafileKind0=PCBLib|IsCurrent=T|DatalinksLocked=T|DatabaseDatalinksLocked=T
|RECORD=46|OwnerIndex=2693
|RECORD=48|OwnerIndex=2693
|RECORD=41|OwnerIndex=2695|IndexInSheet=-1|OwnerPartId=-1|Color=8388608|FontID=1|IsHidden=T|Text=2D|Name=Available Preview Images
|RECORD=45|OwnerIndex=2692|IndexInSheet=-1|Description=Chip Resistor, 2-Leads, Body 1.05x0.55mm, IPC Low Density|UseComponentLibrary=T|ModelName=RESC1005X40X25ML05T05|ModelType=PCBLIB|DatafileCount=1|ModelDatafileEntity0=RESC1005X40X25ML05T05|ModelDatafileKind0=PCBLib|DatalinksLocked=T|DatabaseDatalinksLocked=T
|RECORD=46|OwnerIndex=2697
|RECORD=48|OwnerIndex=2697
|RECORD=41|OwnerIndex=2699|IndexInSheet=-1|OwnerPartId=-1|Color=8388608|FontID=1|IsHidden=T|Text=2D|Name=Available Preview Images
|RECORD=45|OwnerIndex=2692|IndexInSheet=-1|Description=Chip Resistor, 2-Leads, Body 1.05x0.55mm, IPC Medium Density|UseComponentLibrary=T|ModelName=RESC1005X40X25NL05T05|ModelType=PCBLIB|DatafileCount=1|ModelDatafileEntity0=RESC1005X40X25NL05T05|ModelDatafileKind0=PCBLib|DatalinksLocked=T|DatabaseDatalinksLocked=T
|RECORD=46|OwnerIndex=2701
|RECORD=48|OwnerIndex=2701
|RECORD=41|OwnerIndex=2703|IndexInSheet=-1|OwnerPartId=-1|Color=8388608|FontID=1|IsHidden=T|Text=2D|Name=Available Preview Images
|RECORD=1|LibReference=RES|ComponentDescription=1R21 0.063W 1% 0402 (1005 Metric)  SMD|PartCount=2|DisplayModeCount=2|IndexInSheet=240|OwnerPartId=-1|Location.X=845|Location.Y=465|CurrentPartId=1|SourceLibraryName=Altium Content Vault|TargetFileName=*|AreaColor=11599871|Color=128|PartIDLocked=F|DesignItemId=CMP-1011-00180-1|AllPinCount=2
|RECORD=2|OwnerIndex=2705|OwnerPartId=1|OwnerPartDisplayMode=1|FormalType=1|Electrical=4|PinConglomerate=32|PinLength=10|Location.X=865|Location.Y=455|Name=2|Designator=2|PinPropagationDelay=0.000000E+000
|RECORD=2|OwnerIndex=2705|OwnerPartId=1|OwnerPartDisplayMode=1|FormalType=1|Electrical=4|PinConglomerate=34|PinLength=10|Location.X=845|Location.Y=455|Name=1|Designator=1|PinPropagationDelay=0.000000E+000
|RECORD=14|OwnerIndex=2705|IsNotAccesible=T|IndexInSheet=2|OwnerPartId=1|OwnerPartDisplayMode=1|Location.X=845|Location.Y=451|Corner.X=865|Corner.Y=459|LineWidth=1|Color=16711680|AreaColor=11599871
|RECORD=2|OwnerIndex=2705|OwnerPartId=1|FormalType=1|Electrical=4|PinConglomerate=32|PinLength=10|Location.X=865|Location.Y=455|Name=2|Designator=2|PinPropagationDelay=0.000000E+000
|RECORD=2|OwnerIndex=2705|OwnerPartId=1|FormalType=1|Electrical=4|PinConglomerate=34|PinLength=10|Location.X=845|Location.Y=455|Name=1|Designator=1|PinPropagationDelay=0.000000E+000
|RECORD=6|OwnerIndex=2705|IsNotAccesible=T|IndexInSheet=5|OwnerPartId=1|LineWidth=1|Color=16711680|LocationCount=10|X1=865|Y1=455|X2=861|Y2=455|X3=860|Y3=453|X4=858|Y4=457|X5=856|Y5=453|X6=854|Y6=457|X7=852|Y7=453|X8=850|Y8=457|X9=849|Y9=455|X10=845|Y10=455
|RECORD=41|OwnerIndex=2705|IndexInSheet=6|OwnerPartId=-1|Location.X=833|Location.Y=468|Color=8388608|FontID=1|IsHidden=T|Text=1 %|Name=Tolerance
|RECORD=41|OwnerIndex=2705|IndexInSheet=7|OwnerPartId=-1|Location.X=833|Location.Y=468|Color=8388608|FontID=1|IsHidden=T|Text=0402|Name=Case-EIA
|RECORD=41|OwnerIndex=2705|IndexInSheet=8|OwnerPartId=-1|Location.X=833|Location.Y=468|Color=8388608|FontID=1|IsHidden=T|Text=1.21 Ohm|Name=Value
|RECORD=41|OwnerIndex=2705|IndexInSheet=9|OwnerPartId=-1|Location.X=833|Location.Y=468|Color=8388608|FontID=1|IsHidden=T|Text=1005|Name=Case-Metric
|RECORD=41|OwnerIndex=2705|IndexInSheet=10|OwnerPartId=-1|Location.X=833|Location.Y=468|Color=8388608|FontID=1|IsHidden=T|Text=0.063 W|Name=Power
|RECORD=41|OwnerIndex=2705|IndexInSheet=11|OwnerPartId=-1|Location.X=833|Location.Y=468|Color=8388608|FontID=1|IsHidden=T|Text=SMT|Name=Technology
|RECORD=34|OwnerIndex=2705|IndexInSheet=-1|OwnerPartId=-1|Location.X=844|Location.Y=458|Color=8388608|FontID=1|Text=R69|Name=Designator|ReadOnlyState=1
|RECORD=41|OwnerIndex=2705|IndexInSheet=-1|OwnerPartId=-1|Location.X=844|Location.Y=442|Color=8388608|FontID=1|Text=1.21_1%_0402|Name=Comment
|RECORD=44|OwnerIndex=2705
|RECORD=45|OwnerIndex=2724|IndexInSheet=-1|Description=Chip Resistor, Body 1.0x0.5mm, IPC Medium Density|UseComponentLibrary=T|ModelName=RESC0402(1005)_N|ModelType=PCBLIB|DatafileCount=1|ModelDatafileEntity0=RESC0402(1005)_N|ModelDatafileKind0=PCBLib|IsCurrent=T|DatalinksLocked=T|DatabaseDatalinksLocked=T
|RECORD=46|OwnerIndex=2725
|RECORD=48|OwnerIndex=2725
|RECORD=41|OwnerIndex=2727|IndexInSheet=-1|OwnerPartId=-1|Color=8388608|FontID=1|IsHidden=T|Text=2D|Name=Available Preview Images
|RECORD=45|OwnerIndex=2724|IndexInSheet=-1|Description=Chip Resistor, Body 1.0x0.5mm, IPC Low Density|UseComponentLibrary=T|ModelName=RESC0402(1005)_M|ModelType=PCBLIB|DatafileCount=1|ModelDatafileEntity0=RESC0402(1005)_M|ModelDatafileKind0=PCBLib|DatalinksLocked=T|DatabaseDatalinksLocked=T
|RECORD=46|OwnerIndex=2729
|RECORD=48|OwnerIndex=2729
|RECORD=41|OwnerIndex=2731|IndexInSheet=-1|OwnerPartId=-1|Color=8388608|FontID=1|IsHidden=T|Text=2D|Name=Available Preview Images
|RECORD=45|OwnerIndex=2724|IndexInSheet=-1|Description=Chip Resistor, Body 1.0x0.5mm, IPC High Density|UseComponentLibrary=T|ModelName=RESC0402(1005)_L|ModelType=PCBLIB|DatafileCount=1|ModelDatafileEntity0=RESC0402(1005)_L|ModelDatafileKind0=PCBLib|DatalinksLocked=T|DatabaseDatalinksLocked=T
|RECORD=46|OwnerIndex=2733
|RECORD=48|OwnerIndex=2733
|RECORD=41|OwnerIndex=2735|IndexInSheet=-1|OwnerPartId=-1|Color=8388608|FontID=1|IsHidden=T|Text=2D|Name=Available Preview Images
|RECORD=1|LibReference=b4654b650e69147ec39a6b967a45e02|ComponentDescription=General Purpose Ceramic Capacitor, 0402, 100nF, 10%, X7R, 15%, 25V|PartCount=2|DisplayModeCount=1|IndexInSheet=241|OwnerPartId=-1|Location.X=565|Location.Y=315|CurrentPartId=1|LibraryPath=*|SourceLibraryName=Altium Content Vault|TargetFileName=*|AreaColor=11599871|Color=128|PartIDLocked=T|DesignItemId=CMP-2008-02519-2|AllPinCount=2
|RECORD=2|OwnerIndex=2737|OwnerPartId=1|Electrical=4|PinConglomerate=49|PinLength=7|Location.X=565|Location.Y=308|Name=1|Designator=1|PinPropagationDelay=0.000000E+000
|RECORD=2|OwnerIndex=2737|OwnerPartId=1|Electrical=4|PinConglomerate=51|PinLength=6|Location.X=565|Location.Y=301|Name=2|Designator=2|PinPropagationDelay=0.000000E+000
|RECORD=13|OwnerIndex=2737|IsNotAccesible=T|IndexInSheet=2|OwnerPartId=1|Location.X=575|Location.Y=308|Corner.X=555|Corner.Y=308|LineWidth=1|Color=16711680
|RECORD=13|OwnerIndex=2737|IsNotAccesible=T|IndexInSheet=3|OwnerPartId=1|Location.X=575|Location.Y=302|Corner.X=555|Corner.Y=302|LineWidth=1|Color=16711680
|RECORD=13|OwnerIndex=2737|IsNotAccesible=T|IndexInSheet=4|OwnerPartId=1|Location.X=565|Location.Y=308|Corner.X=565|Corner.Y=311|LineWidth=1|Color=16711680
|RECORD=13|OwnerIndex=2737|IsNotAccesible=T|IndexInSheet=5|OwnerPartId=1|Location.X=565|Location.Y=301|Corner.X=565|Corner.Y=300|LineWidth=1|Color=16711680
|RECORD=41|OwnerIndex=2737|IndexInSheet=6|OwnerPartId=-1|Location.X=554|Location.Y=317|Color=8388608|FontID=1|IsHidden=T|Text=1|Name=Package Quantity
|RECORD=41|OwnerIndex=2737|IndexInSheet=7|OwnerPartId=-1|Location.X=554|Location.Y=317|Color=8388608|FontID=1|IsHidden=T|Text=100nF|Name=Capacitance
|RECORD=41|OwnerIndex=2737|IndexInSheet=8|OwnerPartId=-1|Location.X=554|Location.Y=317|Color=8388608|FontID=1|IsHidden=T|Text=-55°C|Name=Min Operating Temperature
|RECORD=41|OwnerIndex=2737|IndexInSheet=9|OwnerPartId=-1|Location.X=554|Location.Y=317|Color=8388608|FontID=1|IsHidden=T|Text=25V|Name=Voltage
|RECORD=41|OwnerIndex=2737|IndexInSheet=10|OwnerPartId=-1|Location.X=554|Location.Y=317|Color=8388608|FontID=1|IsHidden=T|Text=25V|Name=Voltage Rating
|RECORD=41|OwnerIndex=2737|IndexInSheet=11|OwnerPartId=-1|Location.X=554|Location.Y=317|Color=8388608|FontID=1|IsHidden=T|Text=Flat|Name=Construction
|RECORD=41|OwnerIndex=2737|IndexInSheet=12|OwnerPartId=-1|Location.X=554|Location.Y=317|Color=8388608|FontID=1|IsHidden=T|Text=125°C|Name=Max Operating Temperature
|RECORD=41|OwnerIndex=2737|IndexInSheet=13|OwnerPartId=-1|Location.X=554|Location.Y=317|Color=8388608|FontID=1|IsHidden=T|Text=No|Name=Radiation Hardening
|RECORD=41|OwnerIndex=2737|IndexInSheet=14|OwnerPartId=-1|Location.X=554|Location.Y=317|Color=8388608|FontID=1|IsHidden=T|Text=0.5mm|Name=Depth
|RECORD=41|OwnerIndex=2737|IndexInSheet=15|OwnerPartId=-1|Location.X=554|Location.Y=317|Color=8388608|FontID=1|IsHidden=T|Text=0.022inch|Name=Thickness
|RECORD=41|OwnerIndex=2737|IndexInSheet=16|OwnerPartId=-1|Location.X=554|Location.Y=317|Color=8388608|FontID=1|IsHidden=T|Text=25V|Name=Voltage Rating (DC)
|RECORD=41|OwnerIndex=2737|IndexInSheet=17|OwnerPartId=-1|Location.X=554|Location.Y=317|Color=8388608|FontID=1|IsHidden=T|Text=2|Name=Number of Pins
|RECORD=41|OwnerIndex=2737|IndexInSheet=18|OwnerPartId=-1|Location.X=554|Location.Y=317|Color=8388608|FontID=1|IsHidden=T|Text=Lead Free|Name=Lead Free
|RECORD=41|OwnerIndex=2737|IndexInSheet=19|OwnerPartId=-1|Location.X=554|Location.Y=317|Color=8388608|FontID=1|IsHidden=T|Text=-|Name=Series
|RECORD=41|OwnerIndex=2737|IndexInSheet=20|OwnerPartId=-1|Location.X=554|Location.Y=317|Color=8388608|FontID=1|IsHidden=T|Text=No SVHC|Name=REACH SVHC
|RECORD=41|OwnerIndex=2737|IndexInSheet=21|OwnerPartId=-1|Location.X=554|Location.Y=317|Color=8388608|FontID=1|IsHidden=T|Text=1mm|Name=Length
|RECORD=41|OwnerIndex=2737|IndexInSheet=22|OwnerPartId=-1|Location.X=554|Location.Y=317|Color=8388608|FontID=1|IsHidden=T|Text=X7R|Name=Dielectric
|RECORD=41|OwnerIndex=2737|IndexInSheet=23|OwnerPartId=-1|Location.X=554|Location.Y=317|Color=8388608|FontID=1|IsHidden=T|Text=Yes|Name=RoHS Compliant
|RECORD=41|OwnerIndex=2737|IndexInSheet=24|OwnerPartId=-1|Location.X=554|Location.Y=317|Color=8388608|FontID=1|IsHidden=T|Text=Surface Mount|Name=Mount
|RECORD=41|OwnerIndex=2737|IndexInSheet=25|OwnerPartId=-1|Location.X=554|Location.Y=317|Color=8388608|FontID=1|IsHidden=T|Text=Tape and Reel|Name=Packaging
|RECORD=41|OwnerIndex=2737|IndexInSheet=26|OwnerPartId=-1|Location.X=554|Location.Y=317|Color=8388608|FontID=1|IsHidden=T|Text=0402|Name=Case/Package
|RECORD=41|OwnerIndex=2737|IndexInSheet=27|OwnerPartId=-1|Location.X=554|Location.Y=317|Color=8388608|FontID=1|IsHidden=T|Text=0402|Name=Case Code (Imperial)
|RECORD=41|OwnerIndex=2737|IndexInSheet=28|OwnerPartId=-1|Location.X=554|Location.Y=317|Color=8388608|FontID=1|IsHidden=T|Text=SMD/SMT|Name=Termination
|RECORD=41|OwnerIndex=2737|IndexInSheet=29|OwnerPartId=-1|Location.X=554|Location.Y=317|Color=8388608|FontID=1|IsHidden=T|Text=0.02inch|Name=Width
|RECORD=41|OwnerIndex=2737|IndexInSheet=30|OwnerPartId=-1|Location.X=554|Location.Y=317|Color=8388608|FontID=1|IsHidden=T|Text=1005|Name=Case Code (Metric)
|RECORD=41|OwnerIndex=2737|IndexInSheet=31|OwnerPartId=-1|Location.X=554|Location.Y=317|Color=8388608|FontID=1|IsHidden=T|Text=10%|Name=Tolerance
|RECORD=34|OwnerIndex=2737|IndexInSheet=-1|OwnerPartId=-1|Location.X=576|Location.Y=302|Color=8388608|FontID=1|Text=C71|Name=Designator|ReadOnlyState=1
|RECORD=41|OwnerIndex=2737|IndexInSheet=-1|OwnerPartId=1|Location.X=575|Location.Y=290|Color=8388608|FontID=1|Text=0.1uF_25V_0402|Name=Comment
|RECORD=44|OwnerIndex=2737
|RECORD=45|OwnerIndex=2774|IndexInSheet=-1|UseComponentLibrary=T|ModelName=FP-0402-L_1_0_1-W_0_5_0_1-IPC_C|ModelType=PCBLIB|DatafileCount=1|ModelDatafileEntity0=FP-0402-L_1_0_1-W_0_5_0_1-IPC_C|ModelDatafileKind0=PCBLib|IsCurrent=T|DatalinksLocked=T|DatabaseDatalinksLocked=T
|RECORD=46|OwnerIndex=2775
|RECORD=48|OwnerIndex=2775
|RECORD=45|OwnerIndex=2774|IndexInSheet=-1|UseComponentLibrary=T|ModelName=FP-0402-L_1_0_1-W_0_5_0_1-IPC_B|ModelType=PCBLIB|DatafileCount=1|ModelDatafileEntity0=FP-0402-L_1_0_1-W_0_5_0_1-IPC_B|ModelDatafileKind0=PCBLib|DatalinksLocked=T|DatabaseDatalinksLocked=T
|RECORD=46|OwnerIndex=2778
|RECORD=48|OwnerIndex=2778
|RECORD=45|OwnerIndex=2774|IndexInSheet=-1|UseComponentLibrary=T|ModelName=FP-0402-L_1_0_1-W_0_5_0_1-MFG|ModelType=PCBLIB|DatafileCount=1|ModelDatafileEntity0=FP-0402-L_1_0_1-W_0_5_0_1-MFG|ModelDatafileKind0=PCBLib|DatalinksLocked=T|DatabaseDatalinksLocked=T
|RECORD=46|OwnerIndex=2781
|RECORD=48|OwnerIndex=2781
|RECORD=45|OwnerIndex=2774|IndexInSheet=-1|UseComponentLibrary=T|ModelName=FP-0402-L_1_0_1-W_0_5_0_1-IPC_A|ModelType=PCBLIB|DatafileCount=1|ModelDatafileEntity0=FP-0402-L_1_0_1-W_0_5_0_1-IPC_A|ModelDatafileKind0=PCBLib|DatalinksLocked=T|DatabaseDatalinksLocked=T
|RECORD=46|OwnerIndex=2784
|RECORD=48|OwnerIndex=2784
|RECORD=1|LibReference=RES|PartCount=2|DisplayModeCount=2|IndexInSheet=242|OwnerPartId=-1|Location.X=870|Location.Y=395|Orientation=2|CurrentPartId=1|SourceLibraryName=Altium Content Vault|TargetFileName=*|AreaColor=11599871|Color=128|PartIDLocked=F|DesignItemId=CMP-1011-00208-2|AllPinCount=2
|RECORD=2|OwnerIndex=2787|OwnerPartId=1|OwnerPartDisplayMode=1|FormalType=1|Electrical=4|PinConglomerate=34|PinLength=10|Location.X=850|Location.Y=405|Name=2|Designator=2|PinPropagationDelay=0.000000E+000
|RECORD=2|OwnerIndex=2787|OwnerPartId=1|OwnerPartDisplayMode=1|FormalType=1|Electrical=4|PinConglomerate=32|PinLength=10|Location.X=870|Location.Y=405|Name=1|Designator=1|PinPropagationDelay=0.000000E+000
|RECORD=14|OwnerIndex=2787|IsNotAccesible=T|IndexInSheet=2|OwnerPartId=1|OwnerPartDisplayMode=1|Location.X=850|Location.Y=401|Corner.X=870|Corner.Y=409|LineWidth=1|Color=16711680|AreaColor=11599871
|RECORD=2|OwnerIndex=2787|OwnerPartId=1|FormalType=1|Electrical=4|PinConglomerate=34|PinLength=10|Location.X=850|Location.Y=405|Name=2|Designator=2|PinPropagationDelay=0.000000E+000
|RECORD=2|OwnerIndex=2787|OwnerPartId=1|FormalType=1|Electrical=4|PinConglomerate=32|PinLength=10|Location.X=870|Location.Y=405|Name=1|Designator=1|PinPropagationDelay=0.000000E+000
|RECORD=6|OwnerIndex=2787|IsNotAccesible=T|IndexInSheet=5|OwnerPartId=1|LineWidth=1|Color=16711680|LocationCount=10|X1=850|Y1=405|X2=854|Y2=405|X3=855|Y3=407|X4=857|Y4=403|X5=859|Y5=407|X6=861|Y6=403|X7=863|Y7=407|X8=865|Y8=403|X9=866|Y9=405|X10=870|Y10=405
|RECORD=41|OwnerIndex=2787|IndexInSheet=6|OwnerPartId=-1|Location.X=838|Location.Y=408|Color=8388608|FontID=1|IsHidden=T|Text=RC0402FR-072R21L|Name=Part Number
|RECORD=41|OwnerIndex=2787|IndexInSheet=7|OwnerPartId=-1|Location.X=838|Location.Y=408|Color=8388608|FontID=1|IsHidden=T|Text=Yageo|Name=Manufacturer
|RECORD=34|OwnerIndex=2787|IndexInSheet=-1|OwnerPartId=-1|Location.X=849|Location.Y=408|Color=8388608|FontID=1|Text=R71|Name=Designator|ReadOnlyState=1
|RECORD=41|OwnerIndex=2787|IndexInSheet=-1|OwnerPartId=-1|Location.X=849|Location.Y=392|Color=8388608|FontID=1|Text=2.21_1%_0402|Name=Comment
|RECORD=44|OwnerIndex=2787
|RECORD=45|OwnerIndex=2802|IndexInSheet=-1|Description=Chip Resistor, 2-Leads, Body 1.00x0.50mm, IPC Low Density|UseComponentLibrary=T|ModelName=RESC1005X40X25ML05T10|ModelType=PCBLIB|DatafileCount=1|ModelDatafileEntity0=RESC1005X40X25ML05T10|ModelDatafileKind0=PCBLib|IsCurrent=T|DatalinksLocked=T|DatabaseDatalinksLocked=T
|RECORD=46|OwnerIndex=2803
|RECORD=48|OwnerIndex=2803
|RECORD=41|OwnerIndex=2805|IndexInSheet=-1|OwnerPartId=-1|Color=8388608|FontID=1|IsHidden=T|Text=2D|Name=Available Preview Images
|RECORD=45|OwnerIndex=2802|IndexInSheet=-1|Description=Chip Resistor, 2-Leads, Body 1.00x0.50mm, IPC High Density|UseComponentLibrary=T|ModelName=RESC1005X40X25LL05T10|ModelType=PCBLIB|DatafileCount=1|ModelDatafileEntity0=RESC1005X40X25LL05T10|ModelDatafileKind0=PCBLib|DatalinksLocked=T|DatabaseDatalinksLocked=T
|RECORD=46|OwnerIndex=2807
|RECORD=48|OwnerIndex=2807
|RECORD=41|OwnerIndex=2809|IndexInSheet=-1|OwnerPartId=-1|Color=8388608|FontID=1|IsHidden=T|Text=2D|Name=Available Preview Images
|RECORD=45|OwnerIndex=2802|IndexInSheet=-1|Description=Chip Resistor, 2-Leads, Body 1.00x0.50mm, IPC Medium Density|UseComponentLibrary=T|ModelName=RESC1005X40X25NL05T10|ModelType=PCBLIB|DatafileCount=1|ModelDatafileEntity0=RESC1005X40X25NL05T10|ModelDatafileKind0=PCBLib|DatalinksLocked=T|DatabaseDatalinksLocked=T
|RECORD=46|OwnerIndex=2811
|RECORD=48|OwnerIndex=2811
|RECORD=41|OwnerIndex=2813|IndexInSheet=-1|OwnerPartId=-1|Color=8388608|FontID=1|IsHidden=T|Text=2D|Name=Available Preview Images
|RECORD=1|LibReference=725321dda6339637d4d059423bc1c3c|ComponentDescription=Commercial Inductors, High Saturation Series 2.2uH 10A 13.6mO 20%|PartCount=2|DisplayModeCount=1|IndexInSheet=243|OwnerPartId=-1|Location.X=935|Location.Y=375|CurrentPartId=1|LibraryPath=*|SourceLibraryName=Altium Content Vault|TargetFileName=*|AreaColor=11599871|Color=128|PartIDLocked=T|DesignItemId=CMP-02424-000315-1|AllPinCount=2
|RECORD=2|OwnerIndex=2815|OwnerPartId=1|Electrical=4|PinConglomerate=50|PinLength=5|Location.X=940|Location.Y=375|Name=1|Designator=1|PinPropagationDelay=0.000000E+000
|RECORD=2|OwnerIndex=2815|OwnerPartId=1|Electrical=4|PinConglomerate=48|PinLength=5|Location.X=970|Location.Y=375|Name=2|Designator=2|PinPropagationDelay=0.000000E+000
|RECORD=12|OwnerIndex=2815|IsNotAccesible=T|IndexInSheet=2|OwnerPartId=1|Location.X=945|Location.Y=375|Radius=5|LineWidth=1|EndAngle=-180.000|Color=16711680
|RECORD=12|OwnerIndex=2815|IsNotAccesible=T|IndexInSheet=3|OwnerPartId=1|Location.X=955|Location.Y=375|Radius=5|LineWidth=1|EndAngle=-180.000|Color=16711680
|RECORD=12|OwnerIndex=2815|IsNotAccesible=T|IndexInSheet=4|OwnerPartId=1|Location.X=965|Location.Y=375|Radius=5|LineWidth=1|EndAngle=-180.000|Color=16711680
|RECORD=13|OwnerIndex=2815|IsNotAccesible=T|IndexInSheet=5|OwnerPartId=1|Location.X=940|Location.Y=375|Corner.X=938|Corner.Y=375|LineWidth=1|Color=16711680
|RECORD=13|OwnerIndex=2815|IsNotAccesible=T|IndexInSheet=6|OwnerPartId=1|Location.X=970|Location.Y=375|Corner.X=971|Corner.Y=375|LineWidth=1|Color=16711680
|RECORD=41|OwnerIndex=2815|IndexInSheet=7|OwnerPartId=-1|Location.X=933|Location.Y=380|Color=8388608|FontID=1|IsHidden=T|Text=Ferrite|Name=Core Material
|RECORD=41|OwnerIndex=2815|IndexInSheet=8|OwnerPartId=-1|Location.X=933|Location.Y=380|Color=8388608|FontID=1|IsHidden=T|Text=Shielded|Name=Shielding
|RECORD=41|OwnerIndex=2815|IndexInSheet=9|OwnerPartId=-1|Location.X=933|Location.Y=380|Color=8388608|FontID=1|IsHidden=T|Text=20%|Name=Tolerance
|RECORD=41|OwnerIndex=2815|IndexInSheet=10|OwnerPartId=-1|Location.X=933|Location.Y=380|Color=8388608|FontID=1|IsHidden=T|Text=7.24mm|Name=Length
|RECORD=41|OwnerIndex=2815|IndexInSheet=11|OwnerPartId=-1|Location.X=933|Location.Y=380|Color=8388608|FontID=1|IsHidden=T|Text=10A|Name=Current Rating
|RECORD=41|OwnerIndex=2815|IndexInSheet=12|OwnerPartId=-1|Location.X=933|Location.Y=380|Color=8388608|FontID=1|IsHidden=T|Text=2.2uH|Name=Inductance
|RECORD=41|OwnerIndex=2815|IndexInSheet=13|OwnerPartId=-1|Location.X=933|Location.Y=380|Color=8388608|FontID=1|IsHidden=T|Text=-55°C|Name=Min Operating Temperature
|RECORD=41|OwnerIndex=2815|IndexInSheet=14|OwnerPartId=-1|Location.X=933|Location.Y=380|Color=8388608|FontID=1|IsHidden=T|Text=20%|Name=Inductance Tolerance
|RECORD=41|OwnerIndex=2815|IndexInSheet=15|OwnerPartId=-1|Location.X=933|Location.Y=380|Color=8388608|FontID=1|IsHidden=T|Text=500|Name=Package Quantity
|RECORD=41|OwnerIndex=2815|IndexInSheet=16|OwnerPartId=-1|Location.X=933|Location.Y=380|Color=8388608|FontID=1|IsHidden=T|Text=Tin|Name=Contact Plating
|RECORD=41|OwnerIndex=2815|IndexInSheet=17|OwnerPartId=-1|Location.X=933|Location.Y=380|Color=8388608|FontID=1|IsHidden=T|Text=SMD/SMT|Name=Termination
|RECORD=41|OwnerIndex=2815|IndexInSheet=18|OwnerPartId=-1|Location.X=933|Location.Y=380|Color=8388608|FontID=1|IsHidden=T|Text=Tape and Reel|Name=Packaging
|RECORD=41|OwnerIndex=2815|IndexInSheet=19|OwnerPartId=-1|Location.X=933|Location.Y=380|Color=8388608|FontID=1|IsHidden=T|Text=5mm|Name=Height
|RECORD=41|OwnerIndex=2815|IndexInSheet=20|OwnerPartId=-1|Location.X=933|Location.Y=380|Color=8388608|FontID=1|IsHidden=T|Text=1MHz|Name=Self Resonant Frequency
|RECORD=41|OwnerIndex=2815|IndexInSheet=21|OwnerPartId=-1|Location.X=933|Location.Y=380|Color=8388608|FontID=1|IsHidden=T|Text=125°C|Name=Max Operating Temperature
|RECORD=41|OwnerIndex=2815|IndexInSheet=22|OwnerPartId=-1|Location.X=933|Location.Y=380|Color=8388608|FontID=1|IsHidden=T|Text=2525|Name=Case/Package
|RECORD=41|OwnerIndex=2815|IndexInSheet=23|OwnerPartId=-1|Location.X=933|Location.Y=380|Color=8388608|FontID=1|IsHidden=T|Text=13.6mR|Name=DC Resistance (DCR)
|RECORD=41|OwnerIndex=2815|IndexInSheet=24|OwnerPartId=-1|Location.X=933|Location.Y=380|Color=8388608|FontID=1|IsHidden=T|Text=10A|Name=Saturation Current
|RECORD=41|OwnerIndex=2815|IndexInSheet=25|OwnerPartId=-1|Location.X=933|Location.Y=380|Color=8388608|FontID=1|IsHidden=T|Text=Surface Mount|Name=Mount
|RECORD=41|OwnerIndex=2815|IndexInSheet=26|OwnerPartId=-1|Location.X=933|Location.Y=380|Color=8388608|FontID=1|IsHidden=T|Text=Not|Name=Military Standard
|RECORD=41|OwnerIndex=2815|IndexInSheet=27|OwnerPartId=-1|Location.X=933|Location.Y=380|Color=8388608|FontID=1|IsHidden=T|Text=No|Name=Radiation Hardening
|RECORD=41|OwnerIndex=2815|IndexInSheet=28|OwnerPartId=-1|Location.X=933|Location.Y=380|Color=8388608|FontID=1|IsHidden=T|Text=6.72mm|Name=Depth
|RECORD=41|OwnerIndex=2815|IndexInSheet=29|OwnerPartId=-1|Location.X=933|Location.Y=380|Color=8388608|FontID=1|IsHidden=T|Text=100kHz|Name=Test Frequency
|RECORD=41|OwnerIndex=2815|IndexInSheet=30|OwnerPartId=-1|Location.X=933|Location.Y=380|Color=8388608|FontID=1|IsHidden=T|Text=10A|Name=Max DC Current
|RECORD=41|OwnerIndex=2815|IndexInSheet=31|OwnerPartId=-1|Location.X=933|Location.Y=380|Color=8388608|FontID=1|IsHidden=T|Text=Lead Free|Name=Lead Free
|RECORD=41|OwnerIndex=2815|IndexInSheet=32|OwnerPartId=-1|Location.X=933|Location.Y=380|Color=8388608|FontID=1|IsHidden=T|Text=10A|Name=RMS Current (Irms)
|RECORD=41|OwnerIndex=2815|IndexInSheet=33|OwnerPartId=-1|Location.X=933|Location.Y=380|Color=8388608|FontID=1|IsHidden=T|Text=6.47mm|Name=Width
|RECORD=41|OwnerIndex=2815|IndexInSheet=34|OwnerPartId=-1|Location.X=933|Location.Y=380|Color=8388608|FontID=1|IsHidden=T|Text=0.197inch|Name=Height - Seated (Max)
|RECORD=34|OwnerIndex=2815|IndexInSheet=-1|OwnerPartId=-1|Location.X=937|Location.Y=380|Color=8388608|FontID=1|Text=L2|Name=Designator|ReadOnlyState=1
|RECORD=41|OwnerIndex=2815|IndexInSheet=-1|OwnerPartId=1|Location.X=937|Location.Y=362|Color=8388608|FontID=1|Text=2.2uH_10A|Name=Comment
|RECORD=44|OwnerIndex=2815
|RECORD=45|OwnerIndex=2855|IndexInSheet=-1|UseComponentLibrary=T|ModelName=FP-IHLP-2525EZ-FP_2_413x3-MFG|ModelType=PCBLIB|DatafileCount=1|ModelDatafileEntity0=FP-IHLP-2525EZ-FP_2_413x3-MFG|ModelDatafileKind0=PCBLib|IsCurrent=T|DatalinksLocked=T|DatabaseDatalinksLocked=T
|RECORD=46|OwnerIndex=2856
|RECORD=48|OwnerIndex=2856
|RECORD=1|LibReference=11868f565c42a9108669ba33697ecf6|ComponentDescription=CAP CER 0.1UF 50V X7R 0603|PartCount=2|DisplayModeCount=1|IndexInSheet=244|OwnerPartId=-1|Location.X=915|Location.Y=445|CurrentPartId=1|LibraryPath=*|SourceLibraryName=Altium Content Vault|TargetFileName=*|AreaColor=11599871|Color=128|PartIDLocked=T|DesignItemId=CMP-2100-03601-2|AllPinCount=2
|RECORD=2|OwnerIndex=2859|OwnerPartId=1|Electrical=4|PinConglomerate=49|PinLength=7|Location.X=915|Location.Y=438|Name=1|Designator=1|PinPropagationDelay=0.000000E+000
|RECORD=2|OwnerIndex=2859|OwnerPartId=1|Electrical=4|PinConglomerate=51|PinLength=6|Location.X=915|Location.Y=431|Name=2|Designator=2|PinPropagationDelay=0.000000E+000
|RECORD=13|OwnerIndex=2859|IsNotAccesible=T|IndexInSheet=2|OwnerPartId=1|Location.X=925|Location.Y=438|Corner.X=905|Corner.Y=438|LineWidth=1|Color=16711680
|RECORD=13|OwnerIndex=2859|IsNotAccesible=T|IndexInSheet=3|OwnerPartId=1|Location.X=925|Location.Y=432|Corner.X=905|Corner.Y=432|LineWidth=1|Color=16711680
|RECORD=13|OwnerIndex=2859|IsNotAccesible=T|IndexInSheet=4|OwnerPartId=1|Location.X=915|Location.Y=438|Corner.X=915|Corner.Y=441|LineWidth=1|Color=16711680
|RECORD=13|OwnerIndex=2859|IsNotAccesible=T|IndexInSheet=5|OwnerPartId=1|Location.X=915|Location.Y=431|Corner.X=915|Corner.Y=430|LineWidth=1|Color=16711680
|RECORD=41|OwnerIndex=2859|IndexInSheet=6|OwnerPartId=-1|Location.X=904|Location.Y=447|Color=8388608|FontID=1|IsHidden=T|Text=0.9mm|Name=Height
|RECORD=41|OwnerIndex=2859|IndexInSheet=7|OwnerPartId=-1|Location.X=904|Location.Y=447|Color=8388608|FontID=1|IsHidden=T|Text=Ceramic|Name=Material
|RECORD=41|OwnerIndex=2859|IndexInSheet=8|OwnerPartId=-1|Location.X=904|Location.Y=447|Color=8388608|FontID=1|IsHidden=T|Text=YAGEO|Name=Manufacturer
|RECORD=41|OwnerIndex=2859|IndexInSheet=9|OwnerPartId=-1|Location.X=904|Location.Y=447|Color=8388608|FontID=1|IsHidden=T|Text=50 V|Name=Voltage
|RECORD=41|OwnerIndex=2859|IndexInSheet=10|OwnerPartId=-1|Location.X=904|Location.Y=447|Color=8388608|FontID=1|IsHidden=T|Text=Datasheet|Name=ComponentLink2Description
|RECORD=41|OwnerIndex=2859|IndexInSheet=11|OwnerPartId=-1|Location.X=904|Location.Y=447|Color=8388608|FontID=1|IsHidden=T|Text=Capacitors|Name=Device Class L2
|RECORD=41|OwnerIndex=2859|IndexInSheet=12|OwnerPartId=-1|Location.X=904|Location.Y=447|Color=8388608|FontID=1|IsHidden=T|Text=+125°C|Name=Temperature Range High
|RECORD=41|OwnerIndex=2859|IndexInSheet=13|OwnerPartId=-1|Location.X=904|Location.Y=447|Color=8388608|FontID=1|IsHidden=T|Text=Cap|Name=Category
|RECORD=41|OwnerIndex=2859|IndexInSheet=14|OwnerPartId=-1|Location.X=904|Location.Y=447|Color=8388608|FontID=1|IsHidden=T|Text=100 nF|Name=Capacitance
|RECORD=41|OwnerIndex=2859|IndexInSheet=15|OwnerPartId=-1|Location.X=904|Location.Y=447|Color=8388608|FontID=7|IsHidden=T|Text=http://www.yageo.com/exep/pages/download/literatures/UPY-C_GEN_24.pdf|Name=Footprint Url
|RECORD=41|OwnerIndex=2859|IndexInSheet=16|OwnerPartId=-1|Location.X=904|Location.Y=447|Color=8388608|FontID=7|IsHidden=T|Text=http://www.yageo.com/documents/recent/UPY-GPHC_X7R_6.3V-to-50V_18.pdf|Name=ComponentLink2URL
|RECORD=41|OwnerIndex=2859|IndexInSheet=17|OwnerPartId=-1|Location.X=904|Location.Y=447|Color=8388608|FontID=1|IsHidden=T|Text=CC0603-DA|Name=Package
|RECORD=41|OwnerIndex=2859|IndexInSheet=18|OwnerPartId=-1|Location.X=904|Location.Y=447|Color=8388608|FontID=1|IsHidden=T|Text=-55°C to +125°C|Name=Temperature
|RECORD=41|OwnerIndex=2859|IndexInSheet=19|OwnerPartId=-1|Location.X=904|Location.Y=447|Color=8388608|FontID=1|IsHidden=T|Text=15%|Name=Temperature Coefficient
|RECORD=41|OwnerIndex=2859|IndexInSheet=20|OwnerPartId=-1|Location.X=904|Location.Y=447|Color=8388608|FontID=1|IsHidden=T|Text=50 V|Name=Voltage Rating
|RECORD=41|OwnerIndex=2859|IndexInSheet=21|OwnerPartId=-1|Location.X=904|Location.Y=447|Color=8388608|FontID=1|IsHidden=T|Text=X7R|Name=Temperature Characteristic
|RECORD=41|OwnerIndex=2859|IndexInSheet=22|OwnerPartId=-1|Location.X=904|Location.Y=447|Color=8388608|FontID=1|IsHidden=T|Text=Passive Components|Name=Device Class L1
|RECORD=41|OwnerIndex=2859|IndexInSheet=23|OwnerPartId=-1|Location.X=904|Location.Y=447|Color=8388608|FontID=1|IsHidden=T|Text=-55°C|Name=Temperature Range Low
|RECORD=41|OwnerIndex=2859|IndexInSheet=24|OwnerPartId=-1|Location.X=904|Location.Y=447|Color=8388608|FontID=1|IsHidden=T|Text=CC0603KRX7R9BB104|Name=Manufacturer Part Number
|RECORD=41|OwnerIndex=2859|IndexInSheet=25|OwnerPartId=-1|Location.X=904|Location.Y=447|Color=8388608|FontID=1|IsHidden=T|Text=TRUE|Name=RoHS
|RECORD=41|OwnerIndex=2859|IndexInSheet=26|OwnerPartId=-1|Location.X=904|Location.Y=447|Color=8388608|FontID=1|IsHidden=T|Text=0.1|Name=Tolerance
|RECORD=41|OwnerIndex=2859|IndexInSheet=27|OwnerPartId=-1|Location.X=904|Location.Y=447|Color=8388608|FontID=1|IsHidden=T|Text=No|Name=Automotive
|RECORD=41|OwnerIndex=2859|IndexInSheet=28|OwnerPartId=-1|Location.X=904|Location.Y=447|Color=8388608|FontID=1|IsHidden=T|Text=100 nF|Name=Value
|RECORD=41|OwnerIndex=2859|IndexInSheet=29|OwnerPartId=-1|Location.X=904|Location.Y=447|Color=8388608|FontID=1|IsHidden=T|Text=Ceramic Capacitors|Name=Device Class L3
|RECORD=41|OwnerIndex=2859|IndexInSheet=30|OwnerPartId=-1|Location.X=904|Location.Y=447|Color=8388608|FontID=7|IsHidden=T|Text=https://octopart.com/cc0603krx7r9bb104-yageo-42244635|Name=Octopart
|RECORD=41|OwnerIndex=2859|IndexInSheet=31|OwnerPartId=-1|Location.X=904|Location.Y=447|Color=8388608|FontID=1|IsHidden=T|Text=Multilayer Ceramic Capacitor, CC Series, 0.1 - F, - 10%, X7R, 50 V, 0603 [1608 Metric]|Name=Mouser Description
|RECORD=41|OwnerIndex=2859|IndexInSheet=32|OwnerPartId=-1|Location.X=904|Location.Y=447|Color=8388608|FontID=1|IsHidden=T|Text=Yes|Name=Lead Free
|RECORD=41|OwnerIndex=2859|IndexInSheet=33|OwnerPartId=-1|Location.X=904|Location.Y=447|Color=8388608|FontID=1|IsHidden=T|Text=CAP CER 0.1UF 50V X7R 0603|Name=Digikey Description
|RECORD=34|OwnerIndex=2859|IndexInSheet=-1|OwnerPartId=-1|Location.X=926|Location.Y=432|Color=8388608|FontID=1|Text=C68|Name=Designator|ReadOnlyState=1
|RECORD=41|OwnerIndex=2859|IndexInSheet=-1|OwnerPartId=1|Location.X=926|Location.Y=422|Color=8388608|FontID=1|Text=0.1uF_50V_0603|Name=Comment
|RECORD=44|OwnerIndex=2859
|RECORD=45|OwnerIndex=2898|IndexInSheet=-1|UseComponentLibrary=T|ModelName=FP-CC0603-DA-MFG|ModelType=PCBLIB|DatafileCount=1|ModelDatafileEntity0=FP-CC0603-DA-MFG|ModelDatafileKind0=PCBLib|IsCurrent=T|DatalinksLocked=T|DatabaseDatalinksLocked=T
|RECORD=46|OwnerIndex=2899
|RECORD=48|OwnerIndex=2899
|RECORD=45|OwnerIndex=2898|IndexInSheet=-1|UseComponentLibrary=T|ModelName=FP-CC0603-DA-IPC_C|ModelType=PCBLIB|DatafileCount=1|ModelDatafileEntity0=FP-CC0603-DA-IPC_C|ModelDatafileKind0=PCBLib|DatalinksLocked=T|DatabaseDatalinksLocked=T
|RECORD=46|OwnerIndex=2902
|RECORD=48|OwnerIndex=2902
|RECORD=45|OwnerIndex=2898|IndexInSheet=-1|UseComponentLibrary=T|ModelName=FP-CC0603-DA-IPC_B|ModelType=PCBLIB|DatafileCount=1|ModelDatafileEntity0=FP-CC0603-DA-IPC_B|ModelDatafileKind0=PCBLib|DatalinksLocked=T|DatabaseDatalinksLocked=T
|RECORD=46|OwnerIndex=2905
|RECORD=48|OwnerIndex=2905
|RECORD=45|OwnerIndex=2898|IndexInSheet=-1|UseComponentLibrary=T|ModelName=FP-CC0603-DA-IPC_A|ModelType=PCBLIB|DatafileCount=1|ModelDatafileEntity0=FP-CC0603-DA-IPC_A|ModelDatafileKind0=PCBLib|DatalinksLocked=T|DatabaseDatalinksLocked=T
|RECORD=46|OwnerIndex=2908
|RECORD=48|OwnerIndex=2908
|RECORD=1|LibReference=b4654b650e69147ec39a6b967a45e02|ComponentDescription=None|PartCount=2|DisplayModeCount=1|IndexInSheet=245|OwnerPartId=-1|Location.X=1120|Location.Y=355|CurrentPartId=1|LibraryPath=*|SourceLibraryName=Altium Content Vault|TargetFileName=*|AreaColor=11599871|Color=128|PartIDLocked=T|DesignItemId=CMP-14477-000104-2|AllPinCount=2
|RECORD=2|OwnerIndex=2911|OwnerPartId=1|Electrical=4|PinConglomerate=49|PinLength=7|Location.X=1120|Location.Y=348|Name=1|Designator=1|PinPropagationDelay=0.000000E+000
|RECORD=2|OwnerIndex=2911|OwnerPartId=1|Electrical=4|PinConglomerate=51|PinLength=6|Location.X=1120|Location.Y=341|Name=2|Designator=2|PinPropagationDelay=0.000000E+000
|RECORD=13|OwnerIndex=2911|IsNotAccesible=T|IndexInSheet=2|OwnerPartId=1|Location.X=1130|Location.Y=348|Corner.X=1110|Corner.Y=348|LineWidth=1|Color=16711680
|RECORD=13|OwnerIndex=2911|IsNotAccesible=T|IndexInSheet=3|OwnerPartId=1|Location.X=1130|Location.Y=342|Corner.X=1110|Corner.Y=342|LineWidth=1|Color=16711680
|RECORD=13|OwnerIndex=2911|IsNotAccesible=T|IndexInSheet=4|OwnerPartId=1|Location.X=1120|Location.Y=348|Corner.X=1120|Corner.Y=351|LineWidth=1|Color=16711680
|RECORD=13|OwnerIndex=2911|IsNotAccesible=T|IndexInSheet=5|OwnerPartId=1|Location.X=1120|Location.Y=341|Corner.X=1120|Corner.Y=340|LineWidth=1|Color=16711680
|RECORD=41|OwnerIndex=2911|IndexInSheet=6|OwnerPartId=-1|Location.X=1109|Location.Y=357|Color=8388608|FontID=1|IsHidden=T|Text=Tape and Reel|Name=Packaging
|RECORD=41|OwnerIndex=2911|IndexInSheet=7|OwnerPartId=-1|Location.X=1109|Location.Y=357|Color=8388608|FontID=1|IsHidden=T|Text=0.5mm|Name=Depth
|RECORD=41|OwnerIndex=2911|IndexInSheet=8|OwnerPartId=-1|Location.X=1109|Location.Y=357|Color=8388608|FontID=1|IsHidden=T|Text=10%|Name=Tolerance
|RECORD=41|OwnerIndex=2911|IndexInSheet=9|OwnerPartId=-1|Location.X=1109|Location.Y=357|Color=8388608|FontID=1|IsHidden=T|Text=Surface Mount|Name=Mount
|RECORD=41|OwnerIndex=2911|IndexInSheet=10|OwnerPartId=-1|Location.X=1109|Location.Y=357|Color=8388608|FontID=1|IsHidden=T|Text=16V|Name=Voltage Rating
|RECORD=41|OwnerIndex=2911|IndexInSheet=11|OwnerPartId=-1|Location.X=1109|Location.Y=357|Color=8388608|FontID=1|IsHidden=T|Text=0.022inch|Name=Thickness
|RECORD=41|OwnerIndex=2911|IndexInSheet=12|OwnerPartId=-1|Location.X=1109|Location.Y=357|Color=8388608|FontID=1|IsHidden=T|Text=1|Name=Package Quantity
|RECORD=41|OwnerIndex=2911|IndexInSheet=13|OwnerPartId=-1|Location.X=1109|Location.Y=357|Color=8388608|FontID=1|IsHidden=T|Text=-55°C|Name=Min Operating Temperature
|RECORD=41|OwnerIndex=2911|IndexInSheet=14|OwnerPartId=-1|Location.X=1109|Location.Y=357|Color=8388608|FontID=1|IsHidden=T|Text=M|Name=Series
|RECORD=41|OwnerIndex=2911|IndexInSheet=15|OwnerPartId=-1|Location.X=1109|Location.Y=357|Color=8388608|FontID=1|IsHidden=T|Text=16V|Name=Voltage Rating (DC)
|RECORD=41|OwnerIndex=2911|IndexInSheet=16|OwnerPartId=-1|Location.X=1109|Location.Y=357|Color=8388608|FontID=1|IsHidden=T|Text=SMD/SMT|Name=Termination
|RECORD=41|OwnerIndex=2911|IndexInSheet=17|OwnerPartId=-1|Location.X=1109|Location.Y=357|Color=8388608|FontID=1|IsHidden=T|Text=0402|Name=Case/Package
|RECORD=41|OwnerIndex=2911|IndexInSheet=18|OwnerPartId=-1|Location.X=1109|Location.Y=357|Color=8388608|FontID=1|IsHidden=T|Text=X5R|Name=Dielectric
|RECORD=41|OwnerIndex=2911|IndexInSheet=19|OwnerPartId=-1|Location.X=1109|Location.Y=357|Color=8388608|FontID=1|IsHidden=T|Text=2|Name=Number of Pins
|RECORD=41|OwnerIndex=2911|IndexInSheet=20|OwnerPartId=-1|Location.X=1109|Location.Y=357|Color=8388608|FontID=1|IsHidden=T|Text=0402|Name=Case Code (Imperial)
|RECORD=41|OwnerIndex=2911|IndexInSheet=21|OwnerPartId=-1|Location.X=1109|Location.Y=357|Color=8388608|FontID=1|IsHidden=T|Text=1uF|Name=Capacitance
|RECORD=41|OwnerIndex=2911|IndexInSheet=22|OwnerPartId=-1|Location.X=1109|Location.Y=357|Color=8388608|FontID=1|IsHidden=T|Text=1mm|Name=Length
|RECORD=41|OwnerIndex=2911|IndexInSheet=23|OwnerPartId=-1|Location.X=1109|Location.Y=357|Color=8388608|FontID=1|IsHidden=T|Text=Halogen Free|Name=Halogen Free
|RECORD=41|OwnerIndex=2911|IndexInSheet=24|OwnerPartId=-1|Location.X=1109|Location.Y=357|Color=8388608|FontID=1|IsHidden=T|Text=1005|Name=Case Code (Metric)
|RECORD=41|OwnerIndex=2911|IndexInSheet=25|OwnerPartId=-1|Location.X=1109|Location.Y=357|Color=8388608|FontID=1|IsHidden=T|Text=0.02inch|Name=Width
|RECORD=41|OwnerIndex=2911|IndexInSheet=26|OwnerPartId=-1|Location.X=1109|Location.Y=357|Color=8388608|FontID=1|IsHidden=T|Text=Yes|Name=RoHS Compliant
|RECORD=41|OwnerIndex=2911|IndexInSheet=27|OwnerPartId=-1|Location.X=1109|Location.Y=357|Color=8388608|FontID=1|IsHidden=T|Text=No|Name=Radiation Hardening
|RECORD=41|OwnerIndex=2911|IndexInSheet=28|OwnerPartId=-1|Location.X=1109|Location.Y=357|Color=8388608|FontID=1|IsHidden=T|Text=85°C|Name=Max Operating Temperature
|RECORD=41|OwnerIndex=2911|IndexInSheet=29|OwnerPartId=-1|Location.X=1109|Location.Y=357|Color=8388608|FontID=1|IsHidden=T|Text=0.5mm|Name=Height
|RECORD=41|OwnerIndex=2911|IndexInSheet=30|OwnerPartId=-1|Location.X=1109|Location.Y=357|Color=8388608|FontID=1|IsHidden=T|Text=Flat|Name=Construction
|RECORD=34|OwnerIndex=2911|IndexInSheet=-1|OwnerPartId=-1|Location.X=1105|Location.Y=335|Orientation=1|Color=8388608|FontID=2|Text=C69|Name=Designator|ReadOnlyState=1
|RECORD=41|OwnerIndex=2911|IndexInSheet=-1|OwnerPartId=1|Location.X=1140|Location.Y=320|Orientation=1|Color=8388608|FontID=2|Text=1uF_16V_0402|Name=Comment
|RECORD=44|OwnerIndex=2911
|RECORD=45|OwnerIndex=2947|IndexInSheet=-1|UseComponentLibrary=T|ModelName=FP-0402-L_1_0_0_05-W_0_5-IPC_A|ModelType=PCBLIB|DatafileCount=1|ModelDatafileEntity0=FP-0402-L_1_0_0_05-W_0_5-IPC_A|ModelDatafileKind0=PCBLib|IsCurrent=T|DatalinksLocked=T|DatabaseDatalinksLocked=T
|RECORD=46|OwnerIndex=2948
|RECORD=48|OwnerIndex=2948
|RECORD=45|OwnerIndex=2947|IndexInSheet=-1|UseComponentLibrary=T|ModelName=EMK105BJ105_V-F|ModelType=SIM|IsCurrent=T|DatalinksLocked=T|DatabaseDatalinksLocked=T
|RECORD=46|OwnerIndex=2951
|RECORD=48|OwnerIndex=2951
|RECORD=41|OwnerIndex=2953|IndexInSheet=-1|OwnerPartId=-1|Color=8388608|FontID=1|IsHidden=T|Text=General|Name=Kind
|RECORD=41|OwnerIndex=2953|IndexInSheet=-1|OwnerPartId=-1|Color=8388608|FontID=1|IsHidden=T|Text=Spice Subcircuit|Name=SubKind
|RECORD=41|OwnerIndex=2953|IndexInSheet=-1|OwnerPartId=-1|Color=8388608|FontID=1|IsHidden=T|Name=Spice Prefix
|RECORD=41|OwnerIndex=2953|IndexInSheet=-1|OwnerPartId=-1|Color=8388608|FontID=1|IsHidden=T|Name=Excluded Parts
|RECORD=41|OwnerIndex=2953|IndexInSheet=-1|OwnerPartId=-1|Color=8388608|FontID=1|IsHidden=T|Name=Netlist
|RECORD=41|OwnerIndex=2953|IndexInSheet=-1|OwnerPartId=-1|Color=8388608|FontID=1|IsHidden=T|Text=document_sim_cache\GNEMVTBT\0|Name=SimulationCacheLocation|ReadOnlyState=3
|RECORD=45|OwnerIndex=2947|IndexInSheet=-1|UseComponentLibrary=T|ModelName=FP-0402-L_1_0_0_05-W_0_5-IPC_B|ModelType=PCBLIB|DatafileCount=1|ModelDatafileEntity0=FP-0402-L_1_0_0_05-W_0_5-IPC_B|ModelDatafileKind0=PCBLib|DatalinksLocked=T|DatabaseDatalinksLocked=T
|RECORD=46|OwnerIndex=2960
|RECORD=48|OwnerIndex=2960
|RECORD=45|OwnerIndex=2947|IndexInSheet=-1|UseComponentLibrary=T|ModelName=FP-0402-L_1_0_0_05-W_0_5-IPC_C|ModelType=PCBLIB|DatafileCount=1|ModelDatafileEntity0=FP-0402-L_1_0_0_05-W_0_5-IPC_C|ModelDatafileKind0=PCBLib|DatalinksLocked=T|DatabaseDatalinksLocked=T
|RECORD=46|OwnerIndex=2963
|RECORD=48|OwnerIndex=2963
|RECORD=45|OwnerIndex=2947|IndexInSheet=-1|UseComponentLibrary=T|ModelName=FP-0402-L_1_0_0_05-W_0_5-MFG|ModelType=PCBLIB|DatafileCount=1|ModelDatafileEntity0=FP-0402-L_1_0_0_05-W_0_5-MFG|ModelDatafileKind0=PCBLib|DatalinksLocked=T|DatabaseDatalinksLocked=T
|RECORD=46|OwnerIndex=2966
|RECORD=48|OwnerIndex=2966
|RECORD=17|IndexInSheet=246|OwnerPartId=-1|ShowNetName=T|Location.X=1195|Location.Y=465|Orientation=1|Color=128|FontID=1|Text=P3V3_PVDD
|RECORD=17|IndexInSheet=247|OwnerPartId=-1|ShowNetName=T|Location.X=1130|Location.Y=465|Orientation=1|Color=128|FontID=1|Text=P3V3_VDD
|RECORD=17|IndexInSheet=248|OwnerPartId=-1|ShowNetName=T|Location.X=960|Location.Y=470|Orientation=1|Color=128|FontID=1|Text=P3V3_VDD
|RECORD=1|LibReference=RES|ComponentDescription=1R21 0.063W 1% 0402 (1005 Metric)  SMD|PartCount=2|DisplayModeCount=2|IndexInSheet=249|OwnerPartId=-1|Location.X=995|Location.Y=455|CurrentPartId=1|SourceLibraryName=Altium Content Vault|TargetFileName=*|AreaColor=11599871|Color=128|PartIDLocked=F|DesignItemId=CMP-1011-00180-1|AllPinCount=2
|RECORD=2|OwnerIndex=2972|OwnerPartId=1|OwnerPartDisplayMode=1|FormalType=1|Electrical=4|PinConglomerate=32|PinLength=10|Location.X=1015|Location.Y=445|Name=2|Designator=2|PinPropagationDelay=0.000000E+000
|RECORD=2|OwnerIndex=2972|OwnerPartId=1|OwnerPartDisplayMode=1|FormalType=1|Electrical=4|PinConglomerate=34|PinLength=10|Location.X=995|Location.Y=445|Name=1|Designator=1|PinPropagationDelay=0.000000E+000
|RECORD=14|OwnerIndex=2972|IsNotAccesible=T|IndexInSheet=2|OwnerPartId=1|OwnerPartDisplayMode=1|Location.X=995|Location.Y=441|Corner.X=1015|Corner.Y=449|LineWidth=1|Color=16711680|AreaColor=11599871
|RECORD=2|OwnerIndex=2972|OwnerPartId=1|FormalType=1|Electrical=4|PinConglomerate=32|PinLength=10|Location.X=1015|Location.Y=445|Name=2|Designator=2|PinPropagationDelay=0.000000E+000
|RECORD=2|OwnerIndex=2972|OwnerPartId=1|FormalType=1|Electrical=4|PinConglomerate=34|PinLength=10|Location.X=995|Location.Y=445|Name=1|Designator=1|PinPropagationDelay=0.000000E+000
|RECORD=6|OwnerIndex=2972|IsNotAccesible=T|IndexInSheet=5|OwnerPartId=1|LineWidth=1|Color=16711680|LocationCount=10|X1=1015|Y1=445|X2=1011|Y2=445|X3=1010|Y3=443|X4=1008|Y4=447|X5=1006|Y5=443|X6=1004|Y6=447|X7=1002|Y7=443|X8=1000|Y8=447|X9=999|Y9=445|X10=995|Y10=445
|RECORD=41|OwnerIndex=2972|IndexInSheet=6|OwnerPartId=-1|Location.X=983|Location.Y=458|Color=8388608|FontID=1|IsHidden=T|Text=1 %|Name=Tolerance
|RECORD=41|OwnerIndex=2972|IndexInSheet=7|OwnerPartId=-1|Location.X=983|Location.Y=458|Color=8388608|FontID=1|IsHidden=T|Text=0402|Name=Case-EIA
|RECORD=41|OwnerIndex=2972|IndexInSheet=8|OwnerPartId=-1|Location.X=983|Location.Y=458|Color=8388608|FontID=1|IsHidden=T|Text=1.21 Ohm|Name=Value
|RECORD=41|OwnerIndex=2972|IndexInSheet=9|OwnerPartId=-1|Location.X=983|Location.Y=458|Color=8388608|FontID=1|IsHidden=T|Text=1005|Name=Case-Metric
|RECORD=41|OwnerIndex=2972|IndexInSheet=10|OwnerPartId=-1|Location.X=983|Location.Y=458|Color=8388608|FontID=1|IsHidden=T|Text=0.063 W|Name=Power
|RECORD=41|OwnerIndex=2972|IndexInSheet=11|OwnerPartId=-1|Location.X=983|Location.Y=458|Color=8388608|FontID=1|IsHidden=T|Text=SMT|Name=Technology
|RECORD=34|OwnerIndex=2972|IndexInSheet=-1|OwnerPartId=-1|Location.X=970|Location.Y=445|Color=8388608|FontID=1|Text=R70|Name=Designator|ReadOnlyState=1
|RECORD=41|OwnerIndex=2972|IndexInSheet=-1|OwnerPartId=-1|Location.X=1010|Location.Y=445|Color=8388608|FontID=1|Text=1.21_1%_0402|Name=Comment
|RECORD=44|OwnerIndex=2972
|RECORD=45|OwnerIndex=2991|IndexInSheet=-1|Description=Chip Resistor, Body 1.0x0.5mm, IPC Medium Density|UseComponentLibrary=T|ModelName=RESC0402(1005)_N|ModelType=PCBLIB|DatafileCount=1|ModelDatafileEntity0=RESC0402(1005)_N|ModelDatafileKind0=PCBLib|IsCurrent=T|DatalinksLocked=T|DatabaseDatalinksLocked=T
|RECORD=46|OwnerIndex=2992
|RECORD=48|OwnerIndex=2992
|RECORD=41|OwnerIndex=2994|IndexInSheet=-1|OwnerPartId=-1|Color=8388608|FontID=1|IsHidden=T|Text=2D|Name=Available Preview Images
|RECORD=45|OwnerIndex=2991|IndexInSheet=-1|Description=Chip Resistor, Body 1.0x0.5mm, IPC Low Density|UseComponentLibrary=T|ModelName=RESC0402(1005)_M|ModelType=PCBLIB|DatafileCount=1|ModelDatafileEntity0=RESC0402(1005)_M|ModelDatafileKind0=PCBLib|DatalinksLocked=T|DatabaseDatalinksLocked=T
|RECORD=46|OwnerIndex=2996
|RECORD=48|OwnerIndex=2996
|RECORD=41|OwnerIndex=2998|IndexInSheet=-1|OwnerPartId=-1|Color=8388608|FontID=1|IsHidden=T|Text=2D|Name=Available Preview Images
|RECORD=45|OwnerIndex=2991|IndexInSheet=-1|Description=Chip Resistor, Body 1.0x0.5mm, IPC High Density|UseComponentLibrary=T|ModelName=RESC0402(1005)_L|ModelType=PCBLIB|DatafileCount=1|ModelDatafileEntity0=RESC0402(1005)_L|ModelDatafileKind0=PCBLib|DatalinksLocked=T|DatabaseDatalinksLocked=T
|RECORD=46|OwnerIndex=3000
|RECORD=48|OwnerIndex=3000
|RECORD=41|OwnerIndex=3002|IndexInSheet=-1|OwnerPartId=-1|Color=8388608|FontID=1|IsHidden=T|Text=2D|Name=Available Preview Images
|RECORD=17|IndexInSheet=250|OwnerPartId=-1|ShowNetName=T|Location.X=1075|Location.Y=470|Orientation=1|Color=128|FontID=1|Text=P3V3_PVDD
|RECORD=17|IndexInSheet=251|OwnerPartId=-1|ShowNetName=T|Location.X=1120|Location.Y=380|Orientation=1|Color=128|FontID=1|Text=P3V3_VDD
|RECORD=17|IndexInSheet=252|OwnerPartId=-1|Style=4|ShowNetName=T|Location.X=1120|Location.Y=315|Orientation=3|Color=128|FontID=1|Text=GND
|RECORD=17|IndexInSheet=253|OwnerPartId=-1|ShowNetName=T|Location.X=1170|Location.Y=380|Orientation=1|Color=128|FontID=1|Text=P3V3_PVDD
|RECORD=1|LibReference=b4654b650e69147ec39a6b967a45e02|ComponentDescription=Multilayer Ceramic Capacitors 2.2µF ±10% 16V X5R SMD 0402|PartCount=2|DisplayModeCount=1|IndexInSheet=254|OwnerPartId=-1|Location.X=1170|Location.Y=355|CurrentPartId=1|LibraryPath=*|SourceLibraryName=Altium Content Vault|TargetFileName=*|AreaColor=11599871|Color=128|PartIDLocked=T|DesignItemId=CMP-2000-05998-2|AllPinCount=2
|RECORD=2|OwnerIndex=3008|OwnerPartId=1|Electrical=4|PinConglomerate=49|PinLength=7|Location.X=1170|Location.Y=348|Name=1|Designator=1|PinPropagationDelay=0.000000E+000
|RECORD=2|OwnerIndex=3008|OwnerPartId=1|Electrical=4|PinConglomerate=51|PinLength=6|Location.X=1170|Location.Y=341|Name=2|Designator=2|PinPropagationDelay=0.000000E+000
|RECORD=13|OwnerIndex=3008|IsNotAccesible=T|IndexInSheet=2|OwnerPartId=1|Location.X=1180|Location.Y=348|Corner.X=1160|Corner.Y=348|LineWidth=1|Color=16711680
|RECORD=13|OwnerIndex=3008|IsNotAccesible=T|IndexInSheet=3|OwnerPartId=1|Location.X=1180|Location.Y=342|Corner.X=1160|Corner.Y=342|LineWidth=1|Color=16711680
|RECORD=13|OwnerIndex=3008|IsNotAccesible=T|IndexInSheet=4|OwnerPartId=1|Location.X=1170|Location.Y=348|Corner.X=1170|Corner.Y=351|LineWidth=1|Color=16711680
|RECORD=13|OwnerIndex=3008|IsNotAccesible=T|IndexInSheet=5|OwnerPartId=1|Location.X=1170|Location.Y=341|Corner.X=1170|Corner.Y=340|LineWidth=1|Color=16711680
|RECORD=41|OwnerIndex=3008|IndexInSheet=6|OwnerPartId=-1|Location.X=1159|Location.Y=357|Color=8388608|FontID=1|IsHidden=T|Text=No SVHC|Name=REACH SVHC
|RECORD=41|OwnerIndex=3008|IndexInSheet=7|OwnerPartId=-1|Location.X=1159|Location.Y=357|Color=8388608|FontID=1|IsHidden=T|Text=C|Name=Series
|RECORD=41|OwnerIndex=3008|IndexInSheet=8|OwnerPartId=-1|Location.X=1159|Location.Y=357|Color=8388608|FontID=1|IsHidden=T|Text=SMD/SMT|Name=Termination
|RECORD=41|OwnerIndex=3008|IndexInSheet=9|OwnerPartId=-1|Location.X=1159|Location.Y=357|Color=8388608|FontID=1|IsHidden=T|Text=0402|Name=Case Code (Imperial)
|RECORD=41|OwnerIndex=3008|IndexInSheet=10|OwnerPartId=-1|Location.X=1159|Location.Y=357|Color=8388608|FontID=1|IsHidden=T|Text=0.5mm|Name=Depth
|RECORD=41|OwnerIndex=3008|IndexInSheet=11|OwnerPartId=-1|Location.X=1159|Location.Y=357|Color=8388608|FontID=1|IsHidden=T|Text=Surface Mount|Name=Mount
|RECORD=41|OwnerIndex=3008|IndexInSheet=12|OwnerPartId=-1|Location.X=1159|Location.Y=357|Color=8388608|FontID=1|IsHidden=T|Text=0.02inch|Name=Width
|RECORD=41|OwnerIndex=3008|IndexInSheet=13|OwnerPartId=-1|Location.X=1159|Location.Y=357|Color=8388608|FontID=1|IsHidden=T|Text=1|Name=Package Quantity
|RECORD=41|OwnerIndex=3008|IndexInSheet=14|OwnerPartId=-1|Location.X=1159|Location.Y=357|Color=8388608|FontID=1|IsHidden=T|Text=Ceramic|Name=Dielectric Material
|RECORD=41|OwnerIndex=3008|IndexInSheet=15|OwnerPartId=-1|Location.X=1159|Location.Y=357|Color=8388608|FontID=1|IsHidden=T|Text=1mm|Name=Length
|RECORD=41|OwnerIndex=3008|IndexInSheet=16|OwnerPartId=-1|Location.X=1159|Location.Y=357|Color=8388608|FontID=1|IsHidden=T|Text=Tape and Reel|Name=Packaging
|RECORD=41|OwnerIndex=3008|IndexInSheet=17|OwnerPartId=-1|Location.X=1159|Location.Y=357|Color=8388608|FontID=1|IsHidden=T|Text=1005|Name=Case Code (Metric)
|RECORD=41|OwnerIndex=3008|IndexInSheet=18|OwnerPartId=-1|Location.X=1159|Location.Y=357|Color=8388608|FontID=1|IsHidden=T|Text=Yes|Name=RoHS Compliant
|RECORD=41|OwnerIndex=3008|IndexInSheet=19|OwnerPartId=-1|Location.X=1159|Location.Y=357|Color=8388608|FontID=1|IsHidden=T|Text=X5R|Name=Dielectric
|RECORD=41|OwnerIndex=3008|IndexInSheet=20|OwnerPartId=-1|Location.X=1159|Location.Y=357|Color=8388608|FontID=1|IsHidden=T|Text=85°C|Name=Max Operating Temperature
|RECORD=41|OwnerIndex=3008|IndexInSheet=21|OwnerPartId=-1|Location.X=1159|Location.Y=357|Color=8388608|FontID=1|IsHidden=T|Text=Lead Free|Name=Lead Free
|RECORD=41|OwnerIndex=3008|IndexInSheet=22|OwnerPartId=-1|Location.X=1159|Location.Y=357|Color=8388608|FontID=1|IsHidden=T|Text=2.3E-05oz|Name=Weight
|RECORD=41|OwnerIndex=3008|IndexInSheet=23|OwnerPartId=-1|Location.X=1159|Location.Y=357|Color=8388608|FontID=1|IsHidden=T|Text=0.022inch|Name=Thickness
|RECORD=41|OwnerIndex=3008|IndexInSheet=24|OwnerPartId=-1|Location.X=1159|Location.Y=357|Color=8388608|FontID=1|IsHidden=T|Text=2.2uF|Name=Capacitance
|RECORD=41|OwnerIndex=3008|IndexInSheet=25|OwnerPartId=-1|Location.X=1159|Location.Y=357|Color=8388608|FontID=1|IsHidden=T|Text=16V|Name=Voltage Rating (DC)
|RECORD=41|OwnerIndex=3008|IndexInSheet=26|OwnerPartId=-1|Location.X=1159|Location.Y=357|Color=8388608|FontID=1|IsHidden=T|Text=10%|Name=Tolerance
|RECORD=41|OwnerIndex=3008|IndexInSheet=27|OwnerPartId=-1|Location.X=1159|Location.Y=357|Color=8388608|FontID=1|IsHidden=T|Text=16V|Name=Voltage Rating
|RECORD=41|OwnerIndex=3008|IndexInSheet=28|OwnerPartId=-1|Location.X=1159|Location.Y=357|Color=8388608|FontID=1|IsHidden=T|Text=Ceramic|Name=Resistor Type
|RECORD=41|OwnerIndex=3008|IndexInSheet=29|OwnerPartId=-1|Location.X=1159|Location.Y=357|Color=8388608|FontID=1|IsHidden=T|Text=0.5mm|Name=Height
|RECORD=41|OwnerIndex=3008|IndexInSheet=30|OwnerPartId=-1|Location.X=1159|Location.Y=357|Color=8388608|FontID=1|IsHidden=T|Text=0402|Name=Case/Package
|RECORD=41|OwnerIndex=3008|IndexInSheet=31|OwnerPartId=-1|Location.X=1159|Location.Y=357|Color=8388608|FontID=1|IsHidden=T|Text=-55°C|Name=Min Operating Temperature
|RECORD=34|OwnerIndex=3008|IndexInSheet=-1|OwnerPartId=-1|Location.X=1160|Location.Y=335|Orientation=1|Color=8388608|FontID=2|Text=C70|Name=Designator|ReadOnlyState=1
|RECORD=41|OwnerIndex=3008|IndexInSheet=-1|OwnerPartId=1|Location.X=1190|Location.Y=310|Orientation=1|Color=8388608|FontID=2|Text=2.2uF_16V_0402|Name=Comment
|RECORD=44|OwnerIndex=3008
|RECORD=45|OwnerIndex=3045|IndexInSheet=-1|UseComponentLibrary=T|ModelName=FP-C1005-050-0_05-IPC_A|ModelType=PCBLIB|DatafileCount=1|ModelDatafileEntity0=FP-C1005-050-0_05-IPC_A|ModelDatafileKind0=PCBLib|IsCurrent=T|DatalinksLocked=T|DatabaseDatalinksLocked=T
|RECORD=46|OwnerIndex=3046
|RECORD=48|OwnerIndex=3046
|RECORD=45|OwnerIndex=3045|IndexInSheet=-1|UseComponentLibrary=T|ModelName=FP-C1005-050-0_05-MFG|ModelType=PCBLIB|DatafileCount=1|ModelDatafileEntity0=FP-C1005-050-0_05-MFG|ModelDatafileKind0=PCBLib|DatalinksLocked=T|DatabaseDatalinksLocked=T
|RECORD=46|OwnerIndex=3049
|RECORD=48|OwnerIndex=3049
|RECORD=45|OwnerIndex=3045|IndexInSheet=-1|UseComponentLibrary=T|ModelName=FP-C1005-050-0_05-IPC_C|ModelType=PCBLIB|DatafileCount=1|ModelDatafileEntity0=FP-C1005-050-0_05-IPC_C|ModelDatafileKind0=PCBLib|DatalinksLocked=T|DatabaseDatalinksLocked=T
|RECORD=46|OwnerIndex=3052
|RECORD=48|OwnerIndex=3052
|RECORD=45|OwnerIndex=3045|IndexInSheet=-1|UseComponentLibrary=T|ModelName=FP-C1005-050-0_05-IPC_B|ModelType=PCBLIB|DatafileCount=1|ModelDatafileEntity0=FP-C1005-050-0_05-IPC_B|ModelDatafileKind0=PCBLib|DatalinksLocked=T|DatabaseDatalinksLocked=T
|RECORD=46|OwnerIndex=3055
|RECORD=48|OwnerIndex=3055
|RECORD=17|IndexInSheet=255|OwnerPartId=-1|Style=4|ShowNetName=T|Location.X=1170|Location.Y=315|Orientation=3|Color=128|FontID=1|Text=GND
|RECORD=1|LibReference=b4654b650e69147ec39a6b967a45e02|ComponentDescription=Cap Ceramic 1nF 50V C0G ±5% SMD 0402 +125°C Paper T/R|PartCount=2|DisplayModeCount=1|IndexInSheet=256|OwnerPartId=-1|Location.X=830|Location.Y=315|CurrentPartId=1|LibraryPath=*|SourceLibraryName=Altium Content Vault|TargetFileName=*|AreaColor=11599871|Color=128|PartIDLocked=T|DesignItemId=CMP-13271-002012-1|AllPinCount=2|ComponentKindVersion2=5
|RECORD=2|OwnerIndex=3059|OwnerPartId=1|Electrical=4|PinConglomerate=49|PinLength=7|Location.X=830|Location.Y=308|Name=1|Designator=1|PinPropagationDelay=0.000000E+000
|RECORD=2|OwnerIndex=3059|OwnerPartId=1|Electrical=4|PinConglomerate=51|PinLength=6|Location.X=830|Location.Y=301|Name=2|Designator=2|PinPropagationDelay=0.000000E+000
|RECORD=13|OwnerIndex=3059|IsNotAccesible=T|IndexInSheet=2|OwnerPartId=1|Location.X=840|Location.Y=308|Corner.X=820|Corner.Y=308|LineWidth=1|Color=16711680
|RECORD=13|OwnerIndex=3059|IsNotAccesible=T|IndexInSheet=3|OwnerPartId=1|Location.X=840|Location.Y=302|Corner.X=820|Corner.Y=302|LineWidth=1|Color=16711680
|RECORD=13|OwnerIndex=3059|IsNotAccesible=T|IndexInSheet=4|OwnerPartId=1|Location.X=830|Location.Y=308|Corner.X=830|Corner.Y=311|LineWidth=1|Color=16711680
|RECORD=13|OwnerIndex=3059|IsNotAccesible=T|IndexInSheet=5|OwnerPartId=1|Location.X=830|Location.Y=301|Corner.X=830|Corner.Y=300|LineWidth=1|Color=16711680
|RECORD=41|OwnerIndex=3059|IndexInSheet=6|OwnerPartId=-1|Location.X=819|Location.Y=317|Color=8388608|FontID=1|IsHidden=T|Text=0402|Name=Case Code (Imperial)
|RECORD=41|OwnerIndex=3059|IndexInSheet=7|OwnerPartId=-1|Location.X=819|Location.Y=317|Color=8388608|FontID=1|IsHidden=T|Text=1|Name=Package Quantity
|RECORD=41|OwnerIndex=3059|IndexInSheet=8|OwnerPartId=-1|Location.X=819|Location.Y=317|Color=8388608|FontID=1|IsHidden=T|Text=1005|Name=Case Code (Metric)
|RECORD=41|OwnerIndex=3059|IndexInSheet=9|OwnerPartId=-1|Location.X=819|Location.Y=317|Color=8388608|FontID=1|IsHidden=T|Text=1nF|Name=Capacitance
|RECORD=41|OwnerIndex=3059|IndexInSheet=10|OwnerPartId=-1|Location.X=819|Location.Y=317|Color=8388608|FontID=1|IsHidden=T|Text=50V|Name=Voltage Rating (DC)
|RECORD=41|OwnerIndex=3059|IndexInSheet=11|OwnerPartId=-1|Location.X=819|Location.Y=317|Color=8388608|FontID=1|IsHidden=T|Text=Tape and Reel|Name=Packaging
|RECORD=41|OwnerIndex=3059|IndexInSheet=12|OwnerPartId=-1|Location.X=819|Location.Y=317|Color=8388608|FontID=1|IsHidden=T|Text=0.022inch|Name=Thickness
|RECORD=41|OwnerIndex=3059|IndexInSheet=13|OwnerPartId=-1|Location.X=819|Location.Y=317|Color=8388608|FontID=1|IsHidden=T|Text=0.5mm|Name=Height
|RECORD=41|OwnerIndex=3059|IndexInSheet=14|OwnerPartId=-1|Location.X=819|Location.Y=317|Color=8388608|FontID=1|IsHidden=T|Text=50V|Name=Voltage Rating
|RECORD=41|OwnerIndex=3059|IndexInSheet=15|OwnerPartId=-1|Location.X=819|Location.Y=317|Color=8388608|FontID=1|IsHidden=T|Text=C0G|Name=Dielectric
|RECORD=41|OwnerIndex=3059|IndexInSheet=16|OwnerPartId=-1|Location.X=819|Location.Y=317|Color=8388608|FontID=1|IsHidden=T|Text=No|Name=Radiation Hardening
|RECORD=41|OwnerIndex=3059|IndexInSheet=17|OwnerPartId=-1|Location.X=819|Location.Y=317|Color=8388608|FontID=1|IsHidden=T|Text=0.5mm|Name=Depth
|RECORD=41|OwnerIndex=3059|IndexInSheet=18|OwnerPartId=-1|Location.X=819|Location.Y=317|Color=8388608|FontID=1|IsHidden=T|Text=0.02inch|Name=Width
|RECORD=41|OwnerIndex=3059|IndexInSheet=19|OwnerPartId=-1|Location.X=819|Location.Y=317|Color=8388608|FontID=1|IsHidden=T|Text=0402|Name=Case/Package
|RECORD=41|OwnerIndex=3059|IndexInSheet=20|OwnerPartId=-1|Location.X=819|Location.Y=317|Color=8388608|FontID=1|IsHidden=T|Text=Surface Mount|Name=Mount
|RECORD=41|OwnerIndex=3059|IndexInSheet=21|OwnerPartId=-1|Location.X=819|Location.Y=317|Color=8388608|FontID=1|IsHidden=T|Text=1mm|Name=Length
|RECORD=41|OwnerIndex=3059|IndexInSheet=22|OwnerPartId=-1|Location.X=819|Location.Y=317|Color=8388608|FontID=1|IsHidden=T|Text=Ceramic|Name=Material
|RECORD=41|OwnerIndex=3059|IndexInSheet=23|OwnerPartId=-1|Location.X=819|Location.Y=317|Color=8388608|FontID=1|IsHidden=T|Text=125°C|Name=Max Operating Temperature
|RECORD=41|OwnerIndex=3059|IndexInSheet=24|OwnerPartId=-1|Location.X=819|Location.Y=317|Color=8388608|FontID=1|IsHidden=T|Text=5%|Name=Tolerance
|RECORD=41|OwnerIndex=3059|IndexInSheet=25|OwnerPartId=-1|Location.X=819|Location.Y=317|Color=8388608|FontID=1|IsHidden=T|Text=50V|Name=Voltage
|RECORD=41|OwnerIndex=3059|IndexInSheet=26|OwnerPartId=-1|Location.X=819|Location.Y=317|Color=8388608|FontID=1|IsHidden=T|Text=-55°C|Name=Min Operating Temperature
|RECORD=41|OwnerIndex=3059|IndexInSheet=27|OwnerPartId=-1|Location.X=819|Location.Y=317|Color=8388608|FontID=1|IsHidden=T|Text=300ppm/°C|Name=Temperature Coefficient
|RECORD=41|OwnerIndex=3059|IndexInSheet=28|OwnerPartId=-1|Location.X=819|Location.Y=317|Color=8388608|FontID=1|IsHidden=T|Text=Lead Free|Name=Lead Free
|RECORD=34|OwnerIndex=3059|IndexInSheet=-1|OwnerPartId=-1|Location.X=841|Location.Y=302|Color=8388608|FontID=1|Text=C72|Name=Designator|ReadOnlyState=1
|RECORD=41|OwnerIndex=3059|IndexInSheet=-1|OwnerPartId=1|Location.X=841|Location.Y=292|Color=8388608|FontID=1|Text=DNI_1nF_50V_0402|Name=Comment
|RECORD=44|OwnerIndex=3059
|RECORD=45|OwnerIndex=3093|IndexInSheet=-1|UseComponentLibrary=T|ModelName=FP-CL180-IPC_C|ModelType=PCBLIB|DatafileCount=1|ModelDatafileEntity0=FP-CL180-IPC_C|ModelDatafileKind0=PCBLib|IsCurrent=T|DatalinksLocked=T|DatabaseDatalinksLocked=T
|RECORD=46|OwnerIndex=3094
|RECORD=48|OwnerIndex=3094
|RECORD=45|OwnerIndex=3093|IndexInSheet=-1|UseComponentLibrary=T|ModelName=FP-CL180-IPC_B|ModelType=PCBLIB|DatafileCount=1|ModelDatafileEntity0=FP-CL180-IPC_B|ModelDatafileKind0=PCBLib|DatalinksLocked=T|DatabaseDatalinksLocked=T
|RECORD=46|OwnerIndex=3097
|RECORD=48|OwnerIndex=3097
|RECORD=45|OwnerIndex=3093|IndexInSheet=-1|UseComponentLibrary=T|ModelName=FP-CL180-IPC_A|ModelType=PCBLIB|DatafileCount=1|ModelDatafileEntity0=FP-CL180-IPC_A|ModelDatafileKind0=PCBLib|DatalinksLocked=T|DatabaseDatalinksLocked=T
|RECORD=46|OwnerIndex=3100
|RECORD=48|OwnerIndex=3100
|RECORD=1|LibReference=RES|PartCount=2|DisplayModeCount=2|IndexInSheet=257|OwnerPartId=-1|Location.X=820|Location.Y=335|Orientation=1|CurrentPartId=1|SourceLibraryName=Altium Content Vault|TargetFileName=*|AreaColor=11599871|Color=128|PartIDLocked=F|DesignItemId=CMP-2002-04265-1|AllPinCount=2
|RECORD=2|OwnerIndex=3103|OwnerPartId=1|OwnerPartDisplayMode=1|FormalType=1|Electrical=4|PinConglomerate=33|PinLength=10|Location.X=830|Location.Y=355|Name=2|Designator=2|PinPropagationDelay=0.000000E+000
|RECORD=2|OwnerIndex=3103|OwnerPartId=1|OwnerPartDisplayMode=1|FormalType=1|Electrical=4|PinConglomerate=35|PinLength=10|Location.X=830|Location.Y=335|Name=1|Designator=1|PinPropagationDelay=0.000000E+000
|RECORD=14|OwnerIndex=3103|IsNotAccesible=T|IndexInSheet=2|OwnerPartId=1|OwnerPartDisplayMode=1|Location.X=826|Location.Y=335|Corner.X=834|Corner.Y=355|LineWidth=1|Color=16711680|AreaColor=11599871
|RECORD=2|OwnerIndex=3103|OwnerPartId=1|FormalType=1|Electrical=4|PinConglomerate=33|PinLength=10|Location.X=830|Location.Y=355|Name=2|Designator=2|PinPropagationDelay=0.000000E+000
|RECORD=2|OwnerIndex=3103|OwnerPartId=1|FormalType=1|Electrical=4|PinConglomerate=35|PinLength=10|Location.X=830|Location.Y=335|Name=1|Designator=1|PinPropagationDelay=0.000000E+000
|RECORD=6|OwnerIndex=3103|IsNotAccesible=T|IndexInSheet=5|OwnerPartId=1|LineWidth=1|Color=16711680|LocationCount=10|X1=830|Y1=355|X2=830|Y2=351|X3=832|Y3=350|X4=828|Y4=348|X5=832|Y5=346|X6=828|Y6=344|X7=832|Y7=342|X8=828|Y8=340|X9=830|Y9=339|X10=830|Y10=335
|RECORD=41|OwnerIndex=3103|IndexInSheet=6|OwnerPartId=-1|Location.X=827|Location.Y=367|Color=8388608|FontID=1|IsHidden=T|Text=RK73H1ETTP1R21F|Name=Part Number
|RECORD=41|OwnerIndex=3103|IndexInSheet=7|OwnerPartId=-1|Location.X=827|Location.Y=367|Color=8388608|FontID=1|IsHidden=T|Text=KOA Speer|Name=Manufacturer
|RECORD=34|OwnerIndex=3103|IndexInSheet=-1|OwnerPartId=-1|Location.X=833|Location.Y=346|Color=8388608|FontID=1|Text=R73|Name=Designator|ReadOnlyState=1
|RECORD=41|OwnerIndex=3103|IndexInSheet=-1|OwnerPartId=-1|Location.X=833|Location.Y=336|Color=8388608|FontID=1|Text=1.21_1%_0402|Name=Comment
|RECORD=44|OwnerIndex=3103
|RECORD=45|OwnerIndex=3118|IndexInSheet=-1|Description=Chip Resistor, 2-Leads, Body 1.00x0.50mm, IPC High Density|UseComponentLibrary=T|ModelName=RESC1005X40X25LL10T10|ModelType=PCBLIB|DatafileCount=1|ModelDatafileEntity0=RESC1005X40X25LL10T10|ModelDatafileKind0=PCBLib|IsCurrent=T|DatalinksLocked=T|DatabaseDatalinksLocked=T
|RECORD=46|OwnerIndex=3119
|RECORD=48|OwnerIndex=3119
|RECORD=41|OwnerIndex=3121|IndexInSheet=-1|OwnerPartId=-1|Color=8388608|FontID=1|IsHidden=T|Text=2D|Name=Available Preview Images
|RECORD=45|OwnerIndex=3118|IndexInSheet=-1|Description=Chip Resistor, 2-Leads, Body 1.00x0.50mm, IPC Medium Density|UseComponentLibrary=T|ModelName=RESC1005X40X25NL10T10|ModelType=PCBLIB|DatafileCount=1|ModelDatafileEntity0=RESC1005X40X25NL10T10|ModelDatafileKind0=PCBLib|DatalinksLocked=T|DatabaseDatalinksLocked=T
|RECORD=46|OwnerIndex=3123
|RECORD=48|OwnerIndex=3123
|RECORD=41|OwnerIndex=3125|IndexInSheet=-1|OwnerPartId=-1|Color=8388608|FontID=1|IsHidden=T|Text=2D|Name=Available Preview Images
|RECORD=45|OwnerIndex=3118|IndexInSheet=-1|Description=Chip Resistor, 2-Leads, Body 1.00x0.50mm, IPC Low Density|UseComponentLibrary=T|ModelName=RESC1005X40X25ML10T10|ModelType=PCBLIB|DatafileCount=1|ModelDatafileEntity0=RESC1005X40X25ML10T10|ModelDatafileKind0=PCBLib|DatalinksLocked=T|DatabaseDatalinksLocked=T
|RECORD=46|OwnerIndex=3127
|RECORD=48|OwnerIndex=3127
|RECORD=41|OwnerIndex=3129|IndexInSheet=-1|OwnerPartId=-1|Color=8388608|FontID=1|IsHidden=T|Text=2D|Name=Available Preview Images
|RECORD=17|IndexInSheet=258|OwnerPartId=-1|Style=4|ShowNetName=T|Location.X=830|Location.Y=275|Orientation=3|Color=128|FontID=1|Text=GND
|RECORD=1|LibReference=02cd4be3c70576c341d710602a673aa|ComponentDescription=Chip Multilayer Ceramic Capacitors for General Purpose, 1206, 4.7uF, X7R, 15%, 10%, 50V|PartCount=2|DisplayModeCount=1|IndexInSheet=259|OwnerPartId=-1|Location.X=475|Location.Y=290|CurrentPartId=1|LibraryPath=*|SourceLibraryName=Altium Content Vault|TargetFileName=*|AreaColor=11599871|Color=128|PartIDLocked=T|DesignItemId=CMP-1037-04923-3|AllPinCount=2
|RECORD=2|OwnerIndex=3132|OwnerPartId=1|Electrical=4|PinConglomerate=49|PinLength=7|Location.X=475|Location.Y=283|Name=1|Designator=1|PinPropagationDelay=0.000000E+000
|RECORD=2|OwnerIndex=3132|OwnerPartId=1|Electrical=4|PinConglomerate=51|PinLength=6|Location.X=475|Location.Y=276|Name=2|Designator=2|PinPropagationDelay=0.000000E+000
|RECORD=13|OwnerIndex=3132|IsNotAccesible=T|IndexInSheet=2|OwnerPartId=1|Location.X=485|Location.Y=283|Corner.X=465|Corner.Y=283|LineWidth=1|Color=16711680
|RECORD=13|OwnerIndex=3132|IsNotAccesible=T|IndexInSheet=3|OwnerPartId=1|Location.X=485|Location.Y=277|Corner.X=465|Corner.Y=277|LineWidth=1|Color=16711680
|RECORD=13|OwnerIndex=3132|IsNotAccesible=T|IndexInSheet=4|OwnerPartId=1|Location.X=475|Location.Y=283|Corner.X=475|Corner.Y=286|LineWidth=1|Color=16711680
|RECORD=13|OwnerIndex=3132|IsNotAccesible=T|IndexInSheet=5|OwnerPartId=1|Location.X=475|Location.Y=276|Corner.X=475|Corner.Y=275|LineWidth=1|Color=16711680
|RECORD=41|OwnerIndex=3132|IndexInSheet=6|OwnerPartId=-1|Location.X=464|Location.Y=292|Color=8388608|FontID=1|IsHidden=T|Text=1.6mm|Name=Height
|RECORD=41|OwnerIndex=3132|IndexInSheet=7|OwnerPartId=-1|Location.X=464|Location.Y=292|Color=8388608|FontID=1|IsHidden=T|Text=50V|Name=Voltage
|RECORD=41|OwnerIndex=3132|IndexInSheet=8|OwnerPartId=-1|Location.X=464|Location.Y=292|Color=8388608|FontID=1|IsHidden=T|Text=4.7uF|Name=Capacitance
|RECORD=41|OwnerIndex=3132|IndexInSheet=9|OwnerPartId=-1|Location.X=464|Location.Y=292|Color=8388608|FontID=1|IsHidden=T|Text=Lead Free|Name=Lead Free
|RECORD=41|OwnerIndex=3132|IndexInSheet=10|OwnerPartId=-1|Location.X=464|Location.Y=292|Color=8388608|FontID=1|IsHidden=T|Text=125°C|Name=Max Operating Temperature
|RECORD=41|OwnerIndex=3132|IndexInSheet=11|OwnerPartId=-1|Location.X=464|Location.Y=292|Color=8388608|FontID=1|IsHidden=T|Text=Tape and Reel|Name=Packaging
|RECORD=41|OwnerIndex=3132|IndexInSheet=12|OwnerPartId=-1|Location.X=464|Location.Y=292|Color=8388608|FontID=1|IsHidden=T|Text=No SVHC|Name=REACH SVHC
|RECORD=41|OwnerIndex=3132|IndexInSheet=13|OwnerPartId=-1|Location.X=464|Location.Y=292|Color=8388608|FontID=1|IsHidden=T|Text=50V|Name=Voltage Rating
|RECORD=41|OwnerIndex=3132|IndexInSheet=14|OwnerPartId=-1|Location.X=464|Location.Y=292|Color=8388608|FontID=1|IsHidden=T|Text=Surface Mount|Name=Mount
|RECORD=41|OwnerIndex=3132|IndexInSheet=15|OwnerPartId=-1|Location.X=464|Location.Y=292|Color=8388608|FontID=1|IsHidden=T|Text=SMD/SMT|Name=Termination
|RECORD=41|OwnerIndex=3132|IndexInSheet=16|OwnerPartId=-1|Location.X=464|Location.Y=292|Color=8388608|FontID=1|IsHidden=T|Text=10%|Name=Tolerance
|RECORD=41|OwnerIndex=3132|IndexInSheet=17|OwnerPartId=-1|Location.X=464|Location.Y=292|Color=8388608|FontID=1|IsHidden=T|Text=1206|Name=Case/Package
|RECORD=41|OwnerIndex=3132|IndexInSheet=18|OwnerPartId=-1|Location.X=464|Location.Y=292|Color=8388608|FontID=1|IsHidden=T|Text=Ceramic|Name=Material
|RECORD=41|OwnerIndex=3132|IndexInSheet=19|OwnerPartId=-1|Location.X=464|Location.Y=292|Color=8388608|FontID=1|IsHidden=T|Text=1.6mm|Name=Depth
|RECORD=41|OwnerIndex=3132|IndexInSheet=20|OwnerPartId=-1|Location.X=464|Location.Y=292|Color=8388608|FontID=1|IsHidden=T|Text=3.2mm|Name=Length
|RECORD=41|OwnerIndex=3132|IndexInSheet=21|OwnerPartId=-1|Location.X=464|Location.Y=292|Color=8388608|FontID=1|IsHidden=T|Text=3216|Name=Case Code (Metric)
|RECORD=41|OwnerIndex=3132|IndexInSheet=22|OwnerPartId=-1|Location.X=464|Location.Y=292|Color=8388608|FontID=1|IsHidden=T|Text=50V|Name=Voltage Rating (DC)
|RECORD=41|OwnerIndex=3132|IndexInSheet=23|OwnerPartId=-1|Location.X=464|Location.Y=292|Color=8388608|FontID=1|IsHidden=T|Text=1206|Name=Case Code (Imperial)
|RECORD=41|OwnerIndex=3132|IndexInSheet=24|OwnerPartId=-1|Location.X=464|Location.Y=292|Color=8388608|FontID=1|IsHidden=T|Text=No|Name=Radiation Hardening
|RECORD=41|OwnerIndex=3132|IndexInSheet=25|OwnerPartId=-1|Location.X=464|Location.Y=292|Color=8388608|FontID=1|IsHidden=T|Text=0.063inch|Name=Width
|RECORD=41|OwnerIndex=3132|IndexInSheet=26|OwnerPartId=-1|Location.X=464|Location.Y=292|Color=8388608|FontID=1|IsHidden=T|Text=0.071inch|Name=Thickness
|RECORD=41|OwnerIndex=3132|IndexInSheet=27|OwnerPartId=-1|Location.X=464|Location.Y=292|Color=8388608|FontID=1|IsHidden=T|Text=2000|Name=Package Quantity
|RECORD=41|OwnerIndex=3132|IndexInSheet=28|OwnerPartId=-1|Location.X=464|Location.Y=292|Color=8388608|FontID=1|IsHidden=T|Text=-55°C|Name=Min Operating Temperature
|RECORD=41|OwnerIndex=3132|IndexInSheet=29|OwnerPartId=-1|Location.X=464|Location.Y=292|Color=8388608|FontID=1|IsHidden=T|Text=X7R|Name=Dielectric
|RECORD=34|OwnerIndex=3132|IndexInSheet=-1|OwnerPartId=-1|Location.X=465|Location.Y=270|Orientation=1|Color=8388608|FontID=2|Text=C76|Name=Designator|ReadOnlyState=1
|RECORD=41|OwnerIndex=3132|IndexInSheet=-1|OwnerPartId=1|Location.X=495|Location.Y=255|Orientation=1|Color=8388608|FontID=2|Text=4.7uF_50V_1206|Name=Comment
|RECORD=44|OwnerIndex=3132
|RECORD=45|OwnerIndex=3167|IndexInSheet=-1|UseComponentLibrary=T|ModelName=FP-GRM31C-0_2-e0_3_0_8-IPC_C|ModelType=PCBLIB|DatafileCount=1|ModelDatafileEntity0=FP-GRM31C-0_2-e0_3_0_8-IPC_C|ModelDatafileKind0=PCBLib|IsCurrent=T|DatalinksLocked=T|DatabaseDatalinksLocked=T
|RECORD=46|OwnerIndex=3168
|RECORD=48|OwnerIndex=3168
|RECORD=45|OwnerIndex=3167|IndexInSheet=-1|UseComponentLibrary=T|ModelName=FP-GRM31C-0_2-e0_3_0_8-IPC_B|ModelType=PCBLIB|DatafileCount=1|ModelDatafileEntity0=FP-GRM31C-0_2-e0_3_0_8-IPC_B|ModelDatafileKind0=PCBLib|DatalinksLocked=T|DatabaseDatalinksLocked=T
|RECORD=46|OwnerIndex=3171
|RECORD=48|OwnerIndex=3171
|RECORD=45|OwnerIndex=3167|IndexInSheet=-1|UseComponentLibrary=T|ModelName=FP-GRM31C-0_2-e0_3_0_8-IPC_A|ModelType=PCBLIB|DatafileCount=1|ModelDatafileEntity0=FP-GRM31C-0_2-e0_3_0_8-IPC_A|ModelDatafileKind0=PCBLib|DatalinksLocked=T|DatabaseDatalinksLocked=T
|RECORD=46|OwnerIndex=3174
|RECORD=48|OwnerIndex=3174
|RECORD=45|OwnerIndex=3167|IndexInSheet=-1|UseComponentLibrary=T|ModelName=FP-GRM31C-0_2-e0_3_0_8-MFG|ModelType=PCBLIB|DatafileCount=1|ModelDatafileEntity0=FP-GRM31C-0_2-e0_3_0_8-MFG|ModelDatafileKind0=PCBLib|DatalinksLocked=T|DatabaseDatalinksLocked=T
|RECORD=46|OwnerIndex=3177
|RECORD=48|OwnerIndex=3177
|RECORD=1|LibReference=02cd4be3c70576c341d710602a673aa|ComponentDescription=Chip Multilayer Ceramic Capacitors for General Purpose, 1206, 4.7uF, X7R, 15%, 10%, 50V|PartCount=2|DisplayModeCount=1|IndexInSheet=260|OwnerPartId=-1|Location.X=515|Location.Y=290|CurrentPartId=1|LibraryPath=*|SourceLibraryName=Altium Content Vault|TargetFileName=*|AreaColor=11599871|Color=128|PartIDLocked=T|DesignItemId=CMP-1037-04923-3|AllPinCount=2
|RECORD=2|OwnerIndex=3180|OwnerPartId=1|Electrical=4|PinConglomerate=49|PinLength=7|Location.X=515|Location.Y=283|Name=1|Designator=1|PinPropagationDelay=0.000000E+000
|RECORD=2|OwnerIndex=3180|OwnerPartId=1|Electrical=4|PinConglomerate=51|PinLength=6|Location.X=515|Location.Y=276|Name=2|Designator=2|PinPropagationDelay=0.000000E+000
|RECORD=13|OwnerIndex=3180|IsNotAccesible=T|IndexInSheet=2|OwnerPartId=1|Location.X=525|Location.Y=283|Corner.X=505|Corner.Y=283|LineWidth=1|Color=16711680
|RECORD=13|OwnerIndex=3180|IsNotAccesible=T|IndexInSheet=3|OwnerPartId=1|Location.X=525|Location.Y=277|Corner.X=505|Corner.Y=277|LineWidth=1|Color=16711680
|RECORD=13|OwnerIndex=3180|IsNotAccesible=T|IndexInSheet=4|OwnerPartId=1|Location.X=515|Location.Y=283|Corner.X=515|Corner.Y=286|LineWidth=1|Color=16711680
|RECORD=13|OwnerIndex=3180|IsNotAccesible=T|IndexInSheet=5|OwnerPartId=1|Location.X=515|Location.Y=276|Corner.X=515|Corner.Y=275|LineWidth=1|Color=16711680
|RECORD=41|OwnerIndex=3180|IndexInSheet=6|OwnerPartId=-1|Location.X=504|Location.Y=292|Color=8388608|FontID=1|IsHidden=T|Text=1.6mm|Name=Height
|RECORD=41|OwnerIndex=3180|IndexInSheet=7|OwnerPartId=-1|Location.X=504|Location.Y=292|Color=8388608|FontID=1|IsHidden=T|Text=50V|Name=Voltage
|RECORD=41|OwnerIndex=3180|IndexInSheet=8|OwnerPartId=-1|Location.X=504|Location.Y=292|Color=8388608|FontID=1|IsHidden=T|Text=4.7uF|Name=Capacitance
|RECORD=41|OwnerIndex=3180|IndexInSheet=9|OwnerPartId=-1|Location.X=504|Location.Y=292|Color=8388608|FontID=1|IsHidden=T|Text=Lead Free|Name=Lead Free
|RECORD=41|OwnerIndex=3180|IndexInSheet=10|OwnerPartId=-1|Location.X=504|Location.Y=292|Color=8388608|FontID=1|IsHidden=T|Text=125°C|Name=Max Operating Temperature
|RECORD=41|OwnerIndex=3180|IndexInSheet=11|OwnerPartId=-1|Location.X=504|Location.Y=292|Color=8388608|FontID=1|IsHidden=T|Text=Tape and Reel|Name=Packaging
|RECORD=41|OwnerIndex=3180|IndexInSheet=12|OwnerPartId=-1|Location.X=504|Location.Y=292|Color=8388608|FontID=1|IsHidden=T|Text=No SVHC|Name=REACH SVHC
|RECORD=41|OwnerIndex=3180|IndexInSheet=13|OwnerPartId=-1|Location.X=504|Location.Y=292|Color=8388608|FontID=1|IsHidden=T|Text=50V|Name=Voltage Rating
|RECORD=41|OwnerIndex=3180|IndexInSheet=14|OwnerPartId=-1|Location.X=504|Location.Y=292|Color=8388608|FontID=1|IsHidden=T|Text=Surface Mount|Name=Mount
|RECORD=41|OwnerIndex=3180|IndexInSheet=15|OwnerPartId=-1|Location.X=504|Location.Y=292|Color=8388608|FontID=1|IsHidden=T|Text=SMD/SMT|Name=Termination
|RECORD=41|OwnerIndex=3180|IndexInSheet=16|OwnerPartId=-1|Location.X=504|Location.Y=292|Color=8388608|FontID=1|IsHidden=T|Text=10%|Name=Tolerance
|RECORD=41|OwnerIndex=3180|IndexInSheet=17|OwnerPartId=-1|Location.X=504|Location.Y=292|Color=8388608|FontID=1|IsHidden=T|Text=1206|Name=Case/Package
|RECORD=41|OwnerIndex=3180|IndexInSheet=18|OwnerPartId=-1|Location.X=504|Location.Y=292|Color=8388608|FontID=1|IsHidden=T|Text=Ceramic|Name=Material
|RECORD=41|OwnerIndex=3180|IndexInSheet=19|OwnerPartId=-1|Location.X=504|Location.Y=292|Color=8388608|FontID=1|IsHidden=T|Text=1.6mm|Name=Depth
|RECORD=41|OwnerIndex=3180|IndexInSheet=20|OwnerPartId=-1|Location.X=504|Location.Y=292|Color=8388608|FontID=1|IsHidden=T|Text=3.2mm|Name=Length
|RECORD=41|OwnerIndex=3180|IndexInSheet=21|OwnerPartId=-1|Location.X=504|Location.Y=292|Color=8388608|FontID=1|IsHidden=T|Text=3216|Name=Case Code (Metric)
|RECORD=41|OwnerIndex=3180|IndexInSheet=22|OwnerPartId=-1|Location.X=504|Location.Y=292|Color=8388608|FontID=1|IsHidden=T|Text=50V|Name=Voltage Rating (DC)
|RECORD=41|OwnerIndex=3180|IndexInSheet=23|OwnerPartId=-1|Location.X=504|Location.Y=292|Color=8388608|FontID=1|IsHidden=T|Text=1206|Name=Case Code (Imperial)
|RECORD=41|OwnerIndex=3180|IndexInSheet=24|OwnerPartId=-1|Location.X=504|Location.Y=292|Color=8388608|FontID=1|IsHidden=T|Text=No|Name=Radiation Hardening
|RECORD=41|OwnerIndex=3180|IndexInSheet=25|OwnerPartId=-1|Location.X=504|Location.Y=292|Color=8388608|FontID=1|IsHidden=T|Text=0.063inch|Name=Width
|RECORD=41|OwnerIndex=3180|IndexInSheet=26|OwnerPartId=-1|Location.X=504|Location.Y=292|Color=8388608|FontID=1|IsHidden=T|Text=0.071inch|Name=Thickness
|RECORD=41|OwnerIndex=3180|IndexInSheet=27|OwnerPartId=-1|Location.X=504|Location.Y=292|Color=8388608|FontID=1|IsHidden=T|Text=2000|Name=Package Quantity
|RECORD=41|OwnerIndex=3180|IndexInSheet=28|OwnerPartId=-1|Location.X=504|Location.Y=292|Color=8388608|FontID=1|IsHidden=T|Text=-55°C|Name=Min Operating Temperature
|RECORD=41|OwnerIndex=3180|IndexInSheet=29|OwnerPartId=-1|Location.X=504|Location.Y=292|Color=8388608|FontID=1|IsHidden=T|Text=X7R|Name=Dielectric
|RECORD=34|OwnerIndex=3180|IndexInSheet=-1|OwnerPartId=-1|Location.X=505|Location.Y=270|Orientation=1|Color=8388608|FontID=2|Text=C77|Name=Designator|ReadOnlyState=1
|RECORD=41|OwnerIndex=3180|IndexInSheet=-1|OwnerPartId=1|Location.X=535|Location.Y=255|Orientation=1|Color=8388608|FontID=2|Text=4.7uF_50V_1206|Name=Comment
|RECORD=44|OwnerIndex=3180
|RECORD=45|OwnerIndex=3215|IndexInSheet=-1|UseComponentLibrary=T|ModelName=FP-GRM31C-0_2-e0_3_0_8-IPC_C|ModelType=PCBLIB|DatafileCount=1|ModelDatafileEntity0=FP-GRM31C-0_2-e0_3_0_8-IPC_C|ModelDatafileKind0=PCBLib|IsCurrent=T|DatalinksLocked=T|DatabaseDatalinksLocked=T
|RECORD=46|OwnerIndex=3216
|RECORD=48|OwnerIndex=3216
|RECORD=45|OwnerIndex=3215|IndexInSheet=-1|UseComponentLibrary=T|ModelName=FP-GRM31C-0_2-e0_3_0_8-IPC_B|ModelType=PCBLIB|DatafileCount=1|ModelDatafileEntity0=FP-GRM31C-0_2-e0_3_0_8-IPC_B|ModelDatafileKind0=PCBLib|DatalinksLocked=T|DatabaseDatalinksLocked=T
|RECORD=46|OwnerIndex=3219
|RECORD=48|OwnerIndex=3219
|RECORD=45|OwnerIndex=3215|IndexInSheet=-1|UseComponentLibrary=T|ModelName=FP-GRM31C-0_2-e0_3_0_8-IPC_A|ModelType=PCBLIB|DatafileCount=1|ModelDatafileEntity0=FP-GRM31C-0_2-e0_3_0_8-IPC_A|ModelDatafileKind0=PCBLib|DatalinksLocked=T|DatabaseDatalinksLocked=T
|RECORD=46|OwnerIndex=3222
|RECORD=48|OwnerIndex=3222
|RECORD=45|OwnerIndex=3215|IndexInSheet=-1|UseComponentLibrary=T|ModelName=FP-GRM31C-0_2-e0_3_0_8-MFG|ModelType=PCBLIB|DatafileCount=1|ModelDatafileEntity0=FP-GRM31C-0_2-e0_3_0_8-MFG|ModelDatafileKind0=PCBLib|DatalinksLocked=T|DatabaseDatalinksLocked=T
|RECORD=46|OwnerIndex=3225
|RECORD=48|OwnerIndex=3225
|RECORD=1|LibReference=a00bbbee19879c290e62620ae7e47b1|ComponentDescription=CAP TANT 100UF 10% 16V 2917|PartCount=2|DisplayModeCount=1|IndexInSheet=261|OwnerPartId=-1|Location.X=425|Location.Y=290|CurrentPartId=1|LibraryPath=*|SourceLibraryName=Altium Content Vault|TargetFileName=*|AreaColor=11599871|Color=128|PartIDLocked=T|DesignItemId=CMP-2000-07207-2|AllPinCount=2
|RECORD=2|OwnerIndex=3228|OwnerPartId=1|Electrical=4|PinConglomerate=51|PinLength=8|Location.X=425|Location.Y=278|Name=C|Designator=1|PinPropagationDelay=0.000000E+000
|RECORD=2|OwnerIndex=3228|OwnerPartId=1|Electrical=4|PinConglomerate=49|PinLength=8|Location.X=425|Location.Y=282|Name=A|Designator=2|PinPropagationDelay=0.000000E+000
|RECORD=5|OwnerIndex=3228|IsNotAccesible=T|IndexInSheet=2|OwnerPartId=1|LineWidth=1|Color=16711680|LocationCount=4|X1=415|Y1=274|X2=420|Y2=280|X3=430|Y3=280|X4=435|Y4=274
|RECORD=13|OwnerIndex=3228|IsNotAccesible=T|IndexInSheet=3|OwnerPartId=1|Location.X=415|Location.Y=282|Corner.X=435|Corner.Y=282|LineWidth=1|Color=16711680
|RECORD=13|OwnerIndex=3228|IsNotAccesible=T|IndexInSheet=4|OwnerPartId=1|Location.X=425|Location.Y=278|Corner.X=425|Corner.Y=276|LineWidth=1|Color=16711680
|RECORD=13|OwnerIndex=3228|IsNotAccesible=T|IndexInSheet=5|OwnerPartId=1|Location.X=425|Location.Y=282|Corner.X=425|Corner.Y=285|LineWidth=1|Color=16711680
|RECORD=4|OwnerIndex=3228|IsNotAccesible=T|IndexInSheet=6|OwnerPartId=1|Location.X=414|Location.Y=292|Justification=6|Color=8388608|FontID=1|Text=+
|RECORD=41|OwnerIndex=3228|IndexInSheet=7|OwnerPartId=-1|Location.X=414|Location.Y=292|Color=8388608|FontID=1|IsHidden=T|Text=100uF|Name=Capacitance
|RECORD=41|OwnerIndex=3228|IndexInSheet=8|OwnerPartId=-1|Location.X=414|Location.Y=292|Color=8388608|FontID=1|IsHidden=T|Text=No|Name=Radiation Hardening
|RECORD=41|OwnerIndex=3228|IndexInSheet=9|OwnerPartId=-1|Location.X=414|Location.Y=292|Color=8388608|FontID=1|IsHidden=T|Text=Yes|Name=RoHS Compliant
|RECORD=41|OwnerIndex=3228|IndexInSheet=10|OwnerPartId=-1|Location.X=414|Location.Y=292|Color=8388608|FontID=1|IsHidden=T|Text=7.3mm|Name=Length
|RECORD=41|OwnerIndex=3228|IndexInSheet=11|OwnerPartId=-1|Location.X=414|Location.Y=292|Color=8388608|FontID=1|IsHidden=T|Text=General Purpose|Name=Features
|RECORD=41|OwnerIndex=3228|IndexInSheet=12|OwnerPartId=-1|Location.X=414|Location.Y=292|Color=8388608|FontID=1|IsHidden=T|Text=Tape and Reel|Name=Packaging
|RECORD=41|OwnerIndex=3228|IndexInSheet=13|OwnerPartId=-1|Location.X=414|Location.Y=292|Color=8388608|FontID=1|IsHidden=T|Text=1|Name=Package Quantity
|RECORD=41|OwnerIndex=3228|IndexInSheet=14|OwnerPartId=-1|Location.X=414|Location.Y=292|Color=8388608|FontID=1|IsHidden=T|Text=0.023634oz|Name=Weight
|RECORD=41|OwnerIndex=3228|IndexInSheet=15|OwnerPartId=-1|Location.X=414|Location.Y=292|Color=8388608|FontID=1|IsHidden=T|Text=2000Hour|Name=Life (Hours)
|RECORD=41|OwnerIndex=3228|IndexInSheet=16|OwnerPartId=-1|Location.X=414|Location.Y=292|Color=8388608|FontID=1|IsHidden=T|Text=16V|Name=Voltage Rating
|RECORD=41|OwnerIndex=3228|IndexInSheet=17|OwnerPartId=-1|Location.X=414|Location.Y=292|Color=8388608|FontID=1|IsHidden=T|Text=0.169inch|Name=Width
|RECORD=41|OwnerIndex=3228|IndexInSheet=18|OwnerPartId=-1|Location.X=414|Location.Y=292|Color=8388608|FontID=1|IsHidden=T|Text=2917|Name=Case/Package
|RECORD=41|OwnerIndex=3228|IndexInSheet=19|OwnerPartId=-1|Location.X=414|Location.Y=292|Color=8388608|FontID=1|IsHidden=T|Text=125mR|Name=ESR (Equivalent Series Resistance)
|RECORD=41|OwnerIndex=3228|IndexInSheet=20|OwnerPartId=-1|Location.X=414|Location.Y=292|Color=8388608|FontID=1|IsHidden=T|Text=Surface Mount|Name=Mount
|RECORD=41|OwnerIndex=3228|IndexInSheet=21|OwnerPartId=-1|Location.X=414|Location.Y=292|Color=8388608|FontID=1|IsHidden=T|Text=16V|Name=Voltage
|RECORD=41|OwnerIndex=3228|IndexInSheet=22|OwnerPartId=-1|Location.X=414|Location.Y=292|Color=8388608|FontID=1|IsHidden=T|Text=-55°C|Name=Min Operating Temperature
|RECORD=41|OwnerIndex=3228|IndexInSheet=23|OwnerPartId=-1|Location.X=414|Location.Y=292|Color=8388608|FontID=1|IsHidden=T|Text=10%|Name=Tolerance
|RECORD=41|OwnerIndex=3228|IndexInSheet=24|OwnerPartId=-1|Location.X=414|Location.Y=292|Color=8388608|FontID=1|IsHidden=T|Text=No SVHC|Name=REACH SVHC
|RECORD=41|OwnerIndex=3228|IndexInSheet=25|OwnerPartId=-1|Location.X=414|Location.Y=292|Color=8388608|FontID=1|IsHidden=T|Text=0.122inch|Name=Height - Seated (Max)
|RECORD=41|OwnerIndex=3228|IndexInSheet=26|OwnerPartId=-1|Location.X=414|Location.Y=292|Color=8388608|FontID=1|IsHidden=T|Text=2|Name=Number of Pins
|RECORD=41|OwnerIndex=3228|IndexInSheet=27|OwnerPartId=-1|Location.X=414|Location.Y=292|Color=8388608|FontID=1|IsHidden=T|Text=Flat|Name=Construction
|RECORD=41|OwnerIndex=3228|IndexInSheet=28|OwnerPartId=-1|Location.X=414|Location.Y=292|Color=8388608|FontID=1|IsHidden=T|Text=4.3mm|Name=Depth
|RECORD=41|OwnerIndex=3228|IndexInSheet=29|OwnerPartId=-1|Location.X=414|Location.Y=292|Color=8388608|FontID=1|IsHidden=T|Text=T495|Name=Series
|RECORD=41|OwnerIndex=3228|IndexInSheet=30|OwnerPartId=-1|Location.X=414|Location.Y=292|Color=8388608|FontID=1|IsHidden=T|Text=125°C|Name=Max Operating Temperature
|RECORD=41|OwnerIndex=3228|IndexInSheet=31|OwnerPartId=-1|Location.X=414|Location.Y=292|Color=8388608|FontID=1|IsHidden=T|Text=0.001%|Name=Failure Rate
|RECORD=41|OwnerIndex=3228|IndexInSheet=32|OwnerPartId=-1|Location.X=414|Location.Y=292|Color=8388608|FontID=1|IsHidden=T|Text=SMD/SMT|Name=Termination
|RECORD=41|OwnerIndex=3228|IndexInSheet=33|OwnerPartId=-1|Location.X=414|Location.Y=292|Color=8388608|FontID=1|IsHidden=T|Text=Polar|Name=Polarity
|RECORD=41|OwnerIndex=3228|IndexInSheet=34|OwnerPartId=-1|Location.X=414|Location.Y=292|Color=8388608|FontID=1|IsHidden=T|Text=16V|Name=Voltage Rating (DC)
|RECORD=41|OwnerIndex=3228|IndexInSheet=35|OwnerPartId=-1|Location.X=414|Location.Y=292|Color=8388608|FontID=1|IsHidden=T|Text=Tantalum|Name=Dielectric Material
|RECORD=41|OwnerIndex=3228|IndexInSheet=36|OwnerPartId=-1|Location.X=414|Location.Y=292|Color=8388608|FontID=1|IsHidden=T|Text=2917|Name=Case Code (Imperial)
|RECORD=41|OwnerIndex=3228|IndexInSheet=37|OwnerPartId=-1|Location.X=414|Location.Y=292|Color=8388608|FontID=1|IsHidden=T|Text=7343|Name=Case Code (Metric)
|RECORD=41|OwnerIndex=3228|IndexInSheet=38|OwnerPartId=-1|Location.X=414|Location.Y=292|Color=8388608|FontID=1|IsHidden=T|Text=2.8mm|Name=Height
|RECORD=41|OwnerIndex=3228|IndexInSheet=39|OwnerPartId=-1|Location.X=414|Location.Y=292|Color=8388608|FontID=1|IsHidden=T|Text=8%|Name=Dissipation Factor
|RECORD=34|OwnerIndex=3228|IndexInSheet=-1|OwnerPartId=-1|Location.X=410|Location.Y=270|Orientation=1|Color=8388608|FontID=2|Text=C75|Name=Designator|ReadOnlyState=1
|RECORD=41|OwnerIndex=3228|IndexInSheet=-1|OwnerPartId=1|Location.X=450|Location.Y=250|Orientation=1|Color=8388608|FontID=2|Text=100uF_16V_2917|Name=Comment
|RECORD=44|OwnerIndex=3228
|RECORD=45|OwnerIndex=3273|IndexInSheet=-1|UseComponentLibrary=T|ModelName=FP-T495D107K016ATE125-MFG|ModelType=PCBLIB|DatafileCount=1|ModelDatafileEntity0=FP-T495D107K016ATE125-MFG|ModelDatafileKind0=PCBLib|IsCurrent=T|DatalinksLocked=T|DatabaseDatalinksLocked=T
|RECORD=46|OwnerIndex=3274
|RECORD=48|OwnerIndex=3274
|RECORD=1|LibReference=11868f565c42a9108669ba33697ecf6|ComponentDescription=CAP CER 0.1UF 50V X7R 0603|PartCount=2|DisplayModeCount=1|IndexInSheet=262|OwnerPartId=-1|Location.X=925|Location.Y=290|CurrentPartId=1|LibraryPath=*|SourceLibraryName=Altium Content Vault|TargetFileName=*|AreaColor=11599871|Color=128|PartIDLocked=T|DesignItemId=CMP-2100-03601-2|AllPinCount=2
|RECORD=2|OwnerIndex=3277|OwnerPartId=1|Electrical=4|PinConglomerate=49|PinLength=7|Location.X=925|Location.Y=283|Name=1|Designator=1|PinPropagationDelay=0.000000E+000
|RECORD=2|OwnerIndex=3277|OwnerPartId=1|Electrical=4|PinConglomerate=51|PinLength=6|Location.X=925|Location.Y=276|Name=2|Designator=2|PinPropagationDelay=0.000000E+000
|RECORD=13|OwnerIndex=3277|IsNotAccesible=T|IndexInSheet=2|OwnerPartId=1|Location.X=935|Location.Y=283|Corner.X=915|Corner.Y=283|LineWidth=1|Color=16711680
|RECORD=13|OwnerIndex=3277|IsNotAccesible=T|IndexInSheet=3|OwnerPartId=1|Location.X=935|Location.Y=277|Corner.X=915|Corner.Y=277|LineWidth=1|Color=16711680
|RECORD=13|OwnerIndex=3277|IsNotAccesible=T|IndexInSheet=4|OwnerPartId=1|Location.X=925|Location.Y=283|Corner.X=925|Corner.Y=286|LineWidth=1|Color=16711680
|RECORD=13|OwnerIndex=3277|IsNotAccesible=T|IndexInSheet=5|OwnerPartId=1|Location.X=925|Location.Y=276|Corner.X=925|Corner.Y=275|LineWidth=1|Color=16711680
|RECORD=41|OwnerIndex=3277|IndexInSheet=6|OwnerPartId=-1|Location.X=914|Location.Y=292|Color=8388608|FontID=1|IsHidden=T|Text=0.9mm|Name=Height
|RECORD=41|OwnerIndex=3277|IndexInSheet=7|OwnerPartId=-1|Location.X=914|Location.Y=292|Color=8388608|FontID=1|IsHidden=T|Text=Ceramic|Name=Material
|RECORD=41|OwnerIndex=3277|IndexInSheet=8|OwnerPartId=-1|Location.X=914|Location.Y=292|Color=8388608|FontID=1|IsHidden=T|Text=YAGEO|Name=Manufacturer
|RECORD=41|OwnerIndex=3277|IndexInSheet=9|OwnerPartId=-1|Location.X=914|Location.Y=292|Color=8388608|FontID=1|IsHidden=T|Text=50 V|Name=Voltage
|RECORD=41|OwnerIndex=3277|IndexInSheet=10|OwnerPartId=-1|Location.X=914|Location.Y=292|Color=8388608|FontID=1|IsHidden=T|Text=Datasheet|Name=ComponentLink2Description
|RECORD=41|OwnerIndex=3277|IndexInSheet=11|OwnerPartId=-1|Location.X=914|Location.Y=292|Color=8388608|FontID=1|IsHidden=T|Text=Capacitors|Name=Device Class L2
|RECORD=41|OwnerIndex=3277|IndexInSheet=12|OwnerPartId=-1|Location.X=914|Location.Y=292|Color=8388608|FontID=1|IsHidden=T|Text=+125°C|Name=Temperature Range High
|RECORD=41|OwnerIndex=3277|IndexInSheet=13|OwnerPartId=-1|Location.X=914|Location.Y=292|Color=8388608|FontID=1|IsHidden=T|Text=Cap|Name=Category
|RECORD=41|OwnerIndex=3277|IndexInSheet=14|OwnerPartId=-1|Location.X=914|Location.Y=292|Color=8388608|FontID=1|IsHidden=T|Text=100 nF|Name=Capacitance
|RECORD=41|OwnerIndex=3277|IndexInSheet=15|OwnerPartId=-1|Location.X=914|Location.Y=292|Color=8388608|FontID=7|IsHidden=T|Text=http://www.yageo.com/exep/pages/download/literatures/UPY-C_GEN_24.pdf|Name=Footprint Url
|RECORD=41|OwnerIndex=3277|IndexInSheet=16|OwnerPartId=-1|Location.X=914|Location.Y=292|Color=8388608|FontID=7|IsHidden=T|Text=http://www.yageo.com/documents/recent/UPY-GPHC_X7R_6.3V-to-50V_18.pdf|Name=ComponentLink2URL
|RECORD=41|OwnerIndex=3277|IndexInSheet=17|OwnerPartId=-1|Location.X=914|Location.Y=292|Color=8388608|FontID=1|IsHidden=T|Text=CC0603-DA|Name=Package
|RECORD=41|OwnerIndex=3277|IndexInSheet=18|OwnerPartId=-1|Location.X=914|Location.Y=292|Color=8388608|FontID=1|IsHidden=T|Text=-55°C to +125°C|Name=Temperature
|RECORD=41|OwnerIndex=3277|IndexInSheet=19|OwnerPartId=-1|Location.X=914|Location.Y=292|Color=8388608|FontID=1|IsHidden=T|Text=15%|Name=Temperature Coefficient
|RECORD=41|OwnerIndex=3277|IndexInSheet=20|OwnerPartId=-1|Location.X=914|Location.Y=292|Color=8388608|FontID=1|IsHidden=T|Text=50 V|Name=Voltage Rating
|RECORD=41|OwnerIndex=3277|IndexInSheet=21|OwnerPartId=-1|Location.X=914|Location.Y=292|Color=8388608|FontID=1|IsHidden=T|Text=X7R|Name=Temperature Characteristic
|RECORD=41|OwnerIndex=3277|IndexInSheet=22|OwnerPartId=-1|Location.X=914|Location.Y=292|Color=8388608|FontID=1|IsHidden=T|Text=Passive Components|Name=Device Class L1
|RECORD=41|OwnerIndex=3277|IndexInSheet=23|OwnerPartId=-1|Location.X=914|Location.Y=292|Color=8388608|FontID=1|IsHidden=T|Text=-55°C|Name=Temperature Range Low
|RECORD=41|OwnerIndex=3277|IndexInSheet=24|OwnerPartId=-1|Location.X=914|Location.Y=292|Color=8388608|FontID=1|IsHidden=T|Text=CC0603KRX7R9BB104|Name=Manufacturer Part Number
|RECORD=41|OwnerIndex=3277|IndexInSheet=25|OwnerPartId=-1|Location.X=914|Location.Y=292|Color=8388608|FontID=1|IsHidden=T|Text=TRUE|Name=RoHS
|RECORD=41|OwnerIndex=3277|IndexInSheet=26|OwnerPartId=-1|Location.X=914|Location.Y=292|Color=8388608|FontID=1|IsHidden=T|Text=0.1|Name=Tolerance
|RECORD=41|OwnerIndex=3277|IndexInSheet=27|OwnerPartId=-1|Location.X=914|Location.Y=292|Color=8388608|FontID=1|IsHidden=T|Text=No|Name=Automotive
|RECORD=41|OwnerIndex=3277|IndexInSheet=28|OwnerPartId=-1|Location.X=914|Location.Y=292|Color=8388608|FontID=1|IsHidden=T|Text=100 nF|Name=Value
|RECORD=41|OwnerIndex=3277|IndexInSheet=29|OwnerPartId=-1|Location.X=914|Location.Y=292|Color=8388608|FontID=1|IsHidden=T|Text=Ceramic Capacitors|Name=Device Class L3
|RECORD=41|OwnerIndex=3277|IndexInSheet=30|OwnerPartId=-1|Location.X=914|Location.Y=292|Color=8388608|FontID=7|IsHidden=T|Text=https://octopart.com/cc0603krx7r9bb104-yageo-42244635|Name=Octopart
|RECORD=41|OwnerIndex=3277|IndexInSheet=31|OwnerPartId=-1|Location.X=914|Location.Y=292|Color=8388608|FontID=1|IsHidden=T|Text=Multilayer Ceramic Capacitor, CC Series, 0.1 - F, - 10%, X7R, 50 V, 0603 [1608 Metric]|Name=Mouser Description
|RECORD=41|OwnerIndex=3277|IndexInSheet=32|OwnerPartId=-1|Location.X=914|Location.Y=292|Color=8388608|FontID=1|IsHidden=T|Text=Yes|Name=Lead Free
|RECORD=41|OwnerIndex=3277|IndexInSheet=33|OwnerPartId=-1|Location.X=914|Location.Y=292|Color=8388608|FontID=1|IsHidden=T|Text=CAP CER 0.1UF 50V X7R 0603|Name=Digikey Description
|RECORD=34|OwnerIndex=3277|IndexInSheet=-1|OwnerPartId=-1|Location.X=915|Location.Y=275|Orientation=1|Color=8388608|FontID=2|Text=C74|Name=Designator|ReadOnlyState=1
|RECORD=41|OwnerIndex=3277|IndexInSheet=-1|OwnerPartId=1|Location.X=945|Location.Y=230|Orientation=1|Color=8388608|FontID=2|Text=0.1uF_50V_0603|Name=Comment
|RECORD=44|OwnerIndex=3277
|RECORD=45|OwnerIndex=3316|IndexInSheet=-1|UseComponentLibrary=T|ModelName=FP-CC0603-DA-MFG|ModelType=PCBLIB|DatafileCount=1|ModelDatafileEntity0=FP-CC0603-DA-MFG|ModelDatafileKind0=PCBLib|IsCurrent=T|DatalinksLocked=T|DatabaseDatalinksLocked=T
|RECORD=46|OwnerIndex=3317
|RECORD=48|OwnerIndex=3317
|RECORD=45|OwnerIndex=3316|IndexInSheet=-1|UseComponentLibrary=T|ModelName=FP-CC0603-DA-IPC_C|ModelType=PCBLIB|DatafileCount=1|ModelDatafileEntity0=FP-CC0603-DA-IPC_C|ModelDatafileKind0=PCBLib|DatalinksLocked=T|DatabaseDatalinksLocked=T
|RECORD=46|OwnerIndex=3320
|RECORD=48|OwnerIndex=3320
|RECORD=45|OwnerIndex=3316|IndexInSheet=-1|UseComponentLibrary=T|ModelName=FP-CC0603-DA-IPC_B|ModelType=PCBLIB|DatafileCount=1|ModelDatafileEntity0=FP-CC0603-DA-IPC_B|ModelDatafileKind0=PCBLib|DatalinksLocked=T|DatabaseDatalinksLocked=T
|RECORD=46|OwnerIndex=3323
|RECORD=48|OwnerIndex=3323
|RECORD=45|OwnerIndex=3316|IndexInSheet=-1|UseComponentLibrary=T|ModelName=FP-CC0603-DA-IPC_A|ModelType=PCBLIB|DatafileCount=1|ModelDatafileEntity0=FP-CC0603-DA-IPC_A|ModelDatafileKind0=PCBLib|DatalinksLocked=T|DatabaseDatalinksLocked=T
|RECORD=46|OwnerIndex=3326
|RECORD=48|OwnerIndex=3326
|RECORD=1|LibReference=RES|PartCount=2|DisplayModeCount=2|IndexInSheet=263|OwnerPartId=-1|Location.X=915|Location.Y=315|Orientation=1|CurrentPartId=1|SourceLibraryName=Altium Content Vault|TargetFileName=*|AreaColor=11599871|Color=128|PartIDLocked=F|DesignItemId=CMP-2002-07443-1|AllPinCount=2
|RECORD=2|OwnerIndex=3329|OwnerPartId=1|OwnerPartDisplayMode=1|FormalType=1|Electrical=4|PinConglomerate=33|PinLength=10|Location.X=925|Location.Y=335|Name=2|Designator=2|PinPropagationDelay=0.000000E+000
|RECORD=2|OwnerIndex=3329|OwnerPartId=1|OwnerPartDisplayMode=1|FormalType=1|Electrical=4|PinConglomerate=35|PinLength=10|Location.X=925|Location.Y=315|Name=1|Designator=1|PinPropagationDelay=0.000000E+000
|RECORD=14|OwnerIndex=3329|IsNotAccesible=T|IndexInSheet=2|OwnerPartId=1|OwnerPartDisplayMode=1|Location.X=921|Location.Y=315|Corner.X=929|Corner.Y=335|LineWidth=1|Color=16711680|AreaColor=11599871
|RECORD=2|OwnerIndex=3329|OwnerPartId=1|FormalType=1|Electrical=4|PinConglomerate=33|PinLength=10|Location.X=925|Location.Y=335|Name=2|Designator=2|PinPropagationDelay=0.000000E+000
|RECORD=2|OwnerIndex=3329|OwnerPartId=1|FormalType=1|Electrical=4|PinConglomerate=35|PinLength=10|Location.X=925|Location.Y=315|Name=1|Designator=1|PinPropagationDelay=0.000000E+000
|RECORD=6|OwnerIndex=3329|IsNotAccesible=T|IndexInSheet=5|OwnerPartId=1|LineWidth=1|Color=16711680|LocationCount=10|X1=925|Y1=335|X2=925|Y2=331|X3=927|Y3=330|X4=923|Y4=328|X5=927|Y5=326|X6=923|Y6=324|X7=927|Y7=322|X8=923|Y8=320|X9=925|Y9=319|X10=925|Y10=315
|RECORD=41|OwnerIndex=3329|IndexInSheet=6|OwnerPartId=-1|Location.X=922|Location.Y=347|Color=8388608|FontID=1|IsHidden=T|Text=RC0402FR-0719K6L|Name=Part Number
|RECORD=41|OwnerIndex=3329|IndexInSheet=7|OwnerPartId=-1|Location.X=922|Location.Y=347|Color=8388608|FontID=1|IsHidden=T|Text=Yageo|Name=Manufacturer
|RECORD=34|OwnerIndex=3329|IndexInSheet=-1|OwnerPartId=-1|Location.X=920|Location.Y=310|Orientation=1|Color=8388608|FontID=2|Text=R75|Name=Designator|ReadOnlyState=1
|RECORD=41|OwnerIndex=3329|IndexInSheet=-1|OwnerPartId=-1|Location.X=940|Location.Y=300|Orientation=1|Color=8388608|FontID=2|Text=19.6K_1%_0402|Name=Comment
|RECORD=44|OwnerIndex=3329
|RECORD=45|OwnerIndex=3344|IndexInSheet=-1|Description=Chip Resistor, 2-Leads, Body 1.00x0.50mm, IPC Medium Density|UseComponentLibrary=T|ModelName=RESC1005X40X25NL05T10|ModelType=PCBLIB|DatafileCount=1|ModelDatafileEntity0=RESC1005X40X25NL05T10|ModelDatafileKind0=PCBLib|IsCurrent=T|DatalinksLocked=T|DatabaseDatalinksLocked=T
|RECORD=46|OwnerIndex=3345
|RECORD=48|OwnerIndex=3345
|RECORD=41|OwnerIndex=3347|IndexInSheet=-1|OwnerPartId=-1|Color=8388608|FontID=1|IsHidden=T|Text=2D|Name=Available Preview Images
|RECORD=45|OwnerIndex=3344|IndexInSheet=-1|Description=Chip Resistor, 2-Leads, Body 1.00x0.50mm, IPC Low Density|UseComponentLibrary=T|ModelName=RESC1005X40X25ML05T10|ModelType=PCBLIB|DatafileCount=1|ModelDatafileEntity0=RESC1005X40X25ML05T10|ModelDatafileKind0=PCBLib|DatalinksLocked=T|DatabaseDatalinksLocked=T
|RECORD=46|OwnerIndex=3349
|RECORD=48|OwnerIndex=3349
|RECORD=41|OwnerIndex=3351|IndexInSheet=-1|OwnerPartId=-1|Color=8388608|FontID=1|IsHidden=T|Text=2D|Name=Available Preview Images
|RECORD=45|OwnerIndex=3344|IndexInSheet=-1|Description=Chip Resistor, 2-Leads, Body 1.00x0.50mm, IPC High Density|UseComponentLibrary=T|ModelName=RESC1005X40X25LL05T10|ModelType=PCBLIB|DatafileCount=1|ModelDatafileEntity0=RESC1005X40X25LL05T10|ModelDatafileKind0=PCBLib|DatalinksLocked=T|DatabaseDatalinksLocked=T
|RECORD=46|OwnerIndex=3353
|RECORD=48|OwnerIndex=3353
|RECORD=41|OwnerIndex=3355|IndexInSheet=-1|OwnerPartId=-1|Color=8388608|FontID=1|IsHidden=T|Text=2D|Name=Available Preview Images
|RECORD=25|IndexInSheet=264|OwnerPartId=-1|Location.X=525|Location.Y=435|Color=128|FontID=1|Text=P3V3_FB
|RECORD=25|IndexInSheet=265|OwnerPartId=-1|Location.X=830|Location.Y=225|Color=128|FontID=1|Text=P3V3_FB
|RECORD=1|LibReference=RES|PartCount=2|DisplayModeCount=2|IndexInSheet=266|OwnerPartId=-1|Location.X=1005|Location.Y=300|Orientation=1|CurrentPartId=1|SourceLibraryName=Altium Content Vault|TargetFileName=*|AreaColor=11599871|Color=128|PartIDLocked=F|DesignItemId=CMP-2002-07571-1|AllPinCount=2
|RECORD=2|OwnerIndex=3359|OwnerPartId=1|OwnerPartDisplayMode=1|FormalType=1|Electrical=4|PinConglomerate=33|PinLength=10|Location.X=1015|Location.Y=320|Name=2|Designator=2|PinPropagationDelay=0.000000E+000
|RECORD=2|OwnerIndex=3359|OwnerPartId=1|OwnerPartDisplayMode=1|FormalType=1|Electrical=4|PinConglomerate=35|PinLength=10|Location.X=1015|Location.Y=300|Name=1|Designator=1|PinPropagationDelay=0.000000E+000
|RECORD=14|OwnerIndex=3359|IsNotAccesible=T|IndexInSheet=2|OwnerPartId=1|OwnerPartDisplayMode=1|Location.X=1011|Location.Y=300|Corner.X=1019|Corner.Y=320|LineWidth=1|Color=16711680|AreaColor=11599871
|RECORD=2|OwnerIndex=3359|OwnerPartId=1|FormalType=1|Electrical=4|PinConglomerate=33|PinLength=10|Location.X=1015|Location.Y=320|Name=2|Designator=2|PinPropagationDelay=0.000000E+000
|RECORD=2|OwnerIndex=3359|OwnerPartId=1|FormalType=1|Electrical=4|PinConglomerate=35|PinLength=10|Location.X=1015|Location.Y=300|Name=1|Designator=1|PinPropagationDelay=0.000000E+000
|RECORD=6|OwnerIndex=3359|IsNotAccesible=T|IndexInSheet=5|OwnerPartId=1|LineWidth=1|Color=16711680|LocationCount=10|X1=1015|Y1=320|X2=1015|Y2=316|X3=1017|Y3=315|X4=1013|Y4=313|X5=1017|Y5=311|X6=1013|Y6=309|X7=1017|Y7=307|X8=1013|Y8=305|X9=1015|Y9=304|X10=1015|Y10=300
|RECORD=41|OwnerIndex=3359|IndexInSheet=6|OwnerPartId=-1|Location.X=1012|Location.Y=332|Color=8388608|FontID=1|IsHidden=T|Text=RC0402FR-072K49L|Name=Part Number
|RECORD=41|OwnerIndex=3359|IndexInSheet=7|OwnerPartId=-1|Location.X=1012|Location.Y=332|Color=8388608|FontID=1|IsHidden=T|Text=Yageo|Name=Manufacturer
|RECORD=34|OwnerIndex=3359|IndexInSheet=-1|OwnerPartId=-1|Location.X=1010|Location.Y=300|Orientation=1|Color=8388608|FontID=2|Text=R76|Name=Designator|ReadOnlyState=1
|RECORD=41|OwnerIndex=3359|IndexInSheet=-1|OwnerPartId=-1|Location.X=1030|Location.Y=280|Orientation=1|Color=8388608|FontID=2|Text=2.49K_1%_0402|Name=Comment
|RECORD=44|OwnerIndex=3359
|RECORD=45|OwnerIndex=3374|IndexInSheet=-1|Description=Chip Resistor, 2-Leads, Body 1.00x0.50mm, IPC Medium Density|UseComponentLibrary=T|ModelName=RESC1005X40X25NL05T10|ModelType=PCBLIB|DatafileCount=1|ModelDatafileEntity0=RESC1005X40X25NL05T10|ModelDatafileKind0=PCBLib|IsCurrent=T|DatalinksLocked=T|DatabaseDatalinksLocked=T
|RECORD=46|OwnerIndex=3375
|RECORD=48|OwnerIndex=3375
|RECORD=41|OwnerIndex=3377|IndexInSheet=-1|OwnerPartId=-1|Color=8388608|FontID=1|IsHidden=T|Text=2D|Name=Available Preview Images
|RECORD=45|OwnerIndex=3374|IndexInSheet=-1|Description=Chip Resistor, 2-Leads, Body 1.00x0.50mm, IPC High Density|UseComponentLibrary=T|ModelName=RESC1005X40X25LL05T10|ModelType=PCBLIB|DatafileCount=1|ModelDatafileEntity0=RESC1005X40X25LL05T10|ModelDatafileKind0=PCBLib|DatalinksLocked=T|DatabaseDatalinksLocked=T
|RECORD=46|OwnerIndex=3379
|RECORD=48|OwnerIndex=3379
|RECORD=41|OwnerIndex=3381|IndexInSheet=-1|OwnerPartId=-1|Color=8388608|FontID=1|IsHidden=T|Text=2D|Name=Available Preview Images
|RECORD=45|OwnerIndex=3374|IndexInSheet=-1|Description=Chip Resistor, 2-Leads, Body 1.00x0.50mm, IPC Low Density|UseComponentLibrary=T|ModelName=RESC1005X40X25ML05T10|ModelType=PCBLIB|DatafileCount=1|ModelDatafileEntity0=RESC1005X40X25ML05T10|ModelDatafileKind0=PCBLib|DatalinksLocked=T|DatabaseDatalinksLocked=T
|RECORD=46|OwnerIndex=3383
|RECORD=48|OwnerIndex=3383
|RECORD=41|OwnerIndex=3385|IndexInSheet=-1|OwnerPartId=-1|Color=8388608|FontID=1|IsHidden=T|Text=2D|Name=Available Preview Images
|RECORD=1|LibReference=11868f565c42a9108669ba33697ecf6|ComponentDescription=CAP CER 4700PF 50V X7R 0402|PartCount=2|DisplayModeCount=1|IndexInSheet=267|OwnerPartId=-1|Location.X=980|Location.Y=315|CurrentPartId=1|LibraryPath=*|SourceLibraryName=Altium Content Vault|TargetFileName=*|AreaColor=11599871|Color=128|PartIDLocked=T|DesignItemId=CMP-03422-001290-1|AllPinCount=2
|RECORD=2|OwnerIndex=3387|OwnerPartId=1|Electrical=4|PinConglomerate=49|PinLength=7|Location.X=980|Location.Y=308|Name=1|Designator=1|PinPropagationDelay=0.000000E+000
|RECORD=2|OwnerIndex=3387|OwnerPartId=1|Electrical=4|PinConglomerate=51|PinLength=6|Location.X=980|Location.Y=301|Name=2|Designator=2|PinPropagationDelay=0.000000E+000
|RECORD=13|OwnerIndex=3387|IsNotAccesible=T|IndexInSheet=2|OwnerPartId=1|Location.X=990|Location.Y=308|Corner.X=970|Corner.Y=308|LineWidth=1|Color=16711680
|RECORD=13|OwnerIndex=3387|IsNotAccesible=T|IndexInSheet=3|OwnerPartId=1|Location.X=990|Location.Y=302|Corner.X=970|Corner.Y=302|LineWidth=1|Color=16711680
|RECORD=13|OwnerIndex=3387|IsNotAccesible=T|IndexInSheet=4|OwnerPartId=1|Location.X=980|Location.Y=308|Corner.X=980|Corner.Y=311|LineWidth=1|Color=16711680
|RECORD=13|OwnerIndex=3387|IsNotAccesible=T|IndexInSheet=5|OwnerPartId=1|Location.X=980|Location.Y=301|Corner.X=980|Corner.Y=300|LineWidth=1|Color=16711680
|RECORD=41|OwnerIndex=3387|IndexInSheet=6|OwnerPartId=-1|Location.X=969|Location.Y=317|Color=8388608|FontID=7|IsHidden=T|Text=http://www.yageo.com/documents/recent/UPY-GP_NP0_16V-to-50V_16.pdf|Name=ComponentLink2URL
|RECORD=41|OwnerIndex=3387|IndexInSheet=7|OwnerPartId=-1|Location.X=969|Location.Y=317|Color=8388608|FontID=1|IsHidden=T|Text=Ceramic|Name=Material
|RECORD=41|OwnerIndex=3387|IndexInSheet=8|OwnerPartId=-1|Location.X=969|Location.Y=317|Color=8388608|FontID=1|IsHidden=T|Text=Ceramic Capacitors|Name=Device Class L3
|RECORD=41|OwnerIndex=3387|IndexInSheet=9|OwnerPartId=-1|Location.X=969|Location.Y=317|Color=8388608|FontID=1|IsHidden=T|Text=0.55mm|Name=Height
|RECORD=41|OwnerIndex=3387|IndexInSheet=10|OwnerPartId=-1|Location.X=969|Location.Y=317|Color=8388608|FontID=1|IsHidden=T|Text=TRUE|Name=RoHS
|RECORD=41|OwnerIndex=3387|IndexInSheet=11|OwnerPartId=-1|Location.X=969|Location.Y=317|Color=8388608|FontID=1|IsHidden=T|Text=Multilayer Ceramic Capacitors MLCC - SMD/SMT 4.7nF 50V X7R 10%|Name=Mouser Description
|RECORD=41|OwnerIndex=3387|IndexInSheet=12|OwnerPartId=-1|Location.X=969|Location.Y=317|Color=8388608|FontID=1|IsHidden=T|Text=Cap|Name=Category
|RECORD=41|OwnerIndex=3387|IndexInSheet=13|OwnerPartId=-1|Location.X=969|Location.Y=317|Color=8388608|FontID=1|IsHidden=T|Text=YAGEO|Name=Manufacturer
|RECORD=41|OwnerIndex=3387|IndexInSheet=14|OwnerPartId=-1|Location.X=969|Location.Y=317|Color=8388608|FontID=1|IsHidden=T|Text=-55°C to +125°C|Name=Temperature
|RECORD=41|OwnerIndex=3387|IndexInSheet=15|OwnerPartId=-1|Location.X=969|Location.Y=317|Color=8388608|FontID=7|IsHidden=T|Text=http://www.yageo.com/exep/pages/download/literatures/UPY-C_GEN_24.pdf|Name=Footprint Url
|RECORD=41|OwnerIndex=3387|IndexInSheet=16|OwnerPartId=-1|Location.X=969|Location.Y=317|Color=8388608|FontID=1|IsHidden=T|Text=Capacitors|Name=Device Class L2
|RECORD=41|OwnerIndex=3387|IndexInSheet=17|OwnerPartId=-1|Location.X=969|Location.Y=317|Color=8388608|FontID=1|IsHidden=T|Text=No|Name=Automotive
|RECORD=41|OwnerIndex=3387|IndexInSheet=18|OwnerPartId=-1|Location.X=969|Location.Y=317|Color=8388608|FontID=1|IsHidden=T|Text=30ppm/°C|Name=Temperature Coefficient
|RECORD=41|OwnerIndex=3387|IndexInSheet=19|OwnerPartId=-1|Location.X=969|Location.Y=317|Color=8388608|FontID=7|IsHidden=T|Text=https://octopart.com/cc0402krx7r9bb472-yageo-9288149|Name=Octopart
|RECORD=41|OwnerIndex=3387|IndexInSheet=20|OwnerPartId=-1|Location.X=969|Location.Y=317|Color=8388608|FontID=1|IsHidden=T|Text=CAP CER 4700PF 50V X7R 0402|Name=Digikey Description
|RECORD=41|OwnerIndex=3387|IndexInSheet=21|OwnerPartId=-1|Location.X=969|Location.Y=317|Color=8388608|FontID=1|IsHidden=T|Text=Yes|Name=Lead Free
|RECORD=41|OwnerIndex=3387|IndexInSheet=22|OwnerPartId=-1|Location.X=969|Location.Y=317|Color=8388608|FontID=1|IsHidden=T|Text=CAPC10050X50|Name=Ipc Land Pattern Name
|RECORD=41|OwnerIndex=3387|IndexInSheet=23|OwnerPartId=-1|Location.X=969|Location.Y=317|Color=8388608|FontID=1|IsHidden=T|Text=Passive Components|Name=Device Class L1
|RECORD=41|OwnerIndex=3387|IndexInSheet=24|OwnerPartId=-1|Location.X=969|Location.Y=317|Color=8388608|FontID=1|IsHidden=T|Text=Datasheet|Name=ComponentLink2Description
|RECORD=41|OwnerIndex=3387|IndexInSheet=25|OwnerPartId=-1|Location.X=969|Location.Y=317|Color=8388608|FontID=1|IsHidden=T|Text=CC0402KRX7R9BB472|Name=Manufacturer Part Number
|RECORD=41|OwnerIndex=3387|IndexInSheet=26|OwnerPartId=-1|Location.X=969|Location.Y=317|Color=8388608|FontID=1|IsHidden=T|Text=4.7 nF|Name=Capacitance
|RECORD=41|OwnerIndex=3387|IndexInSheet=27|OwnerPartId=-1|Location.X=969|Location.Y=317|Color=8388608|FontID=1|IsHidden=T|Text=X7R|Name=Temperature Characteristic
|RECORD=41|OwnerIndex=3387|IndexInSheet=28|OwnerPartId=-1|Location.X=969|Location.Y=317|Color=8388608|FontID=1|IsHidden=T|Text=50 V|Name=Voltage Rating
|RECORD=41|OwnerIndex=3387|IndexInSheet=29|OwnerPartId=-1|Location.X=969|Location.Y=317|Color=8388608|FontID=1|IsHidden=T|Text=0.1|Name=Tolerance
|RECORD=41|OwnerIndex=3387|IndexInSheet=30|OwnerPartId=-1|Location.X=969|Location.Y=317|Color=8388608|FontID=1|IsHidden=T|Text=NA|Name=Automotive Grade
|RECORD=41|OwnerIndex=3387|IndexInSheet=31|OwnerPartId=-1|Location.X=969|Location.Y=317|Color=8388608|FontID=1|IsHidden=T|Text=-55°C|Name=Temperature Range Low
|RECORD=41|OwnerIndex=3387|IndexInSheet=32|OwnerPartId=-1|Location.X=969|Location.Y=317|Color=8388608|FontID=1|IsHidden=T|Text=4.7 nF|Name=Value
|RECORD=41|OwnerIndex=3387|IndexInSheet=33|OwnerPartId=-1|Location.X=969|Location.Y=317|Color=8388608|FontID=1|IsHidden=T|Text=+125°C|Name=Temperature Range High
|RECORD=41|OwnerIndex=3387|IndexInSheet=34|OwnerPartId=-1|Location.X=969|Location.Y=317|Color=8388608|FontID=1|IsHidden=T|Text=CC0402|Name=Package
|RECORD=34|OwnerIndex=3387|IndexInSheet=-1|OwnerPartId=-1|Location.X=965|Location.Y=300|Orientation=1|Color=8388608|FontID=2|Text=C73|Name=Designator|ReadOnlyState=1
|RECORD=41|OwnerIndex=3387|IndexInSheet=-1|OwnerPartId=1|Location.X=1000|Location.Y=275|Orientation=1|Color=8388608|FontID=2|Text=4.7nF_50V_0402|Name=Comment
|RECORD=44|OwnerIndex=3387
|RECORD=45|OwnerIndex=3427|IndexInSheet=-1|UseComponentLibrary=T|ModelName=FP-CC0402-MFG|ModelType=PCBLIB|DatafileCount=1|ModelDatafileEntity0=FP-CC0402-MFG|ModelDatafileKind0=PCBLib|IsCurrent=T|DatalinksLocked=T|DatabaseDatalinksLocked=T
|RECORD=46|OwnerIndex=3428
|RECORD=48|OwnerIndex=3428
|RECORD=45|OwnerIndex=3427|IndexInSheet=-1|UseComponentLibrary=T|ModelName=FP-CC0402-IPC_C|ModelType=PCBLIB|DatafileCount=1|ModelDatafileEntity0=FP-CC0402-IPC_C|ModelDatafileKind0=PCBLib|DatalinksLocked=T|DatabaseDatalinksLocked=T
|RECORD=46|OwnerIndex=3431
|RECORD=48|OwnerIndex=3431
|RECORD=45|OwnerIndex=3427|IndexInSheet=-1|UseComponentLibrary=T|ModelName=FP-CC0402-IPC_B|ModelType=PCBLIB|DatafileCount=1|ModelDatafileEntity0=FP-CC0402-IPC_B|ModelDatafileKind0=PCBLib|DatalinksLocked=T|DatabaseDatalinksLocked=T
|RECORD=46|OwnerIndex=3434
|RECORD=48|OwnerIndex=3434
|RECORD=45|OwnerIndex=3427|IndexInSheet=-1|UseComponentLibrary=T|ModelName=FP-CC0402-IPC_A|ModelType=PCBLIB|DatafileCount=1|ModelDatafileEntity0=FP-CC0402-IPC_A|ModelDatafileKind0=PCBLib|DatalinksLocked=T|DatabaseDatalinksLocked=T
|RECORD=46|OwnerIndex=3437
|RECORD=48|OwnerIndex=3437
|RECORD=17|IndexInSheet=268|OwnerPartId=-1|Style=4|ShowNetName=T|Location.X=1015|Location.Y=170|Orientation=3|Color=128|FontID=1|Text=GND
|RECORD=17|IndexInSheet=269|OwnerPartId=-1|ShowNetName=T|Location.X=1015|Location.Y=390|Orientation=1|Color=128|FontID=1|Text=P3V3_SENSE
|RECORD=1|LibReference=RES|PartCount=2|DisplayModeCount=2|IndexInSheet=270|OwnerPartId=-1|Location.X=1040|Location.Y=385|CurrentPartId=1|SourceLibraryName=Altium Content Vault|TargetFileName=*|AreaColor=11599871|Color=128|PartIDLocked=F|DesignItemId=CMP-2003-04334-1|AllPinCount=2
|RECORD=2|OwnerIndex=3442|OwnerPartId=1|OwnerPartDisplayMode=1|FormalType=1|Electrical=4|PinConglomerate=32|PinLength=10|Location.X=1060|Location.Y=375|Name=2|Designator=2|PinPropagationDelay=0.000000E+000
|RECORD=2|OwnerIndex=3442|OwnerPartId=1|OwnerPartDisplayMode=1|FormalType=1|Electrical=4|PinConglomerate=34|PinLength=10|Location.X=1040|Location.Y=375|Name=1|Designator=1|PinPropagationDelay=0.000000E+000
|RECORD=14|OwnerIndex=3442|IsNotAccesible=T|IndexInSheet=2|OwnerPartId=1|OwnerPartDisplayMode=1|Location.X=1040|Location.Y=371|Corner.X=1060|Corner.Y=379|LineWidth=1|Color=16711680|AreaColor=11599871
|RECORD=2|OwnerIndex=3442|OwnerPartId=1|FormalType=1|Electrical=4|PinConglomerate=32|PinLength=10|Location.X=1060|Location.Y=375|Name=2|Designator=2|PinPropagationDelay=0.000000E+000
|RECORD=2|OwnerIndex=3442|OwnerPartId=1|FormalType=1|Electrical=4|PinConglomerate=34|PinLength=10|Location.X=1040|Location.Y=375|Name=1|Designator=1|PinPropagationDelay=0.000000E+000
|RECORD=6|OwnerIndex=3442|IsNotAccesible=T|IndexInSheet=5|OwnerPartId=1|LineWidth=1|Color=16711680|LocationCount=10|X1=1060|Y1=375|X2=1056|Y2=375|X3=1055|Y3=373|X4=1053|Y4=377|X5=1051|Y5=373|X6=1049|Y6=377|X7=1047|Y7=373|X8=1045|Y8=377|X9=1044|Y9=375|X10=1040|Y10=375
|RECORD=41|OwnerIndex=3442|IndexInSheet=6|OwnerPartId=-1|Location.X=1028|Location.Y=388|Color=8388608|FontID=1|IsHidden=T|Text=Vishay Dale|Name=Manufacturer
|RECORD=41|OwnerIndex=3442|IndexInSheet=7|OwnerPartId=-1|Location.X=1028|Location.Y=388|Color=8388608|FontID=1|IsHidden=T|Text=WSL12062L000FEA18|Name=Part Number
|RECORD=34|OwnerIndex=3442|IndexInSheet=-1|OwnerPartId=-1|Location.X=1039|Location.Y=378|Color=8388608|FontID=1|Text=R72|Name=Designator|ReadOnlyState=1
|RECORD=41|OwnerIndex=3442|IndexInSheet=-1|OwnerPartId=-1|Location.X=1039|Location.Y=362|Color=8388608|FontID=1|Text=2mOhm_1%_1206|Name=Comment
|RECORD=44|OwnerIndex=3442
|RECORD=45|OwnerIndex=3457|IndexInSheet=-1|Description=Chip Resistor, 2-Leads, Body 3.20x1.60mm, IPC Medium Density|UseComponentLibrary=T|ModelName=RESC3216X89X64NL25T25|ModelType=PCBLIB|DatafileCount=1|ModelDatafileEntity0=RESC3216X89X64NL25T25|ModelDatafileKind0=PCBLib|IsCurrent=T|DatalinksLocked=T|DatabaseDatalinksLocked=T
|RECORD=46|OwnerIndex=3458
|RECORD=48|OwnerIndex=3458
|RECORD=41|OwnerIndex=3460|IndexInSheet=-1|OwnerPartId=-1|Color=8388608|FontID=1|IsHidden=T|Text=2D|Name=Available Preview Images
|RECORD=45|OwnerIndex=3457|IndexInSheet=-1|Description=Chip Resistor, 2-Leads, Body 3.20x1.60mm, IPC High Density|UseComponentLibrary=T|ModelName=RESC3216X89X64LL25T25|ModelType=PCBLIB|DatafileCount=1|ModelDatafileEntity0=RESC3216X89X64LL25T25|ModelDatafileKind0=PCBLib|DatalinksLocked=T|DatabaseDatalinksLocked=T
|RECORD=46|OwnerIndex=3462
|RECORD=48|OwnerIndex=3462
|RECORD=41|OwnerIndex=3464|IndexInSheet=-1|OwnerPartId=-1|Color=8388608|FontID=1|IsHidden=T|Text=2D|Name=Available Preview Images
|RECORD=45|OwnerIndex=3457|IndexInSheet=-1|Description=Chip Resistor, 2-Leads, Body 3.20x1.60mm, IPC Low Density|UseComponentLibrary=T|ModelName=RESC3216X89X64ML25T25|ModelType=PCBLIB|DatafileCount=1|ModelDatafileEntity0=RESC3216X89X64ML25T25|ModelDatafileKind0=PCBLib|DatalinksLocked=T|DatabaseDatalinksLocked=T
|RECORD=46|OwnerIndex=3466
|RECORD=48|OwnerIndex=3466
|RECORD=41|OwnerIndex=3468|IndexInSheet=-1|OwnerPartId=-1|Color=8388608|FontID=1|IsHidden=T|Text=2D|Name=Available Preview Images
|RECORD=1|LibReference=b4654b650e69147ec39a6b967a45e02|ComponentDescription=Multilayer Ceramic Capacitor 10uF 16V X5R 20% SMD 0603 T/R|PartCount=2|DisplayModeCount=1|IndexInSheet=271|OwnerPartId=-1|Location.X=1165|Location.Y=235|CurrentPartId=1|LibraryPath=*|SourceLibraryName=Altium Content Vault|TargetFileName=*|AreaColor=11599871|Color=128|PartIDLocked=T|DesignItemId=CMP-2000-06226-4|AllPinCount=2
|RECORD=2|OwnerIndex=3470|OwnerPartId=1|Electrical=4|PinConglomerate=49|PinLength=7|Location.X=1165|Location.Y=228|Name=1|Designator=1|PinPropagationDelay=0.000000E+000
|RECORD=2|OwnerIndex=3470|OwnerPartId=1|Electrical=4|PinConglomerate=51|PinLength=6|Location.X=1165|Location.Y=221|Name=2|Designator=2|PinPropagationDelay=0.000000E+000
|RECORD=13|OwnerIndex=3470|IsNotAccesible=T|IndexInSheet=2|OwnerPartId=1|Location.X=1175|Location.Y=228|Corner.X=1155|Corner.Y=228|LineWidth=1|Color=16711680
|RECORD=13|OwnerIndex=3470|IsNotAccesible=T|IndexInSheet=3|OwnerPartId=1|Location.X=1175|Location.Y=222|Corner.X=1155|Corner.Y=222|LineWidth=1|Color=16711680
|RECORD=13|OwnerIndex=3470|IsNotAccesible=T|IndexInSheet=4|OwnerPartId=1|Location.X=1165|Location.Y=228|Corner.X=1165|Corner.Y=231|LineWidth=1|Color=16711680
|RECORD=13|OwnerIndex=3470|IsNotAccesible=T|IndexInSheet=5|OwnerPartId=1|Location.X=1165|Location.Y=221|Corner.X=1165|Corner.Y=220|LineWidth=1|Color=16711680
|RECORD=41|OwnerIndex=3470|IndexInSheet=6|OwnerPartId=-1|Location.X=1154|Location.Y=237|Color=8388608|FontID=1|IsHidden=T|Text=Tape and Reel|Name=Packaging
|RECORD=41|OwnerIndex=3470|IndexInSheet=7|OwnerPartId=-1|Location.X=1154|Location.Y=237|Color=8388608|FontID=1|IsHidden=T|Text=Flat|Name=Construction
|RECORD=41|OwnerIndex=3470|IndexInSheet=8|OwnerPartId=-1|Location.X=1154|Location.Y=237|Color=8388608|FontID=1|IsHidden=T|Text=0.8mm|Name=Height
|RECORD=41|OwnerIndex=3470|IndexInSheet=9|OwnerPartId=-1|Location.X=1154|Location.Y=237|Color=8388608|FontID=1|IsHidden=T|Text=85°C|Name=Max Operating Temperature
|RECORD=41|OwnerIndex=3470|IndexInSheet=10|OwnerPartId=-1|Location.X=1154|Location.Y=237|Color=8388608|FontID=1|IsHidden=T|Text=X5R|Name=Dielectric
|RECORD=41|OwnerIndex=3470|IndexInSheet=11|OwnerPartId=-1|Location.X=1154|Location.Y=237|Color=8388608|FontID=1|IsHidden=T|Text=1608|Name=Case Code (Metric)
|RECORD=41|OwnerIndex=3470|IndexInSheet=12|OwnerPartId=-1|Location.X=1154|Location.Y=237|Color=8388608|FontID=1|IsHidden=T|Text=16V|Name=Voltage Rating (DC)
|RECORD=41|OwnerIndex=3470|IndexInSheet=13|OwnerPartId=-1|Location.X=1154|Location.Y=237|Color=8388608|FontID=1|IsHidden=T|Text=0.031inch|Name=Width
|RECORD=41|OwnerIndex=3470|IndexInSheet=14|OwnerPartId=-1|Location.X=1154|Location.Y=237|Color=8388608|FontID=1|IsHidden=T|Text=16V|Name=Voltage Rating
|RECORD=41|OwnerIndex=3470|IndexInSheet=15|OwnerPartId=-1|Location.X=1154|Location.Y=237|Color=8388608|FontID=1|IsHidden=T|Text=0.063inch|Name=Length
|RECORD=41|OwnerIndex=3470|IndexInSheet=16|OwnerPartId=-1|Location.X=1154|Location.Y=237|Color=8388608|FontID=1|IsHidden=T|Text=Yes|Name=RoHS Compliant
|RECORD=41|OwnerIndex=3470|IndexInSheet=17|OwnerPartId=-1|Location.X=1154|Location.Y=237|Color=8388608|FontID=1|IsHidden=T|Text=Halogen Free|Name=Halogen Free
|RECORD=41|OwnerIndex=3470|IndexInSheet=18|OwnerPartId=-1|Location.X=1154|Location.Y=237|Color=8388608|FontID=1|IsHidden=T|Text=0603|Name=Case Code (Imperial)
|RECORD=41|OwnerIndex=3470|IndexInSheet=19|OwnerPartId=-1|Location.X=1154|Location.Y=237|Color=8388608|FontID=1|IsHidden=T|Text=10uF|Name=Capacitance
|RECORD=41|OwnerIndex=3470|IndexInSheet=20|OwnerPartId=-1|Location.X=1154|Location.Y=237|Color=8388608|FontID=1|IsHidden=T|Text=Surface Mount|Name=Mount
|RECORD=41|OwnerIndex=3470|IndexInSheet=21|OwnerPartId=-1|Location.X=1154|Location.Y=237|Color=8388608|FontID=1|IsHidden=T|Text=0.031inch|Name=Thickness
|RECORD=41|OwnerIndex=3470|IndexInSheet=22|OwnerPartId=-1|Location.X=1154|Location.Y=237|Color=8388608|FontID=1|IsHidden=T|Text=20%|Name=Tolerance
|RECORD=41|OwnerIndex=3470|IndexInSheet=23|OwnerPartId=-1|Location.X=1154|Location.Y=237|Color=8388608|FontID=1|IsHidden=T|Text=-55°C|Name=Min Operating Temperature
|RECORD=41|OwnerIndex=3470|IndexInSheet=24|OwnerPartId=-1|Location.X=1154|Location.Y=237|Color=8388608|FontID=1|IsHidden=T|Text=M|Name=Series
|RECORD=41|OwnerIndex=3470|IndexInSheet=25|OwnerPartId=-1|Location.X=1154|Location.Y=237|Color=8388608|FontID=1|IsHidden=T|Text=SMD/SMT|Name=Termination
|RECORD=41|OwnerIndex=3470|IndexInSheet=26|OwnerPartId=-1|Location.X=1154|Location.Y=237|Color=8388608|FontID=1|IsHidden=T|Text=0603|Name=Case/Package
|RECORD=41|OwnerIndex=3470|IndexInSheet=27|OwnerPartId=-1|Location.X=1154|Location.Y=237|Color=8388608|FontID=1|IsHidden=T|Text=1|Name=Package Quantity
|RECORD=34|OwnerIndex=3470|IndexInSheet=-1|OwnerPartId=-1|Location.X=1155|Location.Y=215|Orientation=1|Color=8388608|FontID=2|Text=C80|Name=Designator|ReadOnlyState=1
|RECORD=41|OwnerIndex=3470|IndexInSheet=-1|OwnerPartId=1|Location.X=1185|Location.Y=200|Orientation=1|Color=8388608|FontID=2|Text=10uF_16V_0603|Name=Comment
|RECORD=44|OwnerIndex=3470
|RECORD=45|OwnerIndex=3503|IndexInSheet=-1|UseComponentLibrary=T|ModelName=FP-0603-L_1_6_0_2-W_0_8_0-MFG|ModelType=PCBLIB|DatafileCount=1|ModelDatafileEntity0=FP-0603-L_1_6_0_2-W_0_8_0-MFG|ModelDatafileKind0=PCBLib|IsCurrent=T|DatalinksLocked=T|DatabaseDatalinksLocked=T
|RECORD=46|OwnerIndex=3504
|RECORD=48|OwnerIndex=3504
|RECORD=45|OwnerIndex=3503|IndexInSheet=-1|UseComponentLibrary=T|ModelName=FP-0603-L_1_6_0_2-W_0_8_0-IPC_B|ModelType=PCBLIB|DatafileCount=1|ModelDatafileEntity0=FP-0603-L_1_6_0_2-W_0_8_0-IPC_B|ModelDatafileKind0=PCBLib|DatalinksLocked=T|DatabaseDatalinksLocked=T
|RECORD=46|OwnerIndex=3507
|RECORD=48|OwnerIndex=3507
|RECORD=45|OwnerIndex=3503|IndexInSheet=-1|UseComponentLibrary=T|ModelName=FP-0603-L_1_6_0_2-W_0_8_0-IPC_C|ModelType=PCBLIB|DatafileCount=1|ModelDatafileEntity0=FP-0603-L_1_6_0_2-W_0_8_0-IPC_C|ModelDatafileKind0=PCBLib|DatalinksLocked=T|DatabaseDatalinksLocked=T
|RECORD=46|OwnerIndex=3510
|RECORD=48|OwnerIndex=3510
|RECORD=45|OwnerIndex=3503|IndexInSheet=-1|UseComponentLibrary=T|ModelName=FP-0603-L_1_6_0_2-W_0_8_0-IPC_A|ModelType=PCBLIB|DatafileCount=1|ModelDatafileEntity0=FP-0603-L_1_6_0_2-W_0_8_0-IPC_A|ModelDatafileKind0=PCBLib|DatalinksLocked=T|DatabaseDatalinksLocked=T
|RECORD=46|OwnerIndex=3513
|RECORD=48|OwnerIndex=3513
|RECORD=1|LibReference=a00bbbee19879c290e62620ae7e47b1|ComponentDescription=CAP TANT 100UF 10% 16V 2917|PartCount=2|DisplayModeCount=1|IndexInSheet=272|OwnerPartId=-1|Location.X=1080|Location.Y=235|CurrentPartId=1|LibraryPath=*|SourceLibraryName=Altium Content Vault|TargetFileName=*|AreaColor=11599871|Color=128|PartIDLocked=T|DesignItemId=CMP-2000-07207-2|AllPinCount=2
|RECORD=2|OwnerIndex=3516|OwnerPartId=1|Electrical=4|PinConglomerate=51|PinLength=8|Location.X=1080|Location.Y=223|Name=C|Designator=1|PinPropagationDelay=0.000000E+000
|RECORD=2|OwnerIndex=3516|OwnerPartId=1|Electrical=4|PinConglomerate=49|PinLength=8|Location.X=1080|Location.Y=227|Name=A|Designator=2|PinPropagationDelay=0.000000E+000
|RECORD=5|OwnerIndex=3516|IsNotAccesible=T|IndexInSheet=2|OwnerPartId=1|LineWidth=1|Color=16711680|LocationCount=4|X1=1070|Y1=219|X2=1075|Y2=225|X3=1085|Y3=225|X4=1090|Y4=219
|RECORD=13|OwnerIndex=3516|IsNotAccesible=T|IndexInSheet=3|OwnerPartId=1|Location.X=1070|Location.Y=227|Corner.X=1090|Corner.Y=227|LineWidth=1|Color=16711680
|RECORD=13|OwnerIndex=3516|IsNotAccesible=T|IndexInSheet=4|OwnerPartId=1|Location.X=1080|Location.Y=223|Corner.X=1080|Corner.Y=221|LineWidth=1|Color=16711680
|RECORD=13|OwnerIndex=3516|IsNotAccesible=T|IndexInSheet=5|OwnerPartId=1|Location.X=1080|Location.Y=227|Corner.X=1080|Corner.Y=230|LineWidth=1|Color=16711680
|RECORD=4|OwnerIndex=3516|IsNotAccesible=T|IndexInSheet=6|OwnerPartId=1|Location.X=1069|Location.Y=237|Justification=6|Color=8388608|FontID=1|Text=+
|RECORD=41|OwnerIndex=3516|IndexInSheet=7|OwnerPartId=-1|Location.X=1069|Location.Y=237|Color=8388608|FontID=1|IsHidden=T|Text=100uF|Name=Capacitance
|RECORD=41|OwnerIndex=3516|IndexInSheet=8|OwnerPartId=-1|Location.X=1069|Location.Y=237|Color=8388608|FontID=1|IsHidden=T|Text=No|Name=Radiation Hardening
|RECORD=41|OwnerIndex=3516|IndexInSheet=9|OwnerPartId=-1|Location.X=1069|Location.Y=237|Color=8388608|FontID=1|IsHidden=T|Text=Yes|Name=RoHS Compliant
|RECORD=41|OwnerIndex=3516|IndexInSheet=10|OwnerPartId=-1|Location.X=1069|Location.Y=237|Color=8388608|FontID=1|IsHidden=T|Text=7.3mm|Name=Length
|RECORD=41|OwnerIndex=3516|IndexInSheet=11|OwnerPartId=-1|Location.X=1069|Location.Y=237|Color=8388608|FontID=1|IsHidden=T|Text=General Purpose|Name=Features
|RECORD=41|OwnerIndex=3516|IndexInSheet=12|OwnerPartId=-1|Location.X=1069|Location.Y=237|Color=8388608|FontID=1|IsHidden=T|Text=Tape and Reel|Name=Packaging
|RECORD=41|OwnerIndex=3516|IndexInSheet=13|OwnerPartId=-1|Location.X=1069|Location.Y=237|Color=8388608|FontID=1|IsHidden=T|Text=1|Name=Package Quantity
|RECORD=41|OwnerIndex=3516|IndexInSheet=14|OwnerPartId=-1|Location.X=1069|Location.Y=237|Color=8388608|FontID=1|IsHidden=T|Text=0.023634oz|Name=Weight
|RECORD=41|OwnerIndex=3516|IndexInSheet=15|OwnerPartId=-1|Location.X=1069|Location.Y=237|Color=8388608|FontID=1|IsHidden=T|Text=2000Hour|Name=Life (Hours)
|RECORD=41|OwnerIndex=3516|IndexInSheet=16|OwnerPartId=-1|Location.X=1069|Location.Y=237|Color=8388608|FontID=1|IsHidden=T|Text=16V|Name=Voltage Rating
|RECORD=41|OwnerIndex=3516|IndexInSheet=17|OwnerPartId=-1|Location.X=1069|Location.Y=237|Color=8388608|FontID=1|IsHidden=T|Text=0.169inch|Name=Width
|RECORD=41|OwnerIndex=3516|IndexInSheet=18|OwnerPartId=-1|Location.X=1069|Location.Y=237|Color=8388608|FontID=1|IsHidden=T|Text=2917|Name=Case/Package
|RECORD=41|OwnerIndex=3516|IndexInSheet=19|OwnerPartId=-1|Location.X=1069|Location.Y=237|Color=8388608|FontID=1|IsHidden=T|Text=125mR|Name=ESR (Equivalent Series Resistance)
|RECORD=41|OwnerIndex=3516|IndexInSheet=20|OwnerPartId=-1|Location.X=1069|Location.Y=237|Color=8388608|FontID=1|IsHidden=T|Text=Surface Mount|Name=Mount
|RECORD=41|OwnerIndex=3516|IndexInSheet=21|OwnerPartId=-1|Location.X=1069|Location.Y=237|Color=8388608|FontID=1|IsHidden=T|Text=16V|Name=Voltage
|RECORD=41|OwnerIndex=3516|IndexInSheet=22|OwnerPartId=-1|Location.X=1069|Location.Y=237|Color=8388608|FontID=1|IsHidden=T|Text=-55°C|Name=Min Operating Temperature
|RECORD=41|OwnerIndex=3516|IndexInSheet=23|OwnerPartId=-1|Location.X=1069|Location.Y=237|Color=8388608|FontID=1|IsHidden=T|Text=10%|Name=Tolerance
|RECORD=41|OwnerIndex=3516|IndexInSheet=24|OwnerPartId=-1|Location.X=1069|Location.Y=237|Color=8388608|FontID=1|IsHidden=T|Text=No SVHC|Name=REACH SVHC
|RECORD=41|OwnerIndex=3516|IndexInSheet=25|OwnerPartId=-1|Location.X=1069|Location.Y=237|Color=8388608|FontID=1|IsHidden=T|Text=0.122inch|Name=Height - Seated (Max)
|RECORD=41|OwnerIndex=3516|IndexInSheet=26|OwnerPartId=-1|Location.X=1069|Location.Y=237|Color=8388608|FontID=1|IsHidden=T|Text=2|Name=Number of Pins
|RECORD=41|OwnerIndex=3516|IndexInSheet=27|OwnerPartId=-1|Location.X=1069|Location.Y=237|Color=8388608|FontID=1|IsHidden=T|Text=Flat|Name=Construction
|RECORD=41|OwnerIndex=3516|IndexInSheet=28|OwnerPartId=-1|Location.X=1069|Location.Y=237|Color=8388608|FontID=1|IsHidden=T|Text=4.3mm|Name=Depth
|RECORD=41|OwnerIndex=3516|IndexInSheet=29|OwnerPartId=-1|Location.X=1069|Location.Y=237|Color=8388608|FontID=1|IsHidden=T|Text=T495|Name=Series
|RECORD=41|OwnerIndex=3516|IndexInSheet=30|OwnerPartId=-1|Location.X=1069|Location.Y=237|Color=8388608|FontID=1|IsHidden=T|Text=125°C|Name=Max Operating Temperature
|RECORD=41|OwnerIndex=3516|IndexInSheet=31|OwnerPartId=-1|Location.X=1069|Location.Y=237|Color=8388608|FontID=1|IsHidden=T|Text=0.001%|Name=Failure Rate
|RECORD=41|OwnerIndex=3516|IndexInSheet=32|OwnerPartId=-1|Location.X=1069|Location.Y=237|Color=8388608|FontID=1|IsHidden=T|Text=SMD/SMT|Name=Termination
|RECORD=41|OwnerIndex=3516|IndexInSheet=33|OwnerPartId=-1|Location.X=1069|Location.Y=237|Color=8388608|FontID=1|IsHidden=T|Text=Polar|Name=Polarity
|RECORD=41|OwnerIndex=3516|IndexInSheet=34|OwnerPartId=-1|Location.X=1069|Location.Y=237|Color=8388608|FontID=1|IsHidden=T|Text=16V|Name=Voltage Rating (DC)
|RECORD=41|OwnerIndex=3516|IndexInSheet=35|OwnerPartId=-1|Location.X=1069|Location.Y=237|Color=8388608|FontID=1|IsHidden=T|Text=Tantalum|Name=Dielectric Material
|RECORD=41|OwnerIndex=3516|IndexInSheet=36|OwnerPartId=-1|Location.X=1069|Location.Y=237|Color=8388608|FontID=1|IsHidden=T|Text=2917|Name=Case Code (Imperial)
|RECORD=41|OwnerIndex=3516|IndexInSheet=37|OwnerPartId=-1|Location.X=1069|Location.Y=237|Color=8388608|FontID=1|IsHidden=T|Text=7343|Name=Case Code (Metric)
|RECORD=41|OwnerIndex=3516|IndexInSheet=38|OwnerPartId=-1|Location.X=1069|Location.Y=237|Color=8388608|FontID=1|IsHidden=T|Text=2.8mm|Name=Height
|RECORD=41|OwnerIndex=3516|IndexInSheet=39|OwnerPartId=-1|Location.X=1069|Location.Y=237|Color=8388608|FontID=1|IsHidden=T|Text=8%|Name=Dissipation Factor
|RECORD=34|OwnerIndex=3516|IndexInSheet=-1|OwnerPartId=-1|Location.X=1065|Location.Y=215|Orientation=1|Color=8388608|FontID=2|Text=C79|Name=Designator|ReadOnlyState=1
|RECORD=41|OwnerIndex=3516|IndexInSheet=-1|OwnerPartId=1|Location.X=1105|Location.Y=195|Orientation=1|Color=8388608|FontID=2|Text=100uF_16V_2917|Name=Comment
|RECORD=44|OwnerIndex=3516
|RECORD=45|OwnerIndex=3561|IndexInSheet=-1|UseComponentLibrary=T|ModelName=FP-T495D107K016ATE125-MFG|ModelType=PCBLIB|DatafileCount=1|ModelDatafileEntity0=FP-T495D107K016ATE125-MFG|ModelDatafileKind0=PCBLib|IsCurrent=T|DatalinksLocked=T|DatabaseDatalinksLocked=T
|RECORD=46|OwnerIndex=3562
|RECORD=48|OwnerIndex=3562
|RECORD=1|LibReference=b4654b650e69147ec39a6b967a45e02|ComponentDescription=Multilayer Ceramic Capacitors 2.2µF ±10% 16V X5R SMD 0402|PartCount=2|DisplayModeCount=1|IndexInSheet=273|OwnerPartId=-1|Location.X=1210|Location.Y=235|CurrentPartId=1|LibraryPath=*|SourceLibraryName=Altium Content Vault|TargetFileName=*|AreaColor=11599871|Color=128|PartIDLocked=T|DesignItemId=CMP-2000-05998-2|AllPinCount=2
|RECORD=2|OwnerIndex=3565|OwnerPartId=1|Electrical=4|PinConglomerate=49|PinLength=7|Location.X=1210|Location.Y=228|Name=1|Designator=1|PinPropagationDelay=0.000000E+000
|RECORD=2|OwnerIndex=3565|OwnerPartId=1|Electrical=4|PinConglomerate=51|PinLength=6|Location.X=1210|Location.Y=221|Name=2|Designator=2|PinPropagationDelay=0.000000E+000
|RECORD=13|OwnerIndex=3565|IsNotAccesible=T|IndexInSheet=2|OwnerPartId=1|Location.X=1220|Location.Y=228|Corner.X=1200|Corner.Y=228|LineWidth=1|Color=16711680
|RECORD=13|OwnerIndex=3565|IsNotAccesible=T|IndexInSheet=3|OwnerPartId=1|Location.X=1220|Location.Y=222|Corner.X=1200|Corner.Y=222|LineWidth=1|Color=16711680
|RECORD=13|OwnerIndex=3565|IsNotAccesible=T|IndexInSheet=4|OwnerPartId=1|Location.X=1210|Location.Y=228|Corner.X=1210|Corner.Y=231|LineWidth=1|Color=16711680
|RECORD=13|OwnerIndex=3565|IsNotAccesible=T|IndexInSheet=5|OwnerPartId=1|Location.X=1210|Location.Y=221|Corner.X=1210|Corner.Y=220|LineWidth=1|Color=16711680
|RECORD=41|OwnerIndex=3565|IndexInSheet=6|OwnerPartId=-1|Location.X=1199|Location.Y=237|Color=8388608|FontID=1|IsHidden=T|Text=No SVHC|Name=REACH SVHC
|RECORD=41|OwnerIndex=3565|IndexInSheet=7|OwnerPartId=-1|Location.X=1199|Location.Y=237|Color=8388608|FontID=1|IsHidden=T|Text=C|Name=Series
|RECORD=41|OwnerIndex=3565|IndexInSheet=8|OwnerPartId=-1|Location.X=1199|Location.Y=237|Color=8388608|FontID=1|IsHidden=T|Text=SMD/SMT|Name=Termination
|RECORD=41|OwnerIndex=3565|IndexInSheet=9|OwnerPartId=-1|Location.X=1199|Location.Y=237|Color=8388608|FontID=1|IsHidden=T|Text=0402|Name=Case Code (Imperial)
|RECORD=41|OwnerIndex=3565|IndexInSheet=10|OwnerPartId=-1|Location.X=1199|Location.Y=237|Color=8388608|FontID=1|IsHidden=T|Text=0.5mm|Name=Depth
|RECORD=41|OwnerIndex=3565|IndexInSheet=11|OwnerPartId=-1|Location.X=1199|Location.Y=237|Color=8388608|FontID=1|IsHidden=T|Text=Surface Mount|Name=Mount
|RECORD=41|OwnerIndex=3565|IndexInSheet=12|OwnerPartId=-1|Location.X=1199|Location.Y=237|Color=8388608|FontID=1|IsHidden=T|Text=0.02inch|Name=Width
|RECORD=41|OwnerIndex=3565|IndexInSheet=13|OwnerPartId=-1|Location.X=1199|Location.Y=237|Color=8388608|FontID=1|IsHidden=T|Text=1|Name=Package Quantity
|RECORD=41|OwnerIndex=3565|IndexInSheet=14|OwnerPartId=-1|Location.X=1199|Location.Y=237|Color=8388608|FontID=1|IsHidden=T|Text=Ceramic|Name=Dielectric Material
|RECORD=41|OwnerIndex=3565|IndexInSheet=15|OwnerPartId=-1|Location.X=1199|Location.Y=237|Color=8388608|FontID=1|IsHidden=T|Text=1mm|Name=Length
|RECORD=41|OwnerIndex=3565|IndexInSheet=16|OwnerPartId=-1|Location.X=1199|Location.Y=237|Color=8388608|FontID=1|IsHidden=T|Text=Tape and Reel|Name=Packaging
|RECORD=41|OwnerIndex=3565|IndexInSheet=17|OwnerPartId=-1|Location.X=1199|Location.Y=237|Color=8388608|FontID=1|IsHidden=T|Text=1005|Name=Case Code (Metric)
|RECORD=41|OwnerIndex=3565|IndexInSheet=18|OwnerPartId=-1|Location.X=1199|Location.Y=237|Color=8388608|FontID=1|IsHidden=T|Text=Yes|Name=RoHS Compliant
|RECORD=41|OwnerIndex=3565|IndexInSheet=19|OwnerPartId=-1|Location.X=1199|Location.Y=237|Color=8388608|FontID=1|IsHidden=T|Text=X5R|Name=Dielectric
|RECORD=41|OwnerIndex=3565|IndexInSheet=20|OwnerPartId=-1|Location.X=1199|Location.Y=237|Color=8388608|FontID=1|IsHidden=T|Text=85°C|Name=Max Operating Temperature
|RECORD=41|OwnerIndex=3565|IndexInSheet=21|OwnerPartId=-1|Location.X=1199|Location.Y=237|Color=8388608|FontID=1|IsHidden=T|Text=Lead Free|Name=Lead Free
|RECORD=41|OwnerIndex=3565|IndexInSheet=22|OwnerPartId=-1|Location.X=1199|Location.Y=237|Color=8388608|FontID=1|IsHidden=T|Text=2.3E-05oz|Name=Weight
|RECORD=41|OwnerIndex=3565|IndexInSheet=23|OwnerPartId=-1|Location.X=1199|Location.Y=237|Color=8388608|FontID=1|IsHidden=T|Text=0.022inch|Name=Thickness
|RECORD=41|OwnerIndex=3565|IndexInSheet=24|OwnerPartId=-1|Location.X=1199|Location.Y=237|Color=8388608|FontID=1|IsHidden=T|Text=2.2uF|Name=Capacitance
|RECORD=41|OwnerIndex=3565|IndexInSheet=25|OwnerPartId=-1|Location.X=1199|Location.Y=237|Color=8388608|FontID=1|IsHidden=T|Text=16V|Name=Voltage Rating (DC)
|RECORD=41|OwnerIndex=3565|IndexInSheet=26|OwnerPartId=-1|Location.X=1199|Location.Y=237|Color=8388608|FontID=1|IsHidden=T|Text=10%|Name=Tolerance
|RECORD=41|OwnerIndex=3565|IndexInSheet=27|OwnerPartId=-1|Location.X=1199|Location.Y=237|Color=8388608|FontID=1|IsHidden=T|Text=16V|Name=Voltage Rating
|RECORD=41|OwnerIndex=3565|IndexInSheet=28|OwnerPartId=-1|Location.X=1199|Location.Y=237|Color=8388608|FontID=1|IsHidden=T|Text=Ceramic|Name=Resistor Type
|RECORD=41|OwnerIndex=3565|IndexInSheet=29|OwnerPartId=-1|Location.X=1199|Location.Y=237|Color=8388608|FontID=1|IsHidden=T|Text=0.5mm|Name=Height
|RECORD=41|OwnerIndex=3565|IndexInSheet=30|OwnerPartId=-1|Location.X=1199|Location.Y=237|Color=8388608|FontID=1|IsHidden=T|Text=0402|Name=Case/Package
|RECORD=41|OwnerIndex=3565|IndexInSheet=31|OwnerPartId=-1|Location.X=1199|Location.Y=237|Color=8388608|FontID=1|IsHidden=T|Text=-55°C|Name=Min Operating Temperature
|RECORD=34|OwnerIndex=3565|IndexInSheet=-1|OwnerPartId=-1|Location.X=1200|Location.Y=215|Orientation=1|Color=8388608|FontID=2|Text=C81|Name=Designator|ReadOnlyState=1
|RECORD=41|OwnerIndex=3565|IndexInSheet=-1|OwnerPartId=1|Location.X=1230|Location.Y=190|Orientation=1|Color=8388608|FontID=2|Text=2.2uF_16V_0402|Name=Comment
|RECORD=44|OwnerIndex=3565
|RECORD=45|OwnerIndex=3602|IndexInSheet=-1|UseComponentLibrary=T|ModelName=FP-C1005-050-0_05-IPC_A|ModelType=PCBLIB|DatafileCount=1|ModelDatafileEntity0=FP-C1005-050-0_05-IPC_A|ModelDatafileKind0=PCBLib|IsCurrent=T|DatalinksLocked=T|DatabaseDatalinksLocked=T
|RECORD=46|OwnerIndex=3603
|RECORD=48|OwnerIndex=3603
|RECORD=45|OwnerIndex=3602|IndexInSheet=-1|UseComponentLibrary=T|ModelName=FP-C1005-050-0_05-MFG|ModelType=PCBLIB|DatafileCount=1|ModelDatafileEntity0=FP-C1005-050-0_05-MFG|ModelDatafileKind0=PCBLib|DatalinksLocked=T|DatabaseDatalinksLocked=T
|RECORD=46|OwnerIndex=3606
|RECORD=48|OwnerIndex=3606
|RECORD=45|OwnerIndex=3602|IndexInSheet=-1|UseComponentLibrary=T|ModelName=FP-C1005-050-0_05-IPC_C|ModelType=PCBLIB|DatafileCount=1|ModelDatafileEntity0=FP-C1005-050-0_05-IPC_C|ModelDatafileKind0=PCBLib|DatalinksLocked=T|DatabaseDatalinksLocked=T
|RECORD=46|OwnerIndex=3609
|RECORD=48|OwnerIndex=3609
|RECORD=45|OwnerIndex=3602|IndexInSheet=-1|UseComponentLibrary=T|ModelName=FP-C1005-050-0_05-IPC_B|ModelType=PCBLIB|DatafileCount=1|ModelDatafileEntity0=FP-C1005-050-0_05-IPC_B|ModelDatafileKind0=PCBLib|DatalinksLocked=T|DatabaseDatalinksLocked=T
|RECORD=46|OwnerIndex=3612
|RECORD=48|OwnerIndex=3612
|RECORD=1|LibReference=b4654b650e69147ec39a6b967a45e02|ComponentDescription=None|PartCount=2|DisplayModeCount=1|IndexInSheet=274|OwnerPartId=-1|Location.X=1255|Location.Y=235|CurrentPartId=1|LibraryPath=*|SourceLibraryName=Altium Content Vault|TargetFileName=*|AreaColor=11599871|Color=128|PartIDLocked=T|DesignItemId=CMP-14477-000104-2|AllPinCount=2
|RECORD=2|OwnerIndex=3615|OwnerPartId=1|Electrical=4|PinConglomerate=49|PinLength=7|Location.X=1255|Location.Y=228|Name=1|Designator=1|PinPropagationDelay=0.000000E+000
|RECORD=2|OwnerIndex=3615|OwnerPartId=1|Electrical=4|PinConglomerate=51|PinLength=6|Location.X=1255|Location.Y=221|Name=2|Designator=2|PinPropagationDelay=0.000000E+000
|RECORD=13|OwnerIndex=3615|IsNotAccesible=T|IndexInSheet=2|OwnerPartId=1|Location.X=1265|Location.Y=228|Corner.X=1245|Corner.Y=228|LineWidth=1|Color=16711680
|RECORD=13|OwnerIndex=3615|IsNotAccesible=T|IndexInSheet=3|OwnerPartId=1|Location.X=1265|Location.Y=222|Corner.X=1245|Corner.Y=222|LineWidth=1|Color=16711680
|RECORD=13|OwnerIndex=3615|IsNotAccesible=T|IndexInSheet=4|OwnerPartId=1|Location.X=1255|Location.Y=228|Corner.X=1255|Corner.Y=231|LineWidth=1|Color=16711680
|RECORD=13|OwnerIndex=3615|IsNotAccesible=T|IndexInSheet=5|OwnerPartId=1|Location.X=1255|Location.Y=221|Corner.X=1255|Corner.Y=220|LineWidth=1|Color=16711680
|RECORD=41|OwnerIndex=3615|IndexInSheet=6|OwnerPartId=-1|Location.X=1244|Location.Y=237|Color=8388608|FontID=1|IsHidden=T|Text=Tape and Reel|Name=Packaging
|RECORD=41|OwnerIndex=3615|IndexInSheet=7|OwnerPartId=-1|Location.X=1244|Location.Y=237|Color=8388608|FontID=1|IsHidden=T|Text=0.5mm|Name=Depth
|RECORD=41|OwnerIndex=3615|IndexInSheet=8|OwnerPartId=-1|Location.X=1244|Location.Y=237|Color=8388608|FontID=1|IsHidden=T|Text=10%|Name=Tolerance
|RECORD=41|OwnerIndex=3615|IndexInSheet=9|OwnerPartId=-1|Location.X=1244|Location.Y=237|Color=8388608|FontID=1|IsHidden=T|Text=Surface Mount|Name=Mount
|RECORD=41|OwnerIndex=3615|IndexInSheet=10|OwnerPartId=-1|Location.X=1244|Location.Y=237|Color=8388608|FontID=1|IsHidden=T|Text=16V|Name=Voltage Rating
|RECORD=41|OwnerIndex=3615|IndexInSheet=11|OwnerPartId=-1|Location.X=1244|Location.Y=237|Color=8388608|FontID=1|IsHidden=T|Text=0.022inch|Name=Thickness
|RECORD=41|OwnerIndex=3615|IndexInSheet=12|OwnerPartId=-1|Location.X=1244|Location.Y=237|Color=8388608|FontID=1|IsHidden=T|Text=1|Name=Package Quantity
|RECORD=41|OwnerIndex=3615|IndexInSheet=13|OwnerPartId=-1|Location.X=1244|Location.Y=237|Color=8388608|FontID=1|IsHidden=T|Text=-55°C|Name=Min Operating Temperature
|RECORD=41|OwnerIndex=3615|IndexInSheet=14|OwnerPartId=-1|Location.X=1244|Location.Y=237|Color=8388608|FontID=1|IsHidden=T|Text=M|Name=Series
|RECORD=41|OwnerIndex=3615|IndexInSheet=15|OwnerPartId=-1|Location.X=1244|Location.Y=237|Color=8388608|FontID=1|IsHidden=T|Text=16V|Name=Voltage Rating (DC)
|RECORD=41|OwnerIndex=3615|IndexInSheet=16|OwnerPartId=-1|Location.X=1244|Location.Y=237|Color=8388608|FontID=1|IsHidden=T|Text=SMD/SMT|Name=Termination
|RECORD=41|OwnerIndex=3615|IndexInSheet=17|OwnerPartId=-1|Location.X=1244|Location.Y=237|Color=8388608|FontID=1|IsHidden=T|Text=0402|Name=Case/Package
|RECORD=41|OwnerIndex=3615|IndexInSheet=18|OwnerPartId=-1|Location.X=1244|Location.Y=237|Color=8388608|FontID=1|IsHidden=T|Text=X5R|Name=Dielectric
|RECORD=41|OwnerIndex=3615|IndexInSheet=19|OwnerPartId=-1|Location.X=1244|Location.Y=237|Color=8388608|FontID=1|IsHidden=T|Text=2|Name=Number of Pins
|RECORD=41|OwnerIndex=3615|IndexInSheet=20|OwnerPartId=-1|Location.X=1244|Location.Y=237|Color=8388608|FontID=1|IsHidden=T|Text=0402|Name=Case Code (Imperial)
|RECORD=41|OwnerIndex=3615|IndexInSheet=21|OwnerPartId=-1|Location.X=1244|Location.Y=237|Color=8388608|FontID=1|IsHidden=T|Text=1uF|Name=Capacitance
|RECORD=41|OwnerIndex=3615|IndexInSheet=22|OwnerPartId=-1|Location.X=1244|Location.Y=237|Color=8388608|FontID=1|IsHidden=T|Text=1mm|Name=Length
|RECORD=41|OwnerIndex=3615|IndexInSheet=23|OwnerPartId=-1|Location.X=1244|Location.Y=237|Color=8388608|FontID=1|IsHidden=T|Text=Halogen Free|Name=Halogen Free
|RECORD=41|OwnerIndex=3615|IndexInSheet=24|OwnerPartId=-1|Location.X=1244|Location.Y=237|Color=8388608|FontID=1|IsHidden=T|Text=1005|Name=Case Code (Metric)
|RECORD=41|OwnerIndex=3615|IndexInSheet=25|OwnerPartId=-1|Location.X=1244|Location.Y=237|Color=8388608|FontID=1|IsHidden=T|Text=0.02inch|Name=Width
|RECORD=41|OwnerIndex=3615|IndexInSheet=26|OwnerPartId=-1|Location.X=1244|Location.Y=237|Color=8388608|FontID=1|IsHidden=T|Text=Yes|Name=RoHS Compliant
|RECORD=41|OwnerIndex=3615|IndexInSheet=27|OwnerPartId=-1|Location.X=1244|Location.Y=237|Color=8388608|FontID=1|IsHidden=T|Text=No|Name=Radiation Hardening
|RECORD=41|OwnerIndex=3615|IndexInSheet=28|OwnerPartId=-1|Location.X=1244|Location.Y=237|Color=8388608|FontID=1|IsHidden=T|Text=85°C|Name=Max Operating Temperature
|RECORD=41|OwnerIndex=3615|IndexInSheet=29|OwnerPartId=-1|Location.X=1244|Location.Y=237|Color=8388608|FontID=1|IsHidden=T|Text=0.5mm|Name=Height
|RECORD=41|OwnerIndex=3615|IndexInSheet=30|OwnerPartId=-1|Location.X=1244|Location.Y=237|Color=8388608|FontID=1|IsHidden=T|Text=Flat|Name=Construction
|RECORD=34|OwnerIndex=3615|IndexInSheet=-1|OwnerPartId=-1|Location.X=1240|Location.Y=215|Orientation=1|Color=8388608|FontID=2|Text=C82|Name=Designator|ReadOnlyState=1
|RECORD=41|OwnerIndex=3615|IndexInSheet=-1|OwnerPartId=1|Location.X=1275|Location.Y=200|Orientation=1|Color=8388608|FontID=2|Text=1uF_16V_0402|Name=Comment
|RECORD=44|OwnerIndex=3615
|RECORD=45|OwnerIndex=3651|IndexInSheet=-1|UseComponentLibrary=T|ModelName=FP-0402-L_1_0_0_05-W_0_5-IPC_A|ModelType=PCBLIB|DatafileCount=1|ModelDatafileEntity0=FP-0402-L_1_0_0_05-W_0_5-IPC_A|ModelDatafileKind0=PCBLib|IsCurrent=T|DatalinksLocked=T|DatabaseDatalinksLocked=T
|RECORD=46|OwnerIndex=3652
|RECORD=48|OwnerIndex=3652
|RECORD=45|OwnerIndex=3651|IndexInSheet=-1|UseComponentLibrary=T|ModelName=EMK105BJ105_V-F|ModelType=SIM|IsCurrent=T|DatalinksLocked=T|DatabaseDatalinksLocked=T
|RECORD=46|OwnerIndex=3655
|RECORD=48|OwnerIndex=3655
|RECORD=41|OwnerIndex=3657|IndexInSheet=-1|OwnerPartId=-1|Color=8388608|FontID=1|IsHidden=T|Text=General|Name=Kind
|RECORD=41|OwnerIndex=3657|IndexInSheet=-1|OwnerPartId=-1|Color=8388608|FontID=1|IsHidden=T|Text=Spice Subcircuit|Name=SubKind
|RECORD=41|OwnerIndex=3657|IndexInSheet=-1|OwnerPartId=-1|Color=8388608|FontID=1|IsHidden=T|Name=Spice Prefix
|RECORD=41|OwnerIndex=3657|IndexInSheet=-1|OwnerPartId=-1|Color=8388608|FontID=1|IsHidden=T|Name=Excluded Parts
|RECORD=41|OwnerIndex=3657|IndexInSheet=-1|OwnerPartId=-1|Color=8388608|FontID=1|IsHidden=T|Name=Netlist
|RECORD=41|OwnerIndex=3657|IndexInSheet=-1|OwnerPartId=-1|Color=8388608|FontID=1|IsHidden=T|Text=document_sim_cache\GNEMVTBT\0|Name=SimulationCacheLocation|ReadOnlyState=3
|RECORD=45|OwnerIndex=3651|IndexInSheet=-1|UseComponentLibrary=T|ModelName=FP-0402-L_1_0_0_05-W_0_5-IPC_B|ModelType=PCBLIB|DatafileCount=1|ModelDatafileEntity0=FP-0402-L_1_0_0_05-W_0_5-IPC_B|ModelDatafileKind0=PCBLib|DatalinksLocked=T|DatabaseDatalinksLocked=T
|RECORD=46|OwnerIndex=3664
|RECORD=48|OwnerIndex=3664
|RECORD=45|OwnerIndex=3651|IndexInSheet=-1|UseComponentLibrary=T|ModelName=FP-0402-L_1_0_0_05-W_0_5-IPC_C|ModelType=PCBLIB|DatafileCount=1|ModelDatafileEntity0=FP-0402-L_1_0_0_05-W_0_5-IPC_C|ModelDatafileKind0=PCBLib|DatalinksLocked=T|DatabaseDatalinksLocked=T
|RECORD=46|OwnerIndex=3667
|RECORD=48|OwnerIndex=3667
|RECORD=45|OwnerIndex=3651|IndexInSheet=-1|UseComponentLibrary=T|ModelName=FP-0402-L_1_0_0_05-W_0_5-MFG|ModelType=PCBLIB|DatafileCount=1|ModelDatafileEntity0=FP-0402-L_1_0_0_05-W_0_5-MFG|ModelDatafileKind0=PCBLib|DatalinksLocked=T|DatabaseDatalinksLocked=T
|RECORD=46|OwnerIndex=3670
|RECORD=48|OwnerIndex=3670
|RECORD=1|LibReference=b4654b650e69147ec39a6b967a45e02|ComponentDescription=General Purpose Ceramic Capacitor, 0402, 100nF, 10%, X7R, 15%, 25V|PartCount=2|DisplayModeCount=1|IndexInSheet=275|OwnerPartId=-1|Location.X=1295|Location.Y=235|CurrentPartId=1|LibraryPath=*|SourceLibraryName=Altium Content Vault|TargetFileName=*|AreaColor=11599871|Color=128|PartIDLocked=T|DesignItemId=CMP-2008-02519-2|AllPinCount=2
|RECORD=2|OwnerIndex=3673|OwnerPartId=1|Electrical=4|PinConglomerate=49|PinLength=7|Location.X=1295|Location.Y=228|Name=1|Designator=1|PinPropagationDelay=0.000000E+000
|RECORD=2|OwnerIndex=3673|OwnerPartId=1|Electrical=4|PinConglomerate=51|PinLength=6|Location.X=1295|Location.Y=221|Name=2|Designator=2|PinPropagationDelay=0.000000E+000
|RECORD=13|OwnerIndex=3673|IsNotAccesible=T|IndexInSheet=2|OwnerPartId=1|Location.X=1305|Location.Y=228|Corner.X=1285|Corner.Y=228|LineWidth=1|Color=16711680
|RECORD=13|OwnerIndex=3673|IsNotAccesible=T|IndexInSheet=3|OwnerPartId=1|Location.X=1305|Location.Y=222|Corner.X=1285|Corner.Y=222|LineWidth=1|Color=16711680
|RECORD=13|OwnerIndex=3673|IsNotAccesible=T|IndexInSheet=4|OwnerPartId=1|Location.X=1295|Location.Y=228|Corner.X=1295|Corner.Y=231|LineWidth=1|Color=16711680
|RECORD=13|OwnerIndex=3673|IsNotAccesible=T|IndexInSheet=5|OwnerPartId=1|Location.X=1295|Location.Y=221|Corner.X=1295|Corner.Y=220|LineWidth=1|Color=16711680
|RECORD=41|OwnerIndex=3673|IndexInSheet=6|OwnerPartId=-1|Location.X=1284|Location.Y=237|Color=8388608|FontID=1|IsHidden=T|Text=1|Name=Package Quantity
|RECORD=41|OwnerIndex=3673|IndexInSheet=7|OwnerPartId=-1|Location.X=1284|Location.Y=237|Color=8388608|FontID=1|IsHidden=T|Text=100nF|Name=Capacitance
|RECORD=41|OwnerIndex=3673|IndexInSheet=8|OwnerPartId=-1|Location.X=1284|Location.Y=237|Color=8388608|FontID=1|IsHidden=T|Text=-55°C|Name=Min Operating Temperature
|RECORD=41|OwnerIndex=3673|IndexInSheet=9|OwnerPartId=-1|Location.X=1284|Location.Y=237|Color=8388608|FontID=1|IsHidden=T|Text=25V|Name=Voltage
|RECORD=41|OwnerIndex=3673|IndexInSheet=10|OwnerPartId=-1|Location.X=1284|Location.Y=237|Color=8388608|FontID=1|IsHidden=T|Text=25V|Name=Voltage Rating
|RECORD=41|OwnerIndex=3673|IndexInSheet=11|OwnerPartId=-1|Location.X=1284|Location.Y=237|Color=8388608|FontID=1|IsHidden=T|Text=Flat|Name=Construction
|RECORD=41|OwnerIndex=3673|IndexInSheet=12|OwnerPartId=-1|Location.X=1284|Location.Y=237|Color=8388608|FontID=1|IsHidden=T|Text=125°C|Name=Max Operating Temperature
|RECORD=41|OwnerIndex=3673|IndexInSheet=13|OwnerPartId=-1|Location.X=1284|Location.Y=237|Color=8388608|FontID=1|IsHidden=T|Text=No|Name=Radiation Hardening
|RECORD=41|OwnerIndex=3673|IndexInSheet=14|OwnerPartId=-1|Location.X=1284|Location.Y=237|Color=8388608|FontID=1|IsHidden=T|Text=0.5mm|Name=Depth
|RECORD=41|OwnerIndex=3673|IndexInSheet=15|OwnerPartId=-1|Location.X=1284|Location.Y=237|Color=8388608|FontID=1|IsHidden=T|Text=0.022inch|Name=Thickness
|RECORD=41|OwnerIndex=3673|IndexInSheet=16|OwnerPartId=-1|Location.X=1284|Location.Y=237|Color=8388608|FontID=1|IsHidden=T|Text=25V|Name=Voltage Rating (DC)
|RECORD=41|OwnerIndex=3673|IndexInSheet=17|OwnerPartId=-1|Location.X=1284|Location.Y=237|Color=8388608|FontID=1|IsHidden=T|Text=2|Name=Number of Pins
|RECORD=41|OwnerIndex=3673|IndexInSheet=18|OwnerPartId=-1|Location.X=1284|Location.Y=237|Color=8388608|FontID=1|IsHidden=T|Text=Lead Free|Name=Lead Free
|RECORD=41|OwnerIndex=3673|IndexInSheet=19|OwnerPartId=-1|Location.X=1284|Location.Y=237|Color=8388608|FontID=1|IsHidden=T|Text=-|Name=Series
|RECORD=41|OwnerIndex=3673|IndexInSheet=20|OwnerPartId=-1|Location.X=1284|Location.Y=237|Color=8388608|FontID=1|IsHidden=T|Text=No SVHC|Name=REACH SVHC
|RECORD=41|OwnerIndex=3673|IndexInSheet=21|OwnerPartId=-1|Location.X=1284|Location.Y=237|Color=8388608|FontID=1|IsHidden=T|Text=1mm|Name=Length
|RECORD=41|OwnerIndex=3673|IndexInSheet=22|OwnerPartId=-1|Location.X=1284|Location.Y=237|Color=8388608|FontID=1|IsHidden=T|Text=X7R|Name=Dielectric
|RECORD=41|OwnerIndex=3673|IndexInSheet=23|OwnerPartId=-1|Location.X=1284|Location.Y=237|Color=8388608|FontID=1|IsHidden=T|Text=Yes|Name=RoHS Compliant
|RECORD=41|OwnerIndex=3673|IndexInSheet=24|OwnerPartId=-1|Location.X=1284|Location.Y=237|Color=8388608|FontID=1|IsHidden=T|Text=Surface Mount|Name=Mount
|RECORD=41|OwnerIndex=3673|IndexInSheet=25|OwnerPartId=-1|Location.X=1284|Location.Y=237|Color=8388608|FontID=1|IsHidden=T|Text=Tape and Reel|Name=Packaging
|RECORD=41|OwnerIndex=3673|IndexInSheet=26|OwnerPartId=-1|Location.X=1284|Location.Y=237|Color=8388608|FontID=1|IsHidden=T|Text=0402|Name=Case/Package
|RECORD=41|OwnerIndex=3673|IndexInSheet=27|OwnerPartId=-1|Location.X=1284|Location.Y=237|Color=8388608|FontID=1|IsHidden=T|Text=0402|Name=Case Code (Imperial)
|RECORD=41|OwnerIndex=3673|IndexInSheet=28|OwnerPartId=-1|Location.X=1284|Location.Y=237|Color=8388608|FontID=1|IsHidden=T|Text=SMD/SMT|Name=Termination
|RECORD=41|OwnerIndex=3673|IndexInSheet=29|OwnerPartId=-1|Location.X=1284|Location.Y=237|Color=8388608|FontID=1|IsHidden=T|Text=0.02inch|Name=Width
|RECORD=41|OwnerIndex=3673|IndexInSheet=30|OwnerPartId=-1|Location.X=1284|Location.Y=237|Color=8388608|FontID=1|IsHidden=T|Text=1005|Name=Case Code (Metric)
|RECORD=41|OwnerIndex=3673|IndexInSheet=31|OwnerPartId=-1|Location.X=1284|Location.Y=237|Color=8388608|FontID=1|IsHidden=T|Text=10%|Name=Tolerance
|RECORD=34|OwnerIndex=3673|IndexInSheet=-1|OwnerPartId=-1|Location.X=1285|Location.Y=215|Orientation=1|Color=8388608|FontID=2|Text=C83|Name=Designator|ReadOnlyState=1
|RECORD=41|OwnerIndex=3673|IndexInSheet=-1|OwnerPartId=1|Location.X=1315|Location.Y=200|Orientation=1|Color=8388608|FontID=2|Text=0.1uF_25V_0402|Name=Comment
|RECORD=44|OwnerIndex=3673
|RECORD=45|OwnerIndex=3710|IndexInSheet=-1|UseComponentLibrary=T|ModelName=FP-0402-L_1_0_1-W_0_5_0_1-IPC_C|ModelType=PCBLIB|DatafileCount=1|ModelDatafileEntity0=FP-0402-L_1_0_1-W_0_5_0_1-IPC_C|ModelDatafileKind0=PCBLib|IsCurrent=T|DatalinksLocked=T|DatabaseDatalinksLocked=T
|RECORD=46|OwnerIndex=3711
|RECORD=48|OwnerIndex=3711
|RECORD=45|OwnerIndex=3710|IndexInSheet=-1|UseComponentLibrary=T|ModelName=FP-0402-L_1_0_1-W_0_5_0_1-IPC_B|ModelType=PCBLIB|DatafileCount=1|ModelDatafileEntity0=FP-0402-L_1_0_1-W_0_5_0_1-IPC_B|ModelDatafileKind0=PCBLib|DatalinksLocked=T|DatabaseDatalinksLocked=T
|RECORD=46|OwnerIndex=3714
|RECORD=48|OwnerIndex=3714
|RECORD=45|OwnerIndex=3710|IndexInSheet=-1|UseComponentLibrary=T|ModelName=FP-0402-L_1_0_1-W_0_5_0_1-MFG|ModelType=PCBLIB|DatafileCount=1|ModelDatafileEntity0=FP-0402-L_1_0_1-W_0_5_0_1-MFG|ModelDatafileKind0=PCBLib|DatalinksLocked=T|DatabaseDatalinksLocked=T
|RECORD=46|OwnerIndex=3717
|RECORD=48|OwnerIndex=3717
|RECORD=45|OwnerIndex=3710|IndexInSheet=-1|UseComponentLibrary=T|ModelName=FP-0402-L_1_0_1-W_0_5_0_1-IPC_A|ModelType=PCBLIB|DatafileCount=1|ModelDatafileEntity0=FP-0402-L_1_0_1-W_0_5_0_1-IPC_A|ModelDatafileKind0=PCBLib|DatalinksLocked=T|DatabaseDatalinksLocked=T
|RECORD=46|OwnerIndex=3720
|RECORD=48|OwnerIndex=3720
|RECORD=1|LibReference=11868f565c42a9108669ba33697ecf6|ComponentDescription=Multilayer Ceramic Capacitors 47uF ±20% 16V X5R SMD 1206|PartCount=2|DisplayModeCount=1|IndexInSheet=276|OwnerPartId=-1|Location.X=1125|Location.Y=235|CurrentPartId=1|LibraryPath=*|SourceLibraryName=Altium Content Vault|TargetFileName=*|AreaColor=11599871|Color=128|PartIDLocked=T|DesignItemId=CMP-2000-07442-2|AllPinCount=2
|RECORD=2|OwnerIndex=3723|OwnerPartId=1|Electrical=4|PinConglomerate=49|PinLength=7|Location.X=1125|Location.Y=228|Name=1|Designator=1|PinPropagationDelay=0.000000E+000
|RECORD=2|OwnerIndex=3723|OwnerPartId=1|Electrical=4|PinConglomerate=51|PinLength=6|Location.X=1125|Location.Y=221|Name=2|Designator=2|PinPropagationDelay=0.000000E+000
|RECORD=13|OwnerIndex=3723|IsNotAccesible=T|IndexInSheet=2|OwnerPartId=1|Location.X=1135|Location.Y=228|Corner.X=1115|Corner.Y=228|LineWidth=1|Color=16711680
|RECORD=13|OwnerIndex=3723|IsNotAccesible=T|IndexInSheet=3|OwnerPartId=1|Location.X=1135|Location.Y=222|Corner.X=1115|Corner.Y=222|LineWidth=1|Color=16711680
|RECORD=13|OwnerIndex=3723|IsNotAccesible=T|IndexInSheet=4|OwnerPartId=1|Location.X=1125|Location.Y=228|Corner.X=1125|Corner.Y=231|LineWidth=1|Color=16711680
|RECORD=13|OwnerIndex=3723|IsNotAccesible=T|IndexInSheet=5|OwnerPartId=1|Location.X=1125|Location.Y=221|Corner.X=1125|Corner.Y=220|LineWidth=1|Color=16711680
|RECORD=41|OwnerIndex=3723|IndexInSheet=6|OwnerPartId=-1|Location.X=1114|Location.Y=237|Color=8388608|FontID=1|IsHidden=T|Text=Ceramic|Name=Resistor Type
|RECORD=41|OwnerIndex=3723|IndexInSheet=7|OwnerPartId=-1|Location.X=1114|Location.Y=237|Color=8388608|FontID=1|IsHidden=T|Text=0.063inch|Name=Width
|RECORD=41|OwnerIndex=3723|IndexInSheet=8|OwnerPartId=-1|Location.X=1114|Location.Y=237|Color=8388608|FontID=1|IsHidden=T|Text=1206|Name=Case Code (Imperial)
|RECORD=41|OwnerIndex=3723|IndexInSheet=9|OwnerPartId=-1|Location.X=1114|Location.Y=237|Color=8388608|FontID=1|IsHidden=T|Text=No|Name=Radiation Hardening
|RECORD=41|OwnerIndex=3723|IndexInSheet=10|OwnerPartId=-1|Location.X=1114|Location.Y=237|Color=8388608|FontID=1|IsHidden=T|Text=0.071inch|Name=Thickness
|RECORD=41|OwnerIndex=3723|IndexInSheet=11|OwnerPartId=-1|Location.X=1114|Location.Y=237|Color=8388608|FontID=1|IsHidden=T|Text=X5R|Name=Dielectric
|RECORD=41|OwnerIndex=3723|IndexInSheet=12|OwnerPartId=-1|Location.X=1114|Location.Y=237|Color=8388608|FontID=1|IsHidden=T|Text=0.000571oz|Name=Weight
|RECORD=41|OwnerIndex=3723|IndexInSheet=13|OwnerPartId=-1|Location.X=1114|Location.Y=237|Color=8388608|FontID=1|IsHidden=T|Text=SMD/SMT|Name=Termination
|RECORD=41|OwnerIndex=3723|IndexInSheet=14|OwnerPartId=-1|Location.X=1114|Location.Y=237|Color=8388608|FontID=1|IsHidden=T|Text=Ceramic|Name=Dielectric Material
|RECORD=41|OwnerIndex=3723|IndexInSheet=15|OwnerPartId=-1|Location.X=1114|Location.Y=237|Color=8388608|FontID=1|IsHidden=T|Text=-55°C|Name=Min Operating Temperature
|RECORD=41|OwnerIndex=3723|IndexInSheet=16|OwnerPartId=-1|Location.X=1114|Location.Y=237|Color=8388608|FontID=1|IsHidden=T|Text=1.6mm|Name=Depth
|RECORD=41|OwnerIndex=3723|IndexInSheet=17|OwnerPartId=-1|Location.X=1114|Location.Y=237|Color=8388608|FontID=1|IsHidden=T|Text=3216|Name=Case Code (Metric)
|RECORD=41|OwnerIndex=3723|IndexInSheet=18|OwnerPartId=-1|Location.X=1114|Location.Y=237|Color=8388608|FontID=1|IsHidden=T|Text=85°C|Name=Max Operating Temperature
|RECORD=41|OwnerIndex=3723|IndexInSheet=19|OwnerPartId=-1|Location.X=1114|Location.Y=237|Color=8388608|FontID=1|IsHidden=T|Text=Yes|Name=RoHS Compliant
|RECORD=41|OwnerIndex=3723|IndexInSheet=20|OwnerPartId=-1|Location.X=1114|Location.Y=237|Color=8388608|FontID=1|IsHidden=T|Text=No SVHC|Name=REACH SVHC
|RECORD=41|OwnerIndex=3723|IndexInSheet=21|OwnerPartId=-1|Location.X=1114|Location.Y=237|Color=8388608|FontID=1|IsHidden=T|Text=Surface Mount|Name=Mount
|RECORD=41|OwnerIndex=3723|IndexInSheet=22|OwnerPartId=-1|Location.X=1114|Location.Y=237|Color=8388608|FontID=1|IsHidden=T|Text=Lead Free|Name=Lead Free
|RECORD=41|OwnerIndex=3723|IndexInSheet=23|OwnerPartId=-1|Location.X=1114|Location.Y=237|Color=8388608|FontID=1|IsHidden=T|Text=1.6mm|Name=Height
|RECORD=41|OwnerIndex=3723|IndexInSheet=24|OwnerPartId=-1|Location.X=1114|Location.Y=237|Color=8388608|FontID=1|IsHidden=T|Text=3.2mm|Name=Length
|RECORD=41|OwnerIndex=3723|IndexInSheet=25|OwnerPartId=-1|Location.X=1114|Location.Y=237|Color=8388608|FontID=1|IsHidden=T|Text=20%|Name=Tolerance
|RECORD=41|OwnerIndex=3723|IndexInSheet=26|OwnerPartId=-1|Location.X=1114|Location.Y=237|Color=8388608|FontID=1|IsHidden=T|Text=16V|Name=Voltage Rating (DC)
|RECORD=41|OwnerIndex=3723|IndexInSheet=27|OwnerPartId=-1|Location.X=1114|Location.Y=237|Color=8388608|FontID=1|IsHidden=T|Text=47uF|Name=Capacitance
|RECORD=41|OwnerIndex=3723|IndexInSheet=28|OwnerPartId=-1|Location.X=1114|Location.Y=237|Color=8388608|FontID=1|IsHidden=T|Text=1|Name=Package Quantity
|RECORD=41|OwnerIndex=3723|IndexInSheet=29|OwnerPartId=-1|Location.X=1114|Location.Y=237|Color=8388608|FontID=1|IsHidden=T|Text=Flat|Name=Construction
|RECORD=41|OwnerIndex=3723|IndexInSheet=30|OwnerPartId=-1|Location.X=1114|Location.Y=237|Color=8388608|FontID=1|IsHidden=T|Text=Tape and Reel|Name=Packaging
|RECORD=41|OwnerIndex=3723|IndexInSheet=31|OwnerPartId=-1|Location.X=1114|Location.Y=237|Color=8388608|FontID=1|IsHidden=T|Text=C|Name=Series
|RECORD=41|OwnerIndex=3723|IndexInSheet=32|OwnerPartId=-1|Location.X=1114|Location.Y=237|Color=8388608|FontID=1|IsHidden=T|Text=1206|Name=Case/Package
|RECORD=41|OwnerIndex=3723|IndexInSheet=33|OwnerPartId=-1|Location.X=1114|Location.Y=237|Color=8388608|FontID=1|IsHidden=T|Text=16V|Name=Voltage Rating
|RECORD=34|OwnerIndex=3723|IndexInSheet=-1|OwnerPartId=-1|Location.X=1115|Location.Y=220|Orientation=1|Color=8388608|FontID=2|Text=C78|Name=Designator|ReadOnlyState=1
|RECORD=41|OwnerIndex=3723|IndexInSheet=-1|OwnerPartId=1|Location.X=1145|Location.Y=195|Orientation=1|Color=8388608|FontID=2|Text=47uF_16V_1206|Name=Comment
|RECORD=44|OwnerIndex=3723
|RECORD=45|OwnerIndex=3762|IndexInSheet=-1|UseComponentLibrary=T|ModelName=FP-C3216-160-0_2-MFG|ModelType=PCBLIB|DatafileCount=1|ModelDatafileEntity0=FP-C3216-160-0_2-MFG|ModelDatafileKind0=PCBLib|IsCurrent=T|DatalinksLocked=T|DatabaseDatalinksLocked=T
|RECORD=46|OwnerIndex=3763
|RECORD=48|OwnerIndex=3763
|RECORD=45|OwnerIndex=3762|IndexInSheet=-1|UseComponentLibrary=T|ModelName=FP-C3216-160-0_2-IPC_B|ModelType=PCBLIB|DatafileCount=1|ModelDatafileEntity0=FP-C3216-160-0_2-IPC_B|ModelDatafileKind0=PCBLib|DatalinksLocked=T|DatabaseDatalinksLocked=T
|RECORD=46|OwnerIndex=3766
|RECORD=48|OwnerIndex=3766
|RECORD=45|OwnerIndex=3762|IndexInSheet=-1|UseComponentLibrary=T|ModelName=FP-C3216-160-0_2-IPC_C|ModelType=PCBLIB|DatafileCount=1|ModelDatafileEntity0=FP-C3216-160-0_2-IPC_C|ModelDatafileKind0=PCBLib|DatalinksLocked=T|DatabaseDatalinksLocked=T
|RECORD=46|OwnerIndex=3769
|RECORD=48|OwnerIndex=3769
|RECORD=45|OwnerIndex=3762|IndexInSheet=-1|UseComponentLibrary=T|ModelName=FP-C3216-160-0_2-IPC_A|ModelType=PCBLIB|DatafileCount=1|ModelDatafileEntity0=FP-C3216-160-0_2-IPC_A|ModelDatafileKind0=PCBLib|DatalinksLocked=T|DatabaseDatalinksLocked=T
|RECORD=46|OwnerIndex=3772
|RECORD=48|OwnerIndex=3772
|RECORD=17|IndexInSheet=277|OwnerPartId=-1|Style=4|ShowNetName=T|Location.X=1080|Location.Y=175|Orientation=3|Color=128|FontID=1|Text=GND
|RECORD=1|LibReference=41cc1aee4cbc9fa2660a15773fa0e79|ComponentDescription=IC MONITOR PWR/CURR BIDIR 8-SOIC|PartCount=2|DisplayModeCount=1|IndexInSheet=278|OwnerPartId=-1|Location.X=690|Location.Y=165|CurrentPartId=1|LibraryPath=*|SourceLibraryName=Altium Content Vault|TargetFileName=*|AreaColor=11599871|Color=128|PartIDLocked=T|DesignItemId=CMP-0704-00005-3|AllPinCount=8
|RECORD=14|OwnerIndex=3776|IsNotAccesible=T|OwnerPartId=1|Location.X=710|Location.Y=85|Corner.X=800|Corner.Y=175|LineWidth=1|Color=128|AreaColor=11599871|IsSolid=T
|RECORD=2|OwnerIndex=3776|OwnerPartId=1|PinConglomerate=58|PinLength=20|Location.X=710|Location.Y=105|Name=VIN+|Designator=8|PinName_PositionConglomerate=16|Name_CustomFontID=1|PinDesignator_PositionConglomerate=16|Designator_CustomFontID=1|PinPropagationDelay=0.000000E+000
|RECORD=2|OwnerIndex=3776|OwnerPartId=1|PinConglomerate=58|PinLength=20|Location.X=710|Location.Y=95|Name=VIN-|Designator=7|PinName_PositionConglomerate=16|Name_CustomFontID=1|PinDesignator_PositionConglomerate=16|Designator_CustomFontID=1|PinPropagationDelay=0.000000E+000
|RECORD=2|OwnerIndex=3776|OwnerPartId=1|PinConglomerate=56|PinLength=20|Location.X=800|Location.Y=125|Name=A0|Designator=2|PinName_PositionConglomerate=16|Name_CustomFontID=1|PinDesignator_PositionConglomerate=16|Designator_CustomFontID=1|PinPropagationDelay=0.000000E+000
|RECORD=2|OwnerIndex=3776|OwnerPartId=1|PinConglomerate=56|PinLength=20|Location.X=800|Location.Y=115|Name=A1|Designator=1|PinName_PositionConglomerate=16|Name_CustomFontID=1|PinDesignator_PositionConglomerate=16|Designator_CustomFontID=1|PinPropagationDelay=0.000000E+000
|RECORD=2|OwnerIndex=3776|OwnerPartId=1|SymBol_InnerEdge=3|Electrical=1|PinConglomerate=56|PinLength=20|Location.X=800|Location.Y=145|Name=SCL|Designator=4|PinName_PositionConglomerate=16|Name_CustomFontID=1|PinDesignator_PositionConglomerate=16|Designator_CustomFontID=1|PinPropagationDelay=0.000000E+000
|RECORD=2|OwnerIndex=3776|OwnerPartId=1|Electrical=1|PinConglomerate=56|PinLength=20|Location.X=800|Location.Y=165|Name=SDA|Designator=3|PinName_PositionConglomerate=16|Name_CustomFontID=1|PinDesignator_PositionConglomerate=16|Designator_CustomFontID=1|PinPropagationDelay=0.000000E+000
|RECORD=2|OwnerIndex=3776|OwnerPartId=1|Electrical=7|PinConglomerate=58|PinLength=20|Location.X=710|Location.Y=165|Name=VS|Designator=5|PinName_PositionConglomerate=16|Name_CustomFontID=1|PinDesignator_PositionConglomerate=16|Designator_CustomFontID=1|PinPropagationDelay=0.000000E+000
|RECORD=2|OwnerIndex=3776|OwnerPartId=1|Electrical=7|PinConglomerate=56|PinLength=20|Location.X=800|Location.Y=95|Name=GND|Designator=6|PinName_PositionConglomerate=16|Name_CustomFontID=1|PinDesignator_PositionConglomerate=16|Designator_CustomFontID=1|PinPropagationDelay=0.000000E+000
|RECORD=41|OwnerIndex=3776|IndexInSheet=9|OwnerPartId=-1|Location.X=688|Location.Y=175|Color=8388608|FontID=1|IsHidden=T|Text=3V|Name=Min Supply Voltage
|RECORD=41|OwnerIndex=3776|IndexInSheet=10|OwnerPartId=-1|Location.X=688|Location.Y=175|Color=8388608|FontID=1|IsHidden=T|Text=100dB|Name=Common Mode Rejection Ratio
|RECORD=41|OwnerIndex=3776|IndexInSheet=11|OwnerPartId=-1|Location.X=688|Location.Y=175|Color=8388608|FontID=1|IsHidden=T|Text=Tape and Reel|Name=Packaging
|RECORD=41|OwnerIndex=3776|IndexInSheet=12|OwnerPartId=-1|Location.X=688|Location.Y=175|Color=8388608|FontID=1|IsHidden=T|Text=No SVHC|Name=REACH SVHC
|RECORD=41|OwnerIndex=3776|IndexInSheet=13|OwnerPartId=-1|Location.X=688|Location.Y=175|Color=8388608|FontID=1|IsHidden=T|Text=125°C|Name=Max Operating Temperature
|RECORD=41|OwnerIndex=3776|IndexInSheet=14|OwnerPartId=-1|Location.X=688|Location.Y=175|Color=8388608|FontID=1|IsHidden=T|Text=8|Name=Number of Pins
|RECORD=41|OwnerIndex=3776|IndexInSheet=15|OwnerPartId=-1|Location.X=688|Location.Y=175|Color=8388608|FontID=1|IsHidden=T|Text=10mA|Name=Output Current
|RECORD=41|OwnerIndex=3776|IndexInSheet=16|OwnerPartId=-1|Location.X=688|Location.Y=175|Color=8388608|FontID=1|IsHidden=T|Text=Lead Free|Name=Lead Free
|RECORD=41|OwnerIndex=3776|IndexInSheet=17|OwnerPartId=-1|Location.X=688|Location.Y=175|Color=8388608|FontID=1|IsHidden=T|Text=1|Name=Package Quantity
|RECORD=41|OwnerIndex=3776|IndexInSheet=18|OwnerPartId=-1|Location.X=688|Location.Y=175|Color=8388608|FontID=1|IsHidden=T|Text=No|Name=Radiation Hardening
|RECORD=41|OwnerIndex=3776|IndexInSheet=19|OwnerPartId=-1|Location.X=688|Location.Y=175|Color=8388608|FontID=1|IsHidden=T|Text=SOIC|Name=Case/Package
|RECORD=41|OwnerIndex=3776|IndexInSheet=20|OwnerPartId=-1|Location.X=688|Location.Y=175|Color=8388608|FontID=1|IsHidden=T|Text=1|Name=Number of Amplifiers
|RECORD=41|OwnerIndex=3776|IndexInSheet=21|OwnerPartId=-1|Location.X=688|Location.Y=175|Color=8388608|FontID=1|IsHidden=T|Text=-40°C|Name=Min Operating Temperature
|RECORD=41|OwnerIndex=3776|IndexInSheet=22|OwnerPartId=-1|Location.X=688|Location.Y=175|Color=8388608|FontID=1|IsHidden=T|Text=0.5%|Name=Accuracy
|RECORD=41|OwnerIndex=3776|IndexInSheet=23|OwnerPartId=-1|Location.X=688|Location.Y=175|Color=8388608|FontID=1|IsHidden=T|Text=1mA|Name=Supply Current
|RECORD=41|OwnerIndex=3776|IndexInSheet=24|OwnerPartId=-1|Location.X=688|Location.Y=175|Color=8388608|FontID=1|IsHidden=T|Text=Gold|Name=Contact Plating
|RECORD=41|OwnerIndex=3776|IndexInSheet=25|OwnerPartId=-1|Location.X=688|Location.Y=175|Color=8388608|FontID=1|IsHidden=T|Text=700uA|Name=Quiescent Current
|RECORD=41|OwnerIndex=3776|IndexInSheet=26|OwnerPartId=-1|Location.X=688|Location.Y=175|Color=8388608|FontID=1|IsHidden=T|Text=Zero-Drift|Name=Series
|RECORD=41|OwnerIndex=3776|IndexInSheet=27|OwnerPartId=-1|Location.X=688|Location.Y=175|Color=8388608|FontID=1|IsHidden=T|Text=1mA|Name=Nominal Supply Current
|RECORD=41|OwnerIndex=3776|IndexInSheet=28|OwnerPartId=-1|Location.X=688|Location.Y=175|Color=8388608|FontID=1|IsHidden=T|Text=11kHz|Name=Bandwidth
|RECORD=41|OwnerIndex=3776|IndexInSheet=29|OwnerPartId=-1|Location.X=688|Location.Y=175|Color=8388608|FontID=1|IsHidden=T|Text=40uV|Name=Input Offset Voltage (Vos)
|RECORD=41|OwnerIndex=3776|IndexInSheet=30|OwnerPartId=-1|Location.X=688|Location.Y=175|Color=8388608|FontID=1|IsHidden=T|Text=5.5V|Name=Max Supply Voltage
|RECORD=41|OwnerIndex=3776|IndexInSheet=31|OwnerPartId=-1|Location.X=688|Location.Y=175|Color=8388608|FontID=1|IsHidden=T|Text=Yes|Name=RoHS Compliant
|RECORD=34|OwnerIndex=3776|IndexInSheet=-1|OwnerPartId=-1|Location.X=710|Location.Y=175|Color=8388608|FontID=1|Text=U19|Name=Designator|ReadOnlyState=1
|RECORD=41|OwnerIndex=3776|IndexInSheet=-1|OwnerPartId=1|Location.X=710|Location.Y=75|Color=8388608|FontID=1|Text=INA219BIDR|Name=Comment
|RECORD=44|OwnerIndex=3776
|RECORD=45|OwnerIndex=3819|IndexInSheet=-1|UseComponentLibrary=T|ModelName=FP-D0008A-MFG|ModelType=PCBLIB|DatafileCount=1|ModelDatafileEntity0=FP-D0008A-MFG|ModelDatafileKind0=PCBLib|IsCurrent=T|DatalinksLocked=T|DatabaseDatalinksLocked=T
|RECORD=46|OwnerIndex=3820
|RECORD=48|OwnerIndex=3820
|RECORD=45|OwnerIndex=3819|IndexInSheet=-1|UseComponentLibrary=T|ModelName=FP-D0008A-IPC_A|ModelType=PCBLIB|DatafileCount=1|ModelDatafileEntity0=FP-D0008A-IPC_A|ModelDatafileKind0=PCBLib|DatalinksLocked=T|DatabaseDatalinksLocked=T
|RECORD=46|OwnerIndex=3823
|RECORD=48|OwnerIndex=3823
|RECORD=45|OwnerIndex=3819|IndexInSheet=-1|UseComponentLibrary=T|ModelName=FP-D0008A-IPC_C|ModelType=PCBLIB|DatafileCount=1|ModelDatafileEntity0=FP-D0008A-IPC_C|ModelDatafileKind0=PCBLib|DatalinksLocked=T|DatabaseDatalinksLocked=T
|RECORD=46|OwnerIndex=3826
|RECORD=48|OwnerIndex=3826
|RECORD=45|OwnerIndex=3819|IndexInSheet=-1|UseComponentLibrary=T|ModelName=FP-D0008A-IPC_B|ModelType=PCBLIB|DatafileCount=1|ModelDatafileEntity0=FP-D0008A-IPC_B|ModelDatafileKind0=PCBLib|DatalinksLocked=T|DatabaseDatalinksLocked=T
|RECORD=46|OwnerIndex=3829
|RECORD=48|OwnerIndex=3829
|RECORD=1|LibReference=CAP|PartCount=2|DisplayModeCount=2|IndexInSheet=279|OwnerPartId=-1|Location.X=580|Location.Y=130|Orientation=1|CurrentPartId=1|SourceLibraryName=Altium Content Vault|TargetFileName=*|AreaColor=11599871|Color=128|PartIDLocked=F|DesignItemId=CMP-2008-00031-1|AllPinCount=2
|RECORD=2|OwnerIndex=3832|OwnerPartId=1|OwnerPartDisplayMode=1|FormalType=1|Electrical=4|PinConglomerate=35|PinLength=10|Location.X=590|Location.Y=130|Name=1|Designator=1|PinPropagationDelay=0.000000E+000
|RECORD=2|OwnerIndex=3832|OwnerPartId=1|OwnerPartDisplayMode=1|FormalType=1|Electrical=4|PinConglomerate=33|PinLength=10|Location.X=590|Location.Y=140|Name=2|Designator=2|PinPropagationDelay=0.000000E+000
|RECORD=13|OwnerIndex=3832|IsNotAccesible=T|IndexInSheet=2|OwnerPartId=1|OwnerPartDisplayMode=1|Location.X=598|Location.Y=130|Corner.X=582|Corner.Y=130|LineWidth=1|Color=16711680
|RECORD=13|OwnerIndex=3832|IsNotAccesible=T|IndexInSheet=3|OwnerPartId=1|OwnerPartDisplayMode=1|Location.X=590|Location.Y=134|Corner.X=590|Corner.Y=140|LineWidth=1|Color=16711680
|RECORD=12|OwnerIndex=3832|IsNotAccesible=T|IndexInSheet=4|OwnerPartId=1|OwnerPartDisplayMode=1|Location.X=590|Location.Y=150|Radius=16|LineWidth=1|StartAngle=241.000|EndAngle=270.000|Color=16711680
|RECORD=12|OwnerIndex=3832|IsNotAccesible=T|IndexInSheet=5|OwnerPartId=1|OwnerPartDisplayMode=1|Location.X=590|Location.Y=150|Radius=16|LineWidth=1|StartAngle=270.000|EndAngle=299.000|Color=16711680
|RECORD=2|OwnerIndex=3832|OwnerPartId=1|FormalType=1|Electrical=4|PinConglomerate=35|PinLength=10|Location.X=590|Location.Y=130|Name=1|Designator=1|PinPropagationDelay=0.000000E+000
|RECORD=2|OwnerIndex=3832|OwnerPartId=1|FormalType=1|Electrical=4|PinConglomerate=33|PinLength=10|Location.X=590|Location.Y=140|Name=2|Designator=2|PinPropagationDelay=0.000000E+000
|RECORD=13|OwnerIndex=3832|IsNotAccesible=T|IndexInSheet=8|OwnerPartId=1|Location.X=582|Location.Y=137|Corner.X=598|Corner.Y=137|LineWidth=1|Color=16711680
|RECORD=13|OwnerIndex=3832|IsNotAccesible=T|IndexInSheet=9|OwnerPartId=1|Location.X=598|Location.Y=133|Corner.X=582|Corner.Y=133|LineWidth=1|Color=16711680
|RECORD=6|OwnerIndex=3832|IsNotAccesible=T|IndexInSheet=10|OwnerPartId=1|LineWidth=1|Color=16711680|LocationCount=2|X1=590|Y1=130|X2=590|Y2=133
|RECORD=6|OwnerIndex=3832|IsNotAccesible=T|IndexInSheet=11|OwnerPartId=1|LineWidth=1|Color=16711680|LocationCount=2|X1=590|Y1=140|X2=590|Y2=137
|RECORD=41|OwnerIndex=3832|IndexInSheet=12|OwnerPartId=-1|Location.X=581|Location.Y=152|Color=8388608|FontID=1|IsHidden=T|Text=LD02YD104KAB2A|Name=Part Number
|RECORD=41|OwnerIndex=3832|IndexInSheet=13|OwnerPartId=-1|Location.X=581|Location.Y=152|Color=8388608|FontID=1|IsHidden=T|Text=AVX Interconnect / Elco|Name=Manufacturer
|RECORD=34|OwnerIndex=3832|IndexInSheet=-1|OwnerPartId=-1|Location.X=590|Location.Y=140|Orientation=1|Color=8388608|FontID=2|Text=C84|Name=Designator|ReadOnlyState=1
|RECORD=41|OwnerIndex=3832|IndexInSheet=-1|OwnerPartId=-1|Location.X=600|Location.Y=145|Orientation=1|Color=8388608|FontID=2|Text=0.1uF_0402|Name=Comment
|RECORD=44|OwnerIndex=3832
|RECORD=45|OwnerIndex=3853|IndexInSheet=-1|Description=Chip Capacitor, 2-Leads, Body 1.00x0.50mm, IPC Medium Density|UseComponentLibrary=T|ModelName=CAPC1005X56X25NL10T15|ModelType=PCBLIB|DatafileCount=1|ModelDatafileEntity0=CAPC1005X56X25NL10T15|ModelDatafileKind0=PCBLib|IsCurrent=T|DatalinksLocked=T|DatabaseDatalinksLocked=T
|RECORD=46|OwnerIndex=3854
|RECORD=48|OwnerIndex=3854
|RECORD=41|OwnerIndex=3856|IndexInSheet=-1|OwnerPartId=-1|Color=8388608|FontID=1|IsHidden=T|Text=2D|Name=Available Preview Images
|RECORD=45|OwnerIndex=3853|IndexInSheet=-1|Description=Chip Capacitor, 2-Leads, Body 1.00x0.50mm, IPC High Density|UseComponentLibrary=T|ModelName=CAPC1005X56X25LL10T15|ModelType=PCBLIB|DatafileCount=1|ModelDatafileEntity0=CAPC1005X56X25LL10T15|ModelDatafileKind0=PCBLib|DatalinksLocked=T|DatabaseDatalinksLocked=T
|RECORD=46|OwnerIndex=3858
|RECORD=48|OwnerIndex=3858
|RECORD=41|OwnerIndex=3860|IndexInSheet=-1|OwnerPartId=-1|Color=8388608|FontID=1|IsHidden=T|Text=2D|Name=Available Preview Images
|RECORD=45|OwnerIndex=3853|IndexInSheet=-1|Description=Chip Capacitor, 2-Leads, Body 1.00x0.50mm, IPC Low Density|UseComponentLibrary=T|ModelName=CAPC1005X56X25ML10T15|ModelType=PCBLIB|DatafileCount=1|ModelDatafileEntity0=CAPC1005X56X25ML10T15|ModelDatafileKind0=PCBLib|DatalinksLocked=T|DatabaseDatalinksLocked=T
|RECORD=46|OwnerIndex=3862
|RECORD=48|OwnerIndex=3862
|RECORD=41|OwnerIndex=3864|IndexInSheet=-1|OwnerPartId=-1|Color=8388608|FontID=1|IsHidden=T|Text=2D|Name=Available Preview Images
|RECORD=1|LibReference=b4654b650e69147ec39a6b967a45e02|ComponentDescription=Multilayer Ceramic Capacitor 10uF 16V X5R 20% SMD 0603 T/R|PartCount=2|DisplayModeCount=1|IndexInSheet=280|OwnerPartId=-1|Location.X=550|Location.Y=145|CurrentPartId=1|LibraryPath=*|SourceLibraryName=Altium Content Vault|TargetFileName=*|AreaColor=11599871|Color=128|PartIDLocked=T|DesignItemId=CMP-2000-06226-4|AllPinCount=2
|RECORD=2|OwnerIndex=3866|OwnerPartId=1|Electrical=4|PinConglomerate=49|PinLength=7|Location.X=550|Location.Y=138|Name=1|Designator=1|PinPropagationDelay=0.000000E+000
|RECORD=2|OwnerIndex=3866|OwnerPartId=1|Electrical=4|PinConglomerate=51|PinLength=6|Location.X=550|Location.Y=131|Name=2|Designator=2|PinPropagationDelay=0.000000E+000
|RECORD=13|OwnerIndex=3866|IsNotAccesible=T|IndexInSheet=2|OwnerPartId=1|Location.X=560|Location.Y=138|Corner.X=540|Corner.Y=138|LineWidth=1|Color=16711680
|RECORD=13|OwnerIndex=3866|IsNotAccesible=T|IndexInSheet=3|OwnerPartId=1|Location.X=560|Location.Y=132|Corner.X=540|Corner.Y=132|LineWidth=1|Color=16711680
|RECORD=13|OwnerIndex=3866|IsNotAccesible=T|IndexInSheet=4|OwnerPartId=1|Location.X=550|Location.Y=138|Corner.X=550|Corner.Y=141|LineWidth=1|Color=16711680
|RECORD=13|OwnerIndex=3866|IsNotAccesible=T|IndexInSheet=5|OwnerPartId=1|Location.X=550|Location.Y=131|Corner.X=550|Corner.Y=130|LineWidth=1|Color=16711680
|RECORD=41|OwnerIndex=3866|IndexInSheet=6|OwnerPartId=-1|Location.X=539|Location.Y=147|Color=8388608|FontID=1|IsHidden=T|Text=Tape and Reel|Name=Packaging
|RECORD=41|OwnerIndex=3866|IndexInSheet=7|OwnerPartId=-1|Location.X=539|Location.Y=147|Color=8388608|FontID=1|IsHidden=T|Text=Flat|Name=Construction
|RECORD=41|OwnerIndex=3866|IndexInSheet=8|OwnerPartId=-1|Location.X=539|Location.Y=147|Color=8388608|FontID=1|IsHidden=T|Text=0.8mm|Name=Height
|RECORD=41|OwnerIndex=3866|IndexInSheet=9|OwnerPartId=-1|Location.X=539|Location.Y=147|Color=8388608|FontID=1|IsHidden=T|Text=85°C|Name=Max Operating Temperature
|RECORD=41|OwnerIndex=3866|IndexInSheet=10|OwnerPartId=-1|Location.X=539|Location.Y=147|Color=8388608|FontID=1|IsHidden=T|Text=X5R|Name=Dielectric
|RECORD=41|OwnerIndex=3866|IndexInSheet=11|OwnerPartId=-1|Location.X=539|Location.Y=147|Color=8388608|FontID=1|IsHidden=T|Text=1608|Name=Case Code (Metric)
|RECORD=41|OwnerIndex=3866|IndexInSheet=12|OwnerPartId=-1|Location.X=539|Location.Y=147|Color=8388608|FontID=1|IsHidden=T|Text=16V|Name=Voltage Rating (DC)
|RECORD=41|OwnerIndex=3866|IndexInSheet=13|OwnerPartId=-1|Location.X=539|Location.Y=147|Color=8388608|FontID=1|IsHidden=T|Text=0.031inch|Name=Width
|RECORD=41|OwnerIndex=3866|IndexInSheet=14|OwnerPartId=-1|Location.X=539|Location.Y=147|Color=8388608|FontID=1|IsHidden=T|Text=16V|Name=Voltage Rating
|RECORD=41|OwnerIndex=3866|IndexInSheet=15|OwnerPartId=-1|Location.X=539|Location.Y=147|Color=8388608|FontID=1|IsHidden=T|Text=0.063inch|Name=Length
|RECORD=41|OwnerIndex=3866|IndexInSheet=16|OwnerPartId=-1|Location.X=539|Location.Y=147|Color=8388608|FontID=1|IsHidden=T|Text=Yes|Name=RoHS Compliant
|RECORD=41|OwnerIndex=3866|IndexInSheet=17|OwnerPartId=-1|Location.X=539|Location.Y=147|Color=8388608|FontID=1|IsHidden=T|Text=Halogen Free|Name=Halogen Free
|RECORD=41|OwnerIndex=3866|IndexInSheet=18|OwnerPartId=-1|Location.X=539|Location.Y=147|Color=8388608|FontID=1|IsHidden=T|Text=0603|Name=Case Code (Imperial)
|RECORD=41|OwnerIndex=3866|IndexInSheet=19|OwnerPartId=-1|Location.X=539|Location.Y=147|Color=8388608|FontID=1|IsHidden=T|Text=10uF|Name=Capacitance
|RECORD=41|OwnerIndex=3866|IndexInSheet=20|OwnerPartId=-1|Location.X=539|Location.Y=147|Color=8388608|FontID=1|IsHidden=T|Text=Surface Mount|Name=Mount
|RECORD=41|OwnerIndex=3866|IndexInSheet=21|OwnerPartId=-1|Location.X=539|Location.Y=147|Color=8388608|FontID=1|IsHidden=T|Text=0.031inch|Name=Thickness
|RECORD=41|OwnerIndex=3866|IndexInSheet=22|OwnerPartId=-1|Location.X=539|Location.Y=147|Color=8388608|FontID=1|IsHidden=T|Text=20%|Name=Tolerance
|RECORD=41|OwnerIndex=3866|IndexInSheet=23|OwnerPartId=-1|Location.X=539|Location.Y=147|Color=8388608|FontID=1|IsHidden=T|Text=-55°C|Name=Min Operating Temperature
|RECORD=41|OwnerIndex=3866|IndexInSheet=24|OwnerPartId=-1|Location.X=539|Location.Y=147|Color=8388608|FontID=1|IsHidden=T|Text=M|Name=Series
|RECORD=41|OwnerIndex=3866|IndexInSheet=25|OwnerPartId=-1|Location.X=539|Location.Y=147|Color=8388608|FontID=1|IsHidden=T|Text=SMD/SMT|Name=Termination
|RECORD=41|OwnerIndex=3866|IndexInSheet=26|OwnerPartId=-1|Location.X=539|Location.Y=147|Color=8388608|FontID=1|IsHidden=T|Text=0603|Name=Case/Package
|RECORD=41|OwnerIndex=3866|IndexInSheet=27|OwnerPartId=-1|Location.X=539|Location.Y=147|Color=8388608|FontID=1|IsHidden=T|Text=1|Name=Package Quantity
|RECORD=34|OwnerIndex=3866|IndexInSheet=-1|OwnerPartId=-1|Location.X=540|Location.Y=125|Orientation=1|Color=8388608|FontID=2|Text=C85|Name=Designator|ReadOnlyState=1
|RECORD=41|OwnerIndex=3866|IndexInSheet=-1|OwnerPartId=1|Location.X=570|Location.Y=110|Orientation=1|Color=8388608|FontID=2|Text=10uF_16V_0603|Name=Comment
|RECORD=44|OwnerIndex=3866
|RECORD=45|OwnerIndex=3899|IndexInSheet=-1|UseComponentLibrary=T|ModelName=FP-0603-L_1_6_0_2-W_0_8_0-MFG|ModelType=PCBLIB|DatafileCount=1|ModelDatafileEntity0=FP-0603-L_1_6_0_2-W_0_8_0-MFG|ModelDatafileKind0=PCBLib|IsCurrent=T|DatalinksLocked=T|DatabaseDatalinksLocked=T
|RECORD=46|OwnerIndex=3900
|RECORD=48|OwnerIndex=3900
|RECORD=45|OwnerIndex=3899|IndexInSheet=-1|UseComponentLibrary=T|ModelName=FP-0603-L_1_6_0_2-W_0_8_0-IPC_B|ModelType=PCBLIB|DatafileCount=1|ModelDatafileEntity0=FP-0603-L_1_6_0_2-W_0_8_0-IPC_B|ModelDatafileKind0=PCBLib|DatalinksLocked=T|DatabaseDatalinksLocked=T
|RECORD=46|OwnerIndex=3903
|RECORD=48|OwnerIndex=3903
|RECORD=45|OwnerIndex=3899|IndexInSheet=-1|UseComponentLibrary=T|ModelName=FP-0603-L_1_6_0_2-W_0_8_0-IPC_C|ModelType=PCBLIB|DatafileCount=1|ModelDatafileEntity0=FP-0603-L_1_6_0_2-W_0_8_0-IPC_C|ModelDatafileKind0=PCBLib|DatalinksLocked=T|DatabaseDatalinksLocked=T
|RECORD=46|OwnerIndex=3906
|RECORD=48|OwnerIndex=3906
|RECORD=45|OwnerIndex=3899|IndexInSheet=-1|UseComponentLibrary=T|ModelName=FP-0603-L_1_6_0_2-W_0_8_0-IPC_A|ModelType=PCBLIB|DatafileCount=1|ModelDatafileEntity0=FP-0603-L_1_6_0_2-W_0_8_0-IPC_A|ModelDatafileKind0=PCBLib|DatalinksLocked=T|DatabaseDatalinksLocked=T
|RECORD=46|OwnerIndex=3909
|RECORD=48|OwnerIndex=3909
|RECORD=17|IndexInSheet=281|OwnerPartId=-1|ShowNetName=T|Location.X=550|Location.Y=185|Orientation=1|Color=128|FontID=1|Text=+3.3V
|RECORD=17|IndexInSheet=282|OwnerPartId=-1|Style=4|ShowNetName=T|Location.X=550|Location.Y=115|Orientation=3|Color=128|FontID=1|Text=GND
|RECORD=17|IndexInSheet=283|OwnerPartId=-1|Style=4|ShowNetName=T|Location.X=590|Location.Y=115|Orientation=3|Color=128|FontID=1|Text=GND
|RECORD=17|IndexInSheet=284|OwnerPartId=-1|ShowNetName=T|Location.X=670|Location.Y=130|Orientation=1|Color=128|FontID=1|Text=P3V3_SENSE
|RECORD=17|IndexInSheet=285|OwnerPartId=-1|Style=4|ShowNetName=T|Location.X=830|Location.Y=90|Orientation=3|Color=128|FontID=1|Text=GND
|RECORD=17|IndexInSheet=286|OwnerPartId=-1|ShowNetName=T|Location.X=865|Location.Y=145|Color=255|FontID=1|Text=SCL|IsCrossSheetConnector=T
|RECORD=17|IndexInSheet=287|OwnerPartId=-1|ShowNetName=T|Location.X=865|Location.Y=165|Color=255|FontID=1|Text=SDA|IsCrossSheetConnector=T
|RECORD=1|LibReference=RES-2|ComponentDescription=Chip Resistor, 0 Ohm, 0.1 W, -55 to 155 degC, 0402 (1005 Metric), RoHS, Tape and Reel|PartCount=2|DisplayModeCount=1|IndexInSheet=288|OwnerPartId=-1|Location.X=850|Location.Y=125|CurrentPartId=1|LibraryPath=*|SourceLibraryName=Altium Content Vault|TargetFileName=*|AreaColor=11599871|Color=128|PartIDLocked=T|DesignItemId=CMP-2000-07451-1|AllPinCount=2
|RECORD=2|OwnerIndex=3919|OwnerPartId=1|FormalType=1|Electrical=4|PinConglomerate=32|PinLength=10|Location.X=870|Location.Y=125|Name=2|Designator=2|PinPropagationDelay=0.000000E+000
|RECORD=2|OwnerIndex=3919|OwnerPartId=1|FormalType=1|Electrical=4|PinConglomerate=34|PinLength=10|Location.X=850|Location.Y=125|Name=1|Designator=1|PinPropagationDelay=0.000000E+000
|RECORD=6|OwnerIndex=3919|IsNotAccesible=T|IndexInSheet=2|OwnerPartId=1|LineWidth=1|Color=16711680|LocationCount=10|X1=870|Y1=125|X2=866|Y2=125|X3=865|Y3=123|X4=863|Y4=127|X5=861|Y5=123|X6=859|Y6=127|X7=857|Y7=123|X8=855|Y8=127|X9=854|Y9=125|X10=850|Y10=125
|RECORD=41|OwnerIndex=3919|IndexInSheet=3|OwnerPartId=-1|Location.X=838|Location.Y=140|Color=8388608|FontID=1|IsHidden=T|Text=50V|Name=Voltage Rating (DC)
|RECORD=41|OwnerIndex=3919|IndexInSheet=4|OwnerPartId=-1|Location.X=838|Location.Y=140|Color=8388608|FontID=1|IsHidden=T|Text=2|Name=Number of Terminations
|RECORD=41|OwnerIndex=3919|IndexInSheet=5|OwnerPartId=-1|Location.X=838|Location.Y=140|Color=8388608|FontID=1|IsHidden=T|Text=SurfaceMount|Name=Mount
|RECORD=41|OwnerIndex=3919|IndexInSheet=6|OwnerPartId=-1|Location.X=838|Location.Y=140|Color=8388608|FontID=1|IsHidden=T|Text=0.35mm|Name=Height
|RECORD=41|OwnerIndex=3919|IndexInSheet=7|OwnerPartId=-1|Location.X=838|Location.Y=140|Color=8388608|FontID=1|IsHidden=T|Text=TapeandReel|Name=Packaging
|RECORD=41|OwnerIndex=3919|IndexInSheet=8|OwnerPartId=-1|Location.X=838|Location.Y=140|Color=8388608|FontID=1|IsHidden=T|Text=Tin|Name=Contact Plating
|RECORD=41|OwnerIndex=3919|IndexInSheet=9|OwnerPartId=-1|Location.X=838|Location.Y=140|Color=8388608|FontID=7|IsHidden=T|Text=http://www.panasonic.com/|Name=Manufacturer URL
|RECORD=41|OwnerIndex=3919|IndexInSheet=10|OwnerPartId=-1|Location.X=838|Location.Y=140|Color=8388608|FontID=1|IsHidden=T|Text=ThickFilm|Name=Composition
|RECORD=41|OwnerIndex=3919|IndexInSheet=11|OwnerPartId=-1|Location.X=838|Location.Y=140|Color=8388608|FontID=1|IsHidden=T|Text=155degC|Name=Max Operating Temperature
|RECORD=41|OwnerIndex=3919|IndexInSheet=12|OwnerPartId=-1|Location.X=838|Location.Y=140|Color=8388608|FontID=1|IsHidden=T|Text=600ppm/??C|Name=Temperature Coefficient
|RECORD=41|OwnerIndex=3919|IndexInSheet=13|OwnerPartId=-1|Location.X=838|Location.Y=140|Color=8388608|FontID=1|IsHidden=T|Text=NoSVHC|Name=REACH SVHC
|RECORD=41|OwnerIndex=3919|IndexInSheet=14|OwnerPartId=-1|Location.X=838|Location.Y=140|Color=8388608|FontID=1|IsHidden=T|Text=0402|Name=Case/Package
|RECORD=41|OwnerIndex=3919|IndexInSheet=15|OwnerPartId=-1|Location.X=838|Location.Y=140|Color=8388608|FontID=1|IsHidden=T|Text=100mW|Name=Max Power Dissipation
|RECORD=41|OwnerIndex=3919|IndexInSheet=16|OwnerPartId=-1|Location.X=838|Location.Y=140|Color=8388608|FontID=1|IsHidden=T|Text=402|Name=Package Reference
|RECORD=41|OwnerIndex=3919|IndexInSheet=17|OwnerPartId=-1|Location.X=838|Location.Y=140|Color=8388608|FontID=1|IsHidden=T|Text=0.5mm|Name=Depth
|RECORD=41|OwnerIndex=3919|IndexInSheet=18|OwnerPartId=-1|Location.X=838|Location.Y=140|Color=8388608|FontID=1|IsHidden=T|Text=Panasonic|Name=Manufacturer
|RECORD=41|OwnerIndex=3919|IndexInSheet=19|OwnerPartId=-1|Location.X=838|Location.Y=140|Color=8388608|FontID=1|IsHidden=T|Text=2-Pin Surface Mount Device, Body 1 x 0.5 mm|Name=Package Description
|RECORD=41|OwnerIndex=3919|IndexInSheet=20|OwnerPartId=-1|Location.X=838|Location.Y=140|Color=8388608|FontID=7|IsHidden=T|Text=https://industrial.panasonic.com/cdbs/www-data/pdf/RDA0000/AOA0000C301.pdf|Name=Datasheet URL
|RECORD=41|OwnerIndex=3919|IndexInSheet=21|OwnerPartId=-1|Location.X=838|Location.Y=140|Color=8388608|FontID=1|IsHidden=T|Text=True|Name=RoHSCompliant
|RECORD=41|OwnerIndex=3919|IndexInSheet=22|OwnerPartId=-1|Location.X=838|Location.Y=140|Color=8388608|FontID=1|IsHidden=T|Text=0402|Name=Case Code (Imperial)
|RECORD=41|OwnerIndex=3919|IndexInSheet=23|OwnerPartId=-1|Location.X=838|Location.Y=140|Color=8388608|FontID=1|IsHidden=T|Text=0mOhm|Name=Resistance
|RECORD=41|OwnerIndex=3919|IndexInSheet=24|OwnerPartId=-1|Location.X=838|Location.Y=140|Color=8388608|FontID=1|IsHidden=T|Text=Not|Name=Military Standard
|RECORD=41|OwnerIndex=3919|IndexInSheet=25|OwnerPartId=-1|Location.X=838|Location.Y=140|Color=8388608|FontID=1|IsHidden=T|Text=5%|Name=Tolerance
|RECORD=41|OwnerIndex=3919|IndexInSheet=26|OwnerPartId=-1|Location.X=838|Location.Y=140|Color=8388608|FontID=1|IsHidden=T|Text=-55degC|Name=Min Operating Temperature
|RECORD=41|OwnerIndex=3919|IndexInSheet=27|OwnerPartId=-1|Location.X=838|Location.Y=140|Color=8388608|FontID=1|IsHidden=T|Text=100mW|Name=Power Rating
|RECORD=41|OwnerIndex=3919|IndexInSheet=28|OwnerPartId=-1|Location.X=838|Location.Y=140|Color=8388608|FontID=1|IsHidden=T|Text=03/2015|Name=Datasheet Version
|RECORD=41|OwnerIndex=3919|IndexInSheet=29|OwnerPartId=-1|Location.X=838|Location.Y=140|Color=8388608|FontID=1|IsHidden=T|Text=1mm|Name=Length
|RECORD=41|OwnerIndex=3919|IndexInSheet=30|OwnerPartId=-1|Location.X=838|Location.Y=140|Color=8388608|FontID=1|IsHidden=T|Text=1005|Name=Case Code (Metric)
|RECORD=41|OwnerIndex=3919|IndexInSheet=31|OwnerPartId=-1|Location.X=838|Location.Y=140|Color=8388608|FontID=1|IsHidden=T|Text=SMD/SMT|Name=Termination
|RECORD=41|OwnerIndex=3919|IndexInSheet=32|OwnerPartId=-1|Location.X=838|Location.Y=140|Color=8388608|FontID=1|IsHidden=T|Text=SurfaceMount|Name=Mounting Technology
|RECORD=41|OwnerIndex=3919|IndexInSheet=33|OwnerPartId=-1|Location.X=838|Location.Y=140|Color=8388608|FontID=1|IsHidden=T|Text=50V|Name=Voltage Rating
|RECORD=41|OwnerIndex=3919|IndexInSheet=34|OwnerPartId=-1|Location.X=838|Location.Y=140|Color=8388608|FontID=1|IsHidden=T|Text=0.02inch|Name=Width
|RECORD=41|OwnerIndex=3919|IndexInSheet=35|OwnerPartId=-1|Location.X=838|Location.Y=140|Color=8388608|FontID=1|IsHidden=T|Text=1|Name=Package Quantity
|RECORD=41|OwnerIndex=3919|IndexInSheet=36|OwnerPartId=-1|Location.X=838|Location.Y=140|Color=8388608|FontID=1|IsHidden=T|Text=LeadFree|Name=Lead Free
|RECORD=41|OwnerIndex=3919|IndexInSheet=37|OwnerPartId=-1|Location.X=838|Location.Y=140|Color=8388608|FontID=1|IsHidden=T|Text=No|Name=Radiation Hardening
|RECORD=34|OwnerIndex=3919|IndexInSheet=-1|OwnerPartId=-1|Location.X=830|Location.Y=125|Color=8388608|FontID=1|Text=R79|Name=Designator|ReadOnlyState=1
|RECORD=41|OwnerIndex=3919|IndexInSheet=-1|OwnerPartId=-1|Location.X=870|Location.Y=125|Color=8388608|FontID=1|Text=0_1%_0402|Name=Comment
|RECORD=44|OwnerIndex=3919
|RECORD=45|OwnerIndex=3962|IndexInSheet=-1|Description=Chip Resistor, 2-Leads, Body 1.05x0.55mm, IPC High Density|UseComponentLibrary=T|ModelName=RESC1005X40X25LL05T05|ModelType=PCBLIB|DatafileCount=1|ModelDatafileEntity0=RESC1005X40X25LL05T05|ModelDatafileKind0=PCBLib|IsCurrent=T|DatalinksLocked=T|DatabaseDatalinksLocked=T
|RECORD=46|OwnerIndex=3963
|RECORD=48|OwnerIndex=3963
|RECORD=41|OwnerIndex=3965|IndexInSheet=-1|OwnerPartId=-1|Color=8388608|FontID=1|IsHidden=T|Text=2D|Name=Available Preview Images
|RECORD=45|OwnerIndex=3962|IndexInSheet=-1|Description=Chip Resistor, 2-Leads, Body 1.05x0.55mm, IPC Low Density|UseComponentLibrary=T|ModelName=RESC1005X40X25ML05T05|ModelType=PCBLIB|DatafileCount=1|ModelDatafileEntity0=RESC1005X40X25ML05T05|ModelDatafileKind0=PCBLib|DatalinksLocked=T|DatabaseDatalinksLocked=T
|RECORD=46|OwnerIndex=3967
|RECORD=48|OwnerIndex=3967
|RECORD=41|OwnerIndex=3969|IndexInSheet=-1|OwnerPartId=-1|Color=8388608|FontID=1|IsHidden=T|Text=2D|Name=Available Preview Images
|RECORD=45|OwnerIndex=3962|IndexInSheet=-1|Description=Chip Resistor, 2-Leads, Body 1.05x0.55mm, IPC Medium Density|UseComponentLibrary=T|ModelName=RESC1005X40X25NL05T05|ModelType=PCBLIB|DatafileCount=1|ModelDatafileEntity0=RESC1005X40X25NL05T05|ModelDatafileKind0=PCBLib|DatalinksLocked=T|DatabaseDatalinksLocked=T
|RECORD=46|OwnerIndex=3971
|RECORD=48|OwnerIndex=3971
|RECORD=41|OwnerIndex=3973|IndexInSheet=-1|OwnerPartId=-1|Color=8388608|FontID=1|IsHidden=T|Text=2D|Name=Available Preview Images
|RECORD=1|LibReference=RES-2|ComponentDescription=Chip Resistor, 0 Ohm, 0.1 W, -55 to 155 degC, 0402 (1005 Metric), RoHS, Tape and Reel|PartCount=2|DisplayModeCount=1|IndexInSheet=289|OwnerPartId=-1|Location.X=850|Location.Y=115|CurrentPartId=1|LibraryPath=*|SourceLibraryName=Altium Content Vault|TargetFileName=*|AreaColor=11599871|Color=128|PartIDLocked=T|DesignItemId=CMP-2000-07451-1|AllPinCount=2
|RECORD=2|OwnerIndex=3975|OwnerPartId=1|FormalType=1|Electrical=4|PinConglomerate=32|PinLength=10|Location.X=870|Location.Y=115|Name=2|Designator=2|PinPropagationDelay=0.000000E+000
|RECORD=2|OwnerIndex=3975|OwnerPartId=1|FormalType=1|Electrical=4|PinConglomerate=34|PinLength=10|Location.X=850|Location.Y=115|Name=1|Designator=1|PinPropagationDelay=0.000000E+000
|RECORD=6|OwnerIndex=3975|IsNotAccesible=T|IndexInSheet=2|OwnerPartId=1|LineWidth=1|Color=16711680|LocationCount=10|X1=870|Y1=115|X2=866|Y2=115|X3=865|Y3=113|X4=863|Y4=117|X5=861|Y5=113|X6=859|Y6=117|X7=857|Y7=113|X8=855|Y8=117|X9=854|Y9=115|X10=850|Y10=115
|RECORD=41|OwnerIndex=3975|IndexInSheet=3|OwnerPartId=-1|Location.X=838|Location.Y=130|Color=8388608|FontID=1|IsHidden=T|Text=50V|Name=Voltage Rating (DC)
|RECORD=41|OwnerIndex=3975|IndexInSheet=4|OwnerPartId=-1|Location.X=838|Location.Y=130|Color=8388608|FontID=1|IsHidden=T|Text=2|Name=Number of Terminations
|RECORD=41|OwnerIndex=3975|IndexInSheet=5|OwnerPartId=-1|Location.X=838|Location.Y=130|Color=8388608|FontID=1|IsHidden=T|Text=SurfaceMount|Name=Mount
|RECORD=41|OwnerIndex=3975|IndexInSheet=6|OwnerPartId=-1|Location.X=838|Location.Y=130|Color=8388608|FontID=1|IsHidden=T|Text=0.35mm|Name=Height
|RECORD=41|OwnerIndex=3975|IndexInSheet=7|OwnerPartId=-1|Location.X=838|Location.Y=130|Color=8388608|FontID=1|IsHidden=T|Text=TapeandReel|Name=Packaging
|RECORD=41|OwnerIndex=3975|IndexInSheet=8|OwnerPartId=-1|Location.X=838|Location.Y=130|Color=8388608|FontID=1|IsHidden=T|Text=Tin|Name=Contact Plating
|RECORD=41|OwnerIndex=3975|IndexInSheet=9|OwnerPartId=-1|Location.X=838|Location.Y=130|Color=8388608|FontID=7|IsHidden=T|Text=http://www.panasonic.com/|Name=Manufacturer URL
|RECORD=41|OwnerIndex=3975|IndexInSheet=10|OwnerPartId=-1|Location.X=838|Location.Y=130|Color=8388608|FontID=1|IsHidden=T|Text=ThickFilm|Name=Composition
|RECORD=41|OwnerIndex=3975|IndexInSheet=11|OwnerPartId=-1|Location.X=838|Location.Y=130|Color=8388608|FontID=1|IsHidden=T|Text=155degC|Name=Max Operating Temperature
|RECORD=41|OwnerIndex=3975|IndexInSheet=12|OwnerPartId=-1|Location.X=838|Location.Y=130|Color=8388608|FontID=1|IsHidden=T|Text=600ppm/??C|Name=Temperature Coefficient
|RECORD=41|OwnerIndex=3975|IndexInSheet=13|OwnerPartId=-1|Location.X=838|Location.Y=130|Color=8388608|FontID=1|IsHidden=T|Text=NoSVHC|Name=REACH SVHC
|RECORD=41|OwnerIndex=3975|IndexInSheet=14|OwnerPartId=-1|Location.X=838|Location.Y=130|Color=8388608|FontID=1|IsHidden=T|Text=0402|Name=Case/Package
|RECORD=41|OwnerIndex=3975|IndexInSheet=15|OwnerPartId=-1|Location.X=838|Location.Y=130|Color=8388608|FontID=1|IsHidden=T|Text=100mW|Name=Max Power Dissipation
|RECORD=41|OwnerIndex=3975|IndexInSheet=16|OwnerPartId=-1|Location.X=838|Location.Y=130|Color=8388608|FontID=1|IsHidden=T|Text=402|Name=Package Reference
|RECORD=41|OwnerIndex=3975|IndexInSheet=17|OwnerPartId=-1|Location.X=838|Location.Y=130|Color=8388608|FontID=1|IsHidden=T|Text=0.5mm|Name=Depth
|RECORD=41|OwnerIndex=3975|IndexInSheet=18|OwnerPartId=-1|Location.X=838|Location.Y=130|Color=8388608|FontID=1|IsHidden=T|Text=Panasonic|Name=Manufacturer
|RECORD=41|OwnerIndex=3975|IndexInSheet=19|OwnerPartId=-1|Location.X=838|Location.Y=130|Color=8388608|FontID=1|IsHidden=T|Text=2-Pin Surface Mount Device, Body 1 x 0.5 mm|Name=Package Description
|RECORD=41|OwnerIndex=3975|IndexInSheet=20|OwnerPartId=-1|Location.X=838|Location.Y=130|Color=8388608|FontID=7|IsHidden=T|Text=https://industrial.panasonic.com/cdbs/www-data/pdf/RDA0000/AOA0000C301.pdf|Name=Datasheet URL
|RECORD=41|OwnerIndex=3975|IndexInSheet=21|OwnerPartId=-1|Location.X=838|Location.Y=130|Color=8388608|FontID=1|IsHidden=T|Text=True|Name=RoHSCompliant
|RECORD=41|OwnerIndex=3975|IndexInSheet=22|OwnerPartId=-1|Location.X=838|Location.Y=130|Color=8388608|FontID=1|IsHidden=T|Text=0402|Name=Case Code (Imperial)
|RECORD=41|OwnerIndex=3975|IndexInSheet=23|OwnerPartId=-1|Location.X=838|Location.Y=130|Color=8388608|FontID=1|IsHidden=T|Text=0mOhm|Name=Resistance
|RECORD=41|OwnerIndex=3975|IndexInSheet=24|OwnerPartId=-1|Location.X=838|Location.Y=130|Color=8388608|FontID=1|IsHidden=T|Text=Not|Name=Military Standard
|RECORD=41|OwnerIndex=3975|IndexInSheet=25|OwnerPartId=-1|Location.X=838|Location.Y=130|Color=8388608|FontID=1|IsHidden=T|Text=5%|Name=Tolerance
|RECORD=41|OwnerIndex=3975|IndexInSheet=26|OwnerPartId=-1|Location.X=838|Location.Y=130|Color=8388608|FontID=1|IsHidden=T|Text=-55degC|Name=Min Operating Temperature
|RECORD=41|OwnerIndex=3975|IndexInSheet=27|OwnerPartId=-1|Location.X=838|Location.Y=130|Color=8388608|FontID=1|IsHidden=T|Text=100mW|Name=Power Rating
|RECORD=41|OwnerIndex=3975|IndexInSheet=28|OwnerPartId=-1|Location.X=838|Location.Y=130|Color=8388608|FontID=1|IsHidden=T|Text=03/2015|Name=Datasheet Version
|RECORD=41|OwnerIndex=3975|IndexInSheet=29|OwnerPartId=-1|Location.X=838|Location.Y=130|Color=8388608|FontID=1|IsHidden=T|Text=1mm|Name=Length
|RECORD=41|OwnerIndex=3975|IndexInSheet=30|OwnerPartId=-1|Location.X=838|Location.Y=130|Color=8388608|FontID=1|IsHidden=T|Text=1005|Name=Case Code (Metric)
|RECORD=41|OwnerIndex=3975|IndexInSheet=31|OwnerPartId=-1|Location.X=838|Location.Y=130|Color=8388608|FontID=1|IsHidden=T|Text=SMD/SMT|Name=Termination
|RECORD=41|OwnerIndex=3975|IndexInSheet=32|OwnerPartId=-1|Location.X=838|Location.Y=130|Color=8388608|FontID=1|IsHidden=T|Text=SurfaceMount|Name=Mounting Technology
|RECORD=41|OwnerIndex=3975|IndexInSheet=33|OwnerPartId=-1|Location.X=838|Location.Y=130|Color=8388608|FontID=1|IsHidden=T|Text=50V|Name=Voltage Rating
|RECORD=41|OwnerIndex=3975|IndexInSheet=34|OwnerPartId=-1|Location.X=838|Location.Y=130|Color=8388608|FontID=1|IsHidden=T|Text=0.02inch|Name=Width
|RECORD=41|OwnerIndex=3975|IndexInSheet=35|OwnerPartId=-1|Location.X=838|Location.Y=130|Color=8388608|FontID=1|IsHidden=T|Text=1|Name=Package Quantity
|RECORD=41|OwnerIndex=3975|IndexInSheet=36|OwnerPartId=-1|Location.X=838|Location.Y=130|Color=8388608|FontID=1|IsHidden=T|Text=LeadFree|Name=Lead Free
|RECORD=41|OwnerIndex=3975|IndexInSheet=37|OwnerPartId=-1|Location.X=838|Location.Y=130|Color=8388608|FontID=1|IsHidden=T|Text=No|Name=Radiation Hardening
|RECORD=34|OwnerIndex=3975|IndexInSheet=-1|OwnerPartId=-1|Location.X=830|Location.Y=115|Color=8388608|FontID=1|Text=R80|Name=Designator|ReadOnlyState=1
|RECORD=41|OwnerIndex=3975|IndexInSheet=-1|OwnerPartId=-1|Location.X=870|Location.Y=115|Color=8388608|FontID=1|Text=0_1%_0402|Name=Comment
|RECORD=44|OwnerIndex=3975
|RECORD=45|OwnerIndex=4018|IndexInSheet=-1|Description=Chip Resistor, 2-Leads, Body 1.05x0.55mm, IPC High Density|UseComponentLibrary=T|ModelName=RESC1005X40X25LL05T05|ModelType=PCBLIB|DatafileCount=1|ModelDatafileEntity0=RESC1005X40X25LL05T05|ModelDatafileKind0=PCBLib|IsCurrent=T|DatalinksLocked=T|DatabaseDatalinksLocked=T
|RECORD=46|OwnerIndex=4019
|RECORD=48|OwnerIndex=4019
|RECORD=41|OwnerIndex=4021|IndexInSheet=-1|OwnerPartId=-1|Color=8388608|FontID=1|IsHidden=T|Text=2D|Name=Available Preview Images
|RECORD=45|OwnerIndex=4018|IndexInSheet=-1|Description=Chip Resistor, 2-Leads, Body 1.05x0.55mm, IPC Low Density|UseComponentLibrary=T|ModelName=RESC1005X40X25ML05T05|ModelType=PCBLIB|DatafileCount=1|ModelDatafileEntity0=RESC1005X40X25ML05T05|ModelDatafileKind0=PCBLib|DatalinksLocked=T|DatabaseDatalinksLocked=T
|RECORD=46|OwnerIndex=4023
|RECORD=48|OwnerIndex=4023
|RECORD=41|OwnerIndex=4025|IndexInSheet=-1|OwnerPartId=-1|Color=8388608|FontID=1|IsHidden=T|Text=2D|Name=Available Preview Images
|RECORD=45|OwnerIndex=4018|IndexInSheet=-1|Description=Chip Resistor, 2-Leads, Body 1.05x0.55mm, IPC Medium Density|UseComponentLibrary=T|ModelName=RESC1005X40X25NL05T05|ModelType=PCBLIB|DatafileCount=1|ModelDatafileEntity0=RESC1005X40X25NL05T05|ModelDatafileKind0=PCBLib|DatalinksLocked=T|DatabaseDatalinksLocked=T
|RECORD=46|OwnerIndex=4027
|RECORD=48|OwnerIndex=4027
|RECORD=41|OwnerIndex=4029|IndexInSheet=-1|OwnerPartId=-1|Color=8388608|FontID=1|IsHidden=T|Text=2D|Name=Available Preview Images
|RECORD=4|IndexInSheet=290|OwnerPartId=-1|Location.X=730|Location.Y=195|Color=8388608|FontID=1|Text=Address 0x44
|RECORD=17|IndexInSheet=291|OwnerPartId=-1|ShowNetName=T|Location.X=930|Location.Y=180|Orientation=1|Color=128|FontID=1|Text=+3.3V
|RECORD=27|IndexInSheet=292|OwnerPartId=-1|LineWidth=1|Color=8388608|LocationCount=2|X1=1210|Y1=395|X2=1200|Y2=395
|RECORD=27|IndexInSheet=293|OwnerPartId=-1|LineWidth=1|Color=8388608|LocationCount=2|X1=1210|Y1=385|X2=1200|Y2=385
|RECORD=27|IndexInSheet=294|OwnerPartId=-1|LineWidth=1|Color=8388608|LocationCount=2|X1=1210|Y1=375|X2=1200|Y2=375
|RECORD=27|IndexInSheet=295|OwnerPartId=-1|LineWidth=1|Color=8388608|LocationCount=2|X1=1210|Y1=365|X2=1200|Y2=365
|RECORD=27|IndexInSheet=296|OwnerPartId=-1|LineWidth=1|Color=8388608|LocationCount=2|X1=1210|Y1=355|X2=1200|Y2=355
|RECORD=27|IndexInSheet=297|OwnerPartId=-1|LineWidth=1|Color=8388608|LocationCount=2|X1=1210|Y1=335|X2=1200|Y2=335
|RECORD=27|IndexInSheet=298|OwnerPartId=-1|LineWidth=1|Color=8388608|LocationCount=2|X1=620|Y1=365|X2=610|Y2=365
|RECORD=27|IndexInSheet=299|OwnerPartId=-1|LineWidth=1|Color=8388608|LocationCount=2|X1=620|Y1=375|X2=610|Y2=375
|RECORD=27|IndexInSheet=300|OwnerPartId=-1|LineWidth=1|Color=8388608|LocationCount=2|X1=620|Y1=385|X2=610|Y2=385
|RECORD=27|IndexInSheet=301|OwnerPartId=-1|LineWidth=1|Color=8388608|LocationCount=2|X1=620|Y1=395|X2=610|Y2=395
|RECORD=27|IndexInSheet=302|OwnerPartId=-1|LineWidth=1|Color=8388608|LocationCount=2|X1=620|Y1=405|X2=610|Y2=405
|RECORD=27|IndexInSheet=303|OwnerPartId=-1|LineWidth=1|Color=8388608|LocationCount=3|X1=780|Y1=445|X2=815|Y2=445|X3=815|Y3=470
|RECORD=27|IndexInSheet=304|OwnerPartId=-1|LineWidth=1|Color=8388608|LocationCount=2|X1=815|Y1=510|X2=815|Y2=525
|RECORD=27|IndexInSheet=305|OwnerPartId=-1|LineWidth=1|Color=8388608|LocationCount=3|X1=620|Y1=445|X2=500|Y2=445|X3=500|Y3=475
|RECORD=27|IndexInSheet=306|OwnerPartId=-1|LineWidth=1|Color=8388608|LocationCount=3|X1=500|Y1=515|X2=500|Y2=525|X3=485|Y3=525
|RECORD=27|IndexInSheet=307|OwnerPartId=-1|LineWidth=1|Color=8388608|LocationCount=2|X1=780|Y1=455|X2=835|Y2=455
|RECORD=27|IndexInSheet=308|OwnerPartId=-1|LineWidth=1|Color=8388608|LocationCount=2|X1=565|Y1=315|X2=565|Y2=335
|RECORD=27|IndexInSheet=309|OwnerPartId=-1|LineWidth=1|Color=8388608|LocationCount=3|X1=605|Y1=270|X2=565|Y2=270|X3=565|Y3=295
|RECORD=27|IndexInSheet=310|OwnerPartId=-1|LineWidth=1|Color=8388608|LocationCount=3|X1=875|Y1=455|X2=915|Y2=455|X3=915|Y3=445
|RECORD=27|IndexInSheet=311|OwnerPartId=-1|LineWidth=1|Color=8388608|LocationCount=2|X1=780|Y1=415|X2=790|Y2=415
|RECORD=27|IndexInSheet=312|OwnerPartId=-1|LineWidth=1|Color=8388608|LocationCount=2|X1=780|Y1=405|X2=790|Y2=405
|RECORD=27|IndexInSheet=313|OwnerPartId=-1|LineWidth=1|Color=8388608|LocationCount=2|X1=780|Y1=395|X2=790|Y2=395
|RECORD=27|IndexInSheet=314|OwnerPartId=-1|LineWidth=1|Color=8388608|LocationCount=2|X1=780|Y1=385|X2=790|Y2=385
|RECORD=27|IndexInSheet=315|OwnerPartId=-1|LineWidth=1|Color=8388608|LocationCount=3|X1=840|Y1=405|X2=820|Y2=405|X3=820|Y3=375
|RECORD=27|IndexInSheet=316|OwnerPartId=-1|LineWidth=1|Color=8388608|LocationCount=7|X1=620|Y1=455|X2=615|Y2=455|X3=615|Y3=490|X4=800|Y4=490|X5=800|Y5=420|X6=895|Y6=420|X7=895|Y7=405
|RECORD=27|IndexInSheet=317|OwnerPartId=-1|LineWidth=1|Color=8388608|LocationCount=3|X1=1210|Y1=415|X2=1130|Y2=415|X3=1130|Y3=465
|RECORD=27|IndexInSheet=318|OwnerPartId=-1|LineWidth=1|Color=8388608|LocationCount=3|X1=1210|Y1=425|X2=1195|Y2=425|X3=1195|Y3=465
|RECORD=27|IndexInSheet=319|OwnerPartId=-1|LineWidth=1|Color=8388608|LocationCount=3|X1=960|Y1=470|X2=960|Y2=445|X3=985|Y3=445
|RECORD=27|IndexInSheet=320|OwnerPartId=-1|LineWidth=1|Color=8388608|LocationCount=3|X1=1025|Y1=445|X2=1075|Y2=445|X3=1075|Y3=470
|RECORD=27|IndexInSheet=321|OwnerPartId=-1|LineWidth=1|Color=8388608|LocationCount=2|X1=1120|Y1=355|X2=1120|Y2=380
|RECORD=27|IndexInSheet=322|OwnerPartId=-1|LineWidth=1|Color=8388608|LocationCount=2|X1=1120|Y1=315|X2=1120|Y2=335
|RECORD=27|IndexInSheet=323|OwnerPartId=-1|LineWidth=1|Color=8388608|LocationCount=2|X1=1170|Y1=355|X2=1170|Y2=380
|RECORD=27|IndexInSheet=324|OwnerPartId=-1|LineWidth=1|Color=8388608|LocationCount=2|X1=1170|Y1=315|X2=1170|Y2=335
|RECORD=27|IndexInSheet=325|OwnerPartId=-1|LineWidth=1|Color=8388608|LocationCount=2|X1=830|Y1=365|X2=830|Y2=375
|RECORD=27|IndexInSheet=326|OwnerPartId=-1|LineWidth=1|Color=8388608|LocationCount=2|X1=830|Y1=325|X2=830|Y2=315
|RECORD=27|IndexInSheet=327|OwnerPartId=-1|LineWidth=1|Color=8388608|LocationCount=2|X1=830|Y1=275|X2=830|Y2=295
|RECORD=27|IndexInSheet=328|OwnerPartId=-1|LineWidth=1|Color=8388608|LocationCount=2|X1=475|Y1=290|X2=475|Y2=335
|RECORD=27|IndexInSheet=329|OwnerPartId=-1|LineWidth=1|Color=8388608|LocationCount=4|X1=515|Y1=290|X2=515|Y2=325|X3=505|Y3=325|X4=505|Y4=335
|RECORD=27|IndexInSheet=330|OwnerPartId=-1|LineWidth=1|Color=8388608|LocationCount=2|X1=475|Y1=270|X2=475|Y2=250
|RECORD=27|IndexInSheet=331|OwnerPartId=-1|LineWidth=1|Color=8388608|LocationCount=2|X1=515|Y1=270|X2=515|Y2=250
|RECORD=27|IndexInSheet=332|OwnerPartId=-1|LineWidth=1|Color=8388608|LocationCount=2|X1=925|Y1=345|X2=925|Y2=375
|RECORD=27|IndexInSheet=333|OwnerPartId=-1|LineWidth=1|Color=8388608|LocationCount=2|X1=925|Y1=290|X2=925|Y2=305
|RECORD=27|IndexInSheet=334|OwnerPartId=-1|LineWidth=1|Color=8388608|LocationCount=2|X1=620|Y1=435|X2=510|Y2=435
|RECORD=27|IndexInSheet=335|OwnerPartId=-1|LineWidth=1|Color=8388608|LocationCount=3|X1=925|Y1=270|X2=925|Y2=225|X3=815|Y3=225
|RECORD=27|IndexInSheet=336|OwnerPartId=-1|LineWidth=1|Color=8388608|LocationCount=4|X1=980|Y1=315|X2=980|Y2=345|X3=1015|Y3=345|X4=1015|Y4=330
|RECORD=27|IndexInSheet=337|OwnerPartId=-1|LineWidth=1|Color=8388608|LocationCount=4|X1=1015|Y1=290|X2=1015|Y2=260|X3=980|Y3=260|X4=980|Y4=295
|RECORD=27|IndexInSheet=338|OwnerPartId=-1|LineWidth=1|Color=8388608|LocationCount=3|X1=925|Y1=225|X2=1015|Y2=225|X3=1015|Y3=260
|RECORD=27|IndexInSheet=339|OwnerPartId=-1|LineWidth=1|Color=8388608|LocationCount=3|X1=975|Y1=375|X2=1015|Y2=375|X3=1015|Y3=345
|RECORD=27|IndexInSheet=340|OwnerPartId=-1|LineWidth=1|Color=8388608|LocationCount=2|X1=1015|Y1=215|X2=1015|Y2=225
|RECORD=27|IndexInSheet=341|OwnerPartId=-1|LineWidth=1|Color=8388608|LocationCount=2|X1=1015|Y1=170|X2=1015|Y2=175
|RECORD=27|IndexInSheet=342|OwnerPartId=-1|LineWidth=1|Color=8388608|LocationCount=2|X1=1015|Y1=375|X2=1015|Y2=390
|RECORD=27|IndexInSheet=343|OwnerPartId=-1|LineWidth=1|Color=8388608|LocationCount=4|X1=485|Y1=335|X2=475|Y2=335|X3=425|Y3=335|X4=425|Y4=290
|RECORD=27|IndexInSheet=344|OwnerPartId=-1|LineWidth=1|Color=8388608|LocationCount=3|X1=620|Y1=415|X2=610|Y2=415|X3=485|Y3=415
|RECORD=27|IndexInSheet=345|OwnerPartId=-1|LineWidth=1|Color=8388608|LocationCount=6|X1=485|Y1=535|X2=485|Y2=525|X3=485|Y3=415|X4=485|Y4=335|X5=505|Y5=335|X6=515|Y6=335
|RECORD=27|IndexInSheet=346|OwnerPartId=-1|LineWidth=1|Color=8388608|LocationCount=5|X1=425|Y1=270|X2=425|Y2=250|X3=475|Y3=250|X4=515|Y4=250|X5=605|Y5=250
|RECORD=27|IndexInSheet=347|OwnerPartId=-1|LineWidth=1|Color=8388608|LocationCount=3|X1=555|Y1=335|X2=565|Y2=335|X3=620|Y3=335
|RECORD=27|IndexInSheet=348|OwnerPartId=-1|LineWidth=1|Color=8388608|LocationCount=5|X1=620|Y1=315|X2=605|Y2=315|X3=605|Y3=270|X4=605|Y4=250|X5=605|Y5=230
|RECORD=27|IndexInSheet=349|OwnerPartId=-1|LineWidth=1|Color=8388608|LocationCount=8|X1=620|Y1=355|X2=610|Y2=355|X3=610|Y3=365|X4=610|Y4=375|X5=610|Y5=385|X6=610|Y6=395|X7=610|Y7=405|X8=610|Y8=415
|RECORD=27|IndexInSheet=350|OwnerPartId=-1|LineWidth=1|Color=8388608|LocationCount=6|X1=780|Y1=375|X2=790|Y2=375|X3=820|Y3=375|X4=830|Y4=375|X5=925|Y5=375|X6=935|Y6=375
|RECORD=27|IndexInSheet=351|OwnerPartId=-1|LineWidth=1|Color=8388608|LocationCount=7|X1=780|Y1=425|X2=790|Y2=425|X3=790|Y3=415|X4=790|Y4=405|X5=790|Y5=395|X6=790|Y6=385|X7=790|Y7=375
|RECORD=27|IndexInSheet=352|OwnerPartId=-1|LineWidth=1|Color=8388608|LocationCount=4|X1=880|Y1=405|X2=895|Y2=405|X3=915|Y3=405|X4=915|Y4=425
|RECORD=27|IndexInSheet=353|OwnerPartId=-1|LineWidth=1|Color=8388608|LocationCount=9|X1=1210|Y1=405|X2=1200|Y2=405|X3=1200|Y3=395|X4=1200|Y4=385|X5=1200|Y5=375|X6=1200|Y6=365|X7=1200|Y7=355|X8=1200|Y8=335|X9=1200|Y9=315
|RECORD=27|IndexInSheet=354|OwnerPartId=-1|LineWidth=1|Color=8388608|LocationCount=2|X1=1015|Y1=375|X2=1030|Y2=375
|RECORD=27|IndexInSheet=355|OwnerPartId=-1|LineWidth=1|Color=8388608|LocationCount=4|X1=1070|Y1=375|X2=1080|Y2=375|X3=1085|Y3=375|X4=1085|Y4=390
|RECORD=27|IndexInSheet=356|OwnerPartId=-1|LineWidth=1|Color=8388608|LocationCount=3|X1=1080|Y1=235|X2=1080|Y2=265|X3=1080|Y3=375
|RECORD=27|IndexInSheet=357|OwnerPartId=-1|LineWidth=1|Color=8388608|LocationCount=7|X1=1295|Y1=235|X2=1295|Y2=265|X3=1255|Y3=265|X4=1210|Y4=265|X5=1165|Y5=265|X6=1125|Y6=265|X7=1080|Y7=265
|RECORD=27|IndexInSheet=358|OwnerPartId=-1|LineWidth=1|Color=8388608|LocationCount=2|X1=1125|Y1=235|X2=1125|Y2=265
|RECORD=27|IndexInSheet=359|OwnerPartId=-1|LineWidth=1|Color=8388608|LocationCount=2|X1=1165|Y1=235|X2=1165|Y2=265
|RECORD=27|IndexInSheet=360|OwnerPartId=-1|LineWidth=1|Color=8388608|LocationCount=2|X1=1210|Y1=235|X2=1210|Y2=265
|RECORD=27|IndexInSheet=361|OwnerPartId=-1|LineWidth=1|Color=8388608|LocationCount=2|X1=1255|Y1=235|X2=1255|Y2=265
|RECORD=27|IndexInSheet=362|OwnerPartId=-1|LineWidth=1|Color=8388608|LocationCount=3|X1=1080|Y1=215|X2=1080|Y2=185|X3=1080|Y3=175
|RECORD=27|IndexInSheet=363|OwnerPartId=-1|LineWidth=1|Color=8388608|LocationCount=7|X1=1295|Y1=215|X2=1295|Y2=185|X3=1255|Y3=185|X4=1210|Y4=185|X5=1165|Y5=185|X6=1125|Y6=185|X7=1080|Y7=185
|RECORD=27|IndexInSheet=364|OwnerPartId=-1|LineWidth=1|Color=8388608|LocationCount=2|X1=1125|Y1=215|X2=1125|Y2=185
|RECORD=27|IndexInSheet=365|OwnerPartId=-1|LineWidth=1|Color=8388608|LocationCount=2|X1=1165|Y1=215|X2=1165|Y2=185
|RECORD=27|IndexInSheet=366|OwnerPartId=-1|LineWidth=1|Color=8388608|LocationCount=2|X1=1210|Y1=215|X2=1210|Y2=185
|RECORD=27|IndexInSheet=367|OwnerPartId=-1|LineWidth=1|Color=8388608|LocationCount=2|X1=1255|Y1=215|X2=1255|Y2=185
|RECORD=27|IndexInSheet=368|OwnerPartId=-1|LineWidth=1|Color=8388608|LocationCount=2|X1=550|Y1=145|X2=550|Y2=165
|RECORD=27|IndexInSheet=369|OwnerPartId=-1|LineWidth=1|Color=8388608|LocationCount=2|X1=590|Y1=150|X2=590|Y2=165
|RECORD=27|IndexInSheet=370|OwnerPartId=-1|LineWidth=1|Color=8388608|LocationCount=2|X1=590|Y1=115|X2=590|Y2=120
|RECORD=27|IndexInSheet=371|OwnerPartId=-1|LineWidth=1|Color=8388608|LocationCount=2|X1=550|Y1=115|X2=550|Y2=125
|RECORD=27|IndexInSheet=372|OwnerPartId=-1|LineWidth=1|Color=8388608|LocationCount=3|X1=690|Y1=105|X2=670|Y2=105|X3=670|Y3=130
|RECORD=27|IndexInSheet=373|OwnerPartId=-1|LineWidth=1|Color=8388608|LocationCount=3|X1=690|Y1=95|X2=630|Y2=95|X3=630|Y3=130
|RECORD=27|IndexInSheet=374|OwnerPartId=-1|LineWidth=1|Color=8388608|LocationCount=3|X1=820|Y1=95|X2=830|Y2=95|X3=830|Y3=90
|RECORD=27|IndexInSheet=375|OwnerPartId=-1|LineWidth=1|Color=8388608|LocationCount=2|X1=820|Y1=165|X2=865|Y2=165
|RECORD=27|IndexInSheet=376|OwnerPartId=-1|LineWidth=1|Color=8388608|LocationCount=2|X1=820|Y1=145|X2=865|Y2=145
|RECORD=27|IndexInSheet=377|OwnerPartId=-1|LineWidth=1|Color=8388608|LocationCount=2|X1=820|Y1=125|X2=840|Y2=125
|RECORD=27|IndexInSheet=378|OwnerPartId=-1|LineWidth=1|Color=8388608|LocationCount=2|X1=840|Y1=115|X2=820|Y2=115
|RECORD=27|IndexInSheet=379|OwnerPartId=-1|LineWidth=1|Color=8388608|LocationCount=4|X1=550|Y1=185|X2=550|Y2=165|X3=590|Y3=165|X4=690|Y4=165
|RECORD=17|IndexInSheet=380|OwnerPartId=-1|ShowNetName=T|Location.X=1085|Location.Y=390|Orientation=1|Color=128|FontID=1|Text=+3.3V
|RECORD=27|IndexInSheet=381|OwnerPartId=-1|LineWidth=1|Color=8388608|LocationCount=4|X1=880|Y1=125|X2=920|Y2=125|X3=920|Y3=95|X4=830|Y4=95
|RECORD=27|IndexInSheet=382|OwnerPartId=-1|LineWidth=1|Color=8388608|LocationCount=3|X1=880|Y1=115|X2=930|Y2=115|X3=930|Y3=180
|RECORD=17|IndexInSheet=383|OwnerPartId=-1|Style=4|ShowNetName=T|Location.X=1540|Location.Y=255|Orientation=3|Color=128|FontID=1|Text=GND
|RECORD=27|IndexInSheet=384|OwnerPartId=-1|LineWidth=1|Color=8388608|LocationCount=2|X1=1540|Y1=275|X2=1540|Y2=255
|RECORD=27|IndexInSheet=385|OwnerPartId=-1|LineWidth=1|Color=8388608|LocationCount=2|X1=1540|Y1=365|X2=1540|Y2=345
|RECORD=27|IndexInSheet=386|OwnerPartId=-1|LineWidth=1|Color=8388608|LocationCount=2|X1=1540|Y1=425|X2=1540|Y2=435
|RECORD=17|IndexInSheet=387|OwnerPartId=-1|ShowNetName=T|Location.X=895|Location.Y=650|Orientation=1|Color=128|FontID=1|Text=+5.0V
|RECORD=17|IndexInSheet=388|OwnerPartId=-1|ShowNetName=T|Location.X=1350|Location.Y=910|Orientation=1|Color=128|FontID=1|Text=+5.0V
|RECORD=17|IndexInSheet=389|OwnerPartId=-1|ShowNetName=T|Location.X=1540|Location.Y=435|Orientation=1|Color=128|FontID=1|Text=+5.0V
|RECORD=17|IndexInSheet=390|OwnerPartId=-1|ShowNetName=T|Location.X=630|Location.Y=130|Orientation=1|Color=128|FontID=1|Text=+3.3V
|RECORD=17|IndexInSheet=391|OwnerPartId=-1|Style=4|ShowNetName=T|Location.X=1400|Location.Y=835|Orientation=3|Color=128|FontID=1|Text=GND
|RECORD=27|IndexInSheet=392|OwnerPartId=-1|LineWidth=1|Color=8388608|LocationCount=4|X1=750|Y1=855|X2=740|Y2=855|X3=690|Y3=855|X4=690|Y4=810
|RECORD=27|IndexInSheet=393|OwnerPartId=-1|LineWidth=1|Color=8388608|LocationCount=3|X1=885|Y1=935|X2=875|Y2=935|X3=750|Y3=935
|RECORD=27|IndexInSheet=394|OwnerPartId=-1|LineWidth=1|Color=8388608|LocationCount=6|X1=750|Y1=1055|X2=750|Y2=1045|X3=750|Y3=935|X4=750|Y4=855|X5=770|Y5=855|X6=780|Y6=855
|RECORD=27|IndexInSheet=395|OwnerPartId=-1|LineWidth=1|Color=8388608|LocationCount=5|X1=690|Y1=790|X2=690|Y2=770|X3=740|Y3=770|X4=780|Y4=770|X5=870|Y5=770
|RECORD=27|IndexInSheet=396|OwnerPartId=-1|LineWidth=1|Color=8388608|LocationCount=3|X1=820|Y1=855|X2=830|Y2=855|X3=885|Y3=855
|RECORD=27|IndexInSheet=397|OwnerPartId=-1|LineWidth=1|Color=8388608|LocationCount=4|X1=815|Y1=705|X2=815|Y2=685|X3=855|Y3=685|X4=955|Y4=685
|RECORD=27|IndexInSheet=398|OwnerPartId=-1|LineWidth=1|Color=8388608|LocationCount=5|X1=885|Y1=835|X2=870|Y2=835|X3=870|Y3=790|X4=870|Y4=770|X5=870|Y5=750
|RECORD=27|IndexInSheet=399|OwnerPartId=-1|LineWidth=1|Color=8388608|LocationCount=8|X1=885|Y1=875|X2=875|Y2=875|X3=875|Y3=885|X4=875|Y4=895|X5=875|Y5=905|X6=875|Y6=915|X7=875|Y7=925|X8=875|Y8=935
|RECORD=27|IndexInSheet=400|OwnerPartId=-1|LineWidth=1|Color=8388608|LocationCount=6|X1=1045|Y1=895|X2=1055|Y2=895|X3=1085|Y3=895|X4=1095|Y4=895|X5=1190|Y5=895|X6=1200|Y6=895
|RECORD=27|IndexInSheet=401|OwnerPartId=-1|LineWidth=1|Color=8388608|LocationCount=7|X1=1045|Y1=945|X2=1055|Y2=945|X3=1055|Y3=935|X4=1055|Y4=925|X5=1055|Y5=915|X6=1055|Y6=905|X7=1055|Y7=895
|RECORD=27|IndexInSheet=402|OwnerPartId=-1|LineWidth=1|Color=8388608|LocationCount=4|X1=1145|Y1=925|X2=1160|Y2=925|X3=1180|Y3=925|X4=1180|Y4=945
|RECORD=27|IndexInSheet=403|OwnerPartId=-1|LineWidth=1|Color=8388608|LocationCount=4|X1=1335|Y1=895|X2=1345|Y2=895|X3=1350|Y3=895|X4=1350|Y4=910
|RECORD=27|IndexInSheet=404|OwnerPartId=-1|LineWidth=1|Color=8388608|LocationCount=7|X1=1560|Y1=735|X2=1560|Y2=705|X3=1520|Y3=705|X4=1475|Y4=705|X5=1430|Y5=705|X6=1390|Y6=705|X7=1345|Y7=705
|RECORD=27|IndexInSheet=405|OwnerPartId=-1|LineWidth=1|Color=8388608|LocationCount=7|X1=1560|Y1=755|X2=1560|Y2=785|X3=1520|Y3=785|X4=1475|Y4=785|X5=1430|Y5=785|X6=1390|Y6=785|X7=1345|Y7=785
|RECORD=27|IndexInSheet=406|OwnerPartId=-1|LineWidth=1|Color=8388608|LocationCount=3|X1=1345|Y1=735|X2=1345|Y2=705|X3=1345|Y3=695
|RECORD=27|IndexInSheet=407|OwnerPartId=-1|LineWidth=1|Color=8388608|LocationCount=3|X1=1345|Y1=755|X2=1345|Y2=785|X3=1345|Y3=895
|RECORD=27|IndexInSheet=408|OwnerPartId=-1|LineWidth=1|Color=8388608|LocationCount=9|X1=1540|Y1=925|X2=1530|Y2=925|X3=1530|Y3=915|X4=1530|Y4=905|X5=1530|Y5=895|X6=1530|Y6=885|X7=1530|Y7=875|X8=1530|Y8=855|X9=1530|Y9=835
|RECORD=1|LibReference=1d6ec82d83fb6aee721767c19dac4b9|ComponentDescription=DIODE SCHOTTKY 40V 350MA SOD323|PartCount=2|DisplayModeCount=1|IndexInSheet=409|OwnerPartId=-1|Location.X=1250|Location.Y=1040|Orientation=2|CurrentPartId=1|LibraryPath=*|SourceLibraryName=Altium Content Vault|TargetFileName=*|AreaColor=11599871|Color=128|PartIDLocked=T|DesignItemId=CMP-12790-000048-1|AllPinCount=2
|RECORD=2|OwnerIndex=4150|OwnerPartId=1|Electrical=4|PinConglomerate=48|PinLength=20|Location.X=1230|Location.Y=1040|Name=A|Designator=2|PinPropagationDelay=0.000000E+000
|RECORD=2|OwnerIndex=4150|OwnerPartId=1|Electrical=4|PinConglomerate=50|PinLength=20|Location.X=1210|Location.Y=1040|Name=C|Designator=1|PinPropagationDelay=0.000000E+000
|RECORD=13|OwnerIndex=4150|IsNotAccesible=T|IndexInSheet=2|OwnerPartId=1|Location.X=1230|Location.Y=1030|Corner.X=1230|Corner.Y=1050|LineWidth=1|Color=16711680
|RECORD=13|OwnerIndex=4150|IsNotAccesible=T|IndexInSheet=3|OwnerPartId=1|Location.X=1210|Location.Y=1030|Corner.X=1210|Corner.Y=1050|LineWidth=1|Color=16711680
|RECORD=13|OwnerIndex=4150|IsNotAccesible=T|IndexInSheet=4|OwnerPartId=1|Location.X=1230|Location.Y=1030|Corner.X=1210|Corner.Y=1040|LineWidth=1|Color=16711680
|RECORD=13|OwnerIndex=4150|IsNotAccesible=T|IndexInSheet=5|OwnerPartId=1|Location.X=1230|Location.Y=1050|Corner.X=1210|Corner.Y=1040|LineWidth=1|Color=16711680
|RECORD=13|OwnerIndex=4150|IsNotAccesible=T|IndexInSheet=6|OwnerPartId=1|Location.X=1210|Location.Y=1030|Corner.X=1213|Corner.Y=1030|LineWidth=1|Color=16711680
|RECORD=13|OwnerIndex=4150|IsNotAccesible=T|IndexInSheet=7|OwnerPartId=1|Location.X=1207|Location.Y=1050|Corner.X=1207|Corner.Y=1047|LineWidth=1|Color=16711680
|RECORD=13|OwnerIndex=4150|IsNotAccesible=T|IndexInSheet=8|OwnerPartId=1|Location.X=1213|Location.Y=1030|Corner.X=1213|Corner.Y=1033|LineWidth=1|Color=16711680
|RECORD=13|OwnerIndex=4150|IsNotAccesible=T|IndexInSheet=9|OwnerPartId=1|Location.X=1210|Location.Y=1050|Corner.X=1207|Corner.Y=1050|LineWidth=1|Color=16711680
|RECORD=13|OwnerIndex=4150|IsNotAccesible=T|IndexInSheet=10|OwnerPartId=1|Location.X=1230|Location.Y=1040|Corner.X=1233|Corner.Y=1040|LineWidth=1|Color=16711680
|RECORD=13|OwnerIndex=4150|IsNotAccesible=T|IndexInSheet=11|OwnerPartId=1|Location.X=1210|Location.Y=1040|Corner.X=1207|Corner.Y=1040|LineWidth=1|Color=16711680
|RECORD=41|OwnerIndex=4150|IndexInSheet=12|OwnerPartId=-1|Location.X=1188|Location.Y=1051|Color=8388608|FontID=7|IsHidden=T|Text=https://www.diodes.com/assets/Datasheets/ds30101.pdf|Name=ComponentLink2URL
|RECORD=41|OwnerIndex=4150|IndexInSheet=13|OwnerPartId=-1|Location.X=1188|Location.Y=1051|Color=8388608|FontID=1|IsHidden=T|Text=SOD250130X110-2|Name=Ipc Land Pattern Name
|RECORD=41|OwnerIndex=4150|IndexInSheet=14|OwnerPartId=-1|Location.X=1188|Location.Y=1051|Color=8388608|FontID=7|IsHidden=T|Text=https://octopart.com/sd103aws-7-f-diodes+inc.-55389602|Name=Octopart
|RECORD=41|OwnerIndex=4150|IndexInSheet=15|OwnerPartId=-1|Location.X=1188|Location.Y=1051|Color=8388608|FontID=1|IsHidden=T|Text=1.5A|Name=Max Surge Forward Current
|RECORD=41|OwnerIndex=4150|IndexInSheet=16|OwnerPartId=-1|Location.X=1188|Location.Y=1051|Color=8388608|FontID=1|IsHidden=T|Text=350mA|Name=Forward Current
|RECORD=41|OwnerIndex=4150|IndexInSheet=17|OwnerPartId=-1|Location.X=1188|Location.Y=1051|Color=8388608|FontID=1|IsHidden=T|Text=Discrete Semiconductors|Name=Device Class L1
|RECORD=41|OwnerIndex=4150|IndexInSheet=18|OwnerPartId=-1|Location.X=1188|Location.Y=1051|Color=8388608|FontID=1|IsHidden=T|Text=Yes|Name=Lead Free
|RECORD=41|OwnerIndex=4150|IndexInSheet=19|OwnerPartId=-1|Location.X=1188|Location.Y=1051|Color=8388608|FontID=1|IsHidden=T|Text=35pF|Name=Capacitance
|RECORD=41|OwnerIndex=4150|IndexInSheet=20|OwnerPartId=-1|Location.X=1188|Location.Y=1051|Color=8388608|FontID=1|IsHidden=T|Text=5uA|Name=Peak Reverse Current
|RECORD=41|OwnerIndex=4150|IndexInSheet=21|OwnerPartId=-1|Location.X=1188|Location.Y=1051|Color=8388608|FontID=1|IsHidden=T|Text=Diodes Inc.|Name=Manufacturer
|RECORD=41|OwnerIndex=4150|IndexInSheet=22|OwnerPartId=-1|Location.X=1188|Location.Y=1051|Color=8388608|FontID=1|IsHidden=T|Text=0.05mm|Name=Standoff Height
|RECORD=41|OwnerIndex=4150|IndexInSheet=23|OwnerPartId=-1|Location.X=1188|Location.Y=1051|Color=8388608|FontID=1|IsHidden=T|Text=Datasheet|Name=ComponentLink2Description
|RECORD=41|OwnerIndex=4150|IndexInSheet=24|OwnerPartId=-1|Location.X=1188|Location.Y=1051|Color=8388608|FontID=1|IsHidden=T|Text=+125°C|Name=Max Junction Temp
|RECORD=41|OwnerIndex=4150|IndexInSheet=25|OwnerPartId=-1|Location.X=1188|Location.Y=1051|Color=8388608|FontID=1|IsHidden=T|Text=TRUE|Name=RoHS
|RECORD=41|OwnerIndex=4150|IndexInSheet=26|OwnerPartId=-1|Location.X=1188|Location.Y=1051|Color=8388608|FontID=1|IsHidden=T|Text=-65°C to +125°C|Name=Temperature
|RECORD=41|OwnerIndex=4150|IndexInSheet=27|OwnerPartId=-1|Location.X=1188|Location.Y=1051|Color=8388608|FontID=1|IsHidden=T|Text=-65°C|Name=Temperature Range Low
|RECORD=41|OwnerIndex=4150|IndexInSheet=28|OwnerPartId=-1|Location.X=1188|Location.Y=1051|Color=8388608|FontID=1|IsHidden=T|Text=Diode|Name=Category
|RECORD=41|OwnerIndex=4150|IndexInSheet=29|OwnerPartId=-1|Location.X=1188|Location.Y=1051|Color=8388608|FontID=1|IsHidden=T|Text=SOD323|Name=Package
|RECORD=41|OwnerIndex=4150|IndexInSheet=30|OwnerPartId=-1|Location.X=1188|Location.Y=1051|Color=8388608|FontID=1|IsHidden=T|Text=35pF|Name=Value
|RECORD=41|OwnerIndex=4150|IndexInSheet=31|OwnerPartId=-1|Location.X=1188|Location.Y=1051|Color=8388608|FontID=1|IsHidden=T|Text=Grade 1|Name=Automotive Grade
|RECORD=41|OwnerIndex=4150|IndexInSheet=32|OwnerPartId=-1|Location.X=1188|Location.Y=1051|Color=8388608|FontID=1|IsHidden=T|Text=DIODE SCHOTTKY 40V 350MA SOD323|Name=Digikey Description
|RECORD=41|OwnerIndex=4150|IndexInSheet=33|OwnerPartId=-1|Location.X=1188|Location.Y=1051|Color=8388608|FontID=1|IsHidden=T|Text=Yes|Name=Automotive
|RECORD=41|OwnerIndex=4150|IndexInSheet=34|OwnerPartId=-1|Location.X=1188|Location.Y=1051|Color=8388608|FontID=1|IsHidden=T|Text=Diodes|Name=Device Class L2
|RECORD=41|OwnerIndex=4150|IndexInSheet=35|OwnerPartId=-1|Location.X=1188|Location.Y=1051|Color=8388608|FontID=1|IsHidden=T|Text=Schottky Diodes & Rectifiers 40V 200mW|Name=Mouser Description
|RECORD=41|OwnerIndex=4150|IndexInSheet=36|OwnerPartId=-1|Location.X=1188|Location.Y=1051|Color=8388608|FontID=1|IsHidden=T|Text=SD103AWS-7-F|Name=Manufacturer Part Number
|RECORD=41|OwnerIndex=4150|IndexInSheet=37|OwnerPartId=-1|Location.X=1188|Location.Y=1051|Color=8388608|FontID=1|IsHidden=T|Text=Schottky Diodes|Name=Device Class L3
|RECORD=41|OwnerIndex=4150|IndexInSheet=38|OwnerPartId=-1|Location.X=1188|Location.Y=1051|Color=8388608|FontID=1|IsHidden=T|Text=40V|Name=Max Repetitive Reverse Voltage
|RECORD=41|OwnerIndex=4150|IndexInSheet=39|OwnerPartId=-1|Location.X=1188|Location.Y=1051|Color=8388608|FontID=7|IsHidden=T|Text=https://www.diodes.com/assets/Package-Files/SOD323.pdf|Name=Footprint Url
|RECORD=41|OwnerIndex=4150|IndexInSheet=40|OwnerPartId=-1|Location.X=1188|Location.Y=1051|Color=8388608|FontID=1|IsHidden=T|Text=40V|Name=Reverse Voltage
|RECORD=41|OwnerIndex=4150|IndexInSheet=41|OwnerPartId=-1|Location.X=1188|Location.Y=1051|Color=8388608|FontID=1|IsHidden=T|Text=+125°C|Name=Temperature Range High
|RECORD=41|OwnerIndex=4150|IndexInSheet=42|OwnerPartId=-1|Location.X=1188|Location.Y=1051|Color=8388608|FontID=1|IsHidden=T|Text=1.2mm|Name=Height
|RECORD=34|OwnerIndex=4150|IndexInSheet=-1|OwnerPartId=-1|Location.X=1206|Location.Y=1051|Color=8388608|FontID=1|Text=D21|Name=Designator|ReadOnlyState=1
|RECORD=41|OwnerIndex=4150|IndexInSheet=-1|OwnerPartId=1|Location.X=1206|Location.Y=1019|Color=8388608|FontID=1|Text=SD103AWS-7-F|Name=Comment
|RECORD=44|OwnerIndex=4150
|RECORD=45|OwnerIndex=4198|IndexInSheet=-1|UseComponentLibrary=T|ModelName=FP-SOD323-MFG|ModelType=PCBLIB|DatafileCount=1|ModelDatafileEntity0=FP-SOD323-MFG|ModelDatafileKind0=PCBLib|IsCurrent=T|DatalinksLocked=T|DatabaseDatalinksLocked=T
|RECORD=46|OwnerIndex=4199
|RECORD=48|OwnerIndex=4199
|RECORD=45|OwnerIndex=4198|IndexInSheet=-1|UseComponentLibrary=T|ModelName=FP-SOD323-IPC_C|ModelType=PCBLIB|DatafileCount=1|ModelDatafileEntity0=FP-SOD323-IPC_C|ModelDatafileKind0=PCBLib|DatalinksLocked=T|DatabaseDatalinksLocked=T
|RECORD=46|OwnerIndex=4202
|RECORD=48|OwnerIndex=4202
|RECORD=45|OwnerIndex=4198|IndexInSheet=-1|UseComponentLibrary=T|ModelName=FP-SOD323-IPC_B|ModelType=PCBLIB|DatafileCount=1|ModelDatafileEntity0=FP-SOD323-IPC_B|ModelDatafileKind0=PCBLib|DatalinksLocked=T|DatabaseDatalinksLocked=T
|RECORD=46|OwnerIndex=4205
|RECORD=48|OwnerIndex=4205
|RECORD=45|OwnerIndex=4198|IndexInSheet=-1|UseComponentLibrary=T|ModelName=FP-SOD323-IPC_A|ModelType=PCBLIB|DatafileCount=1|ModelDatafileEntity0=FP-SOD323-IPC_A|ModelDatafileKind0=PCBLib|DatalinksLocked=T|DatabaseDatalinksLocked=T
|RECORD=46|OwnerIndex=4208
|RECORD=48|OwnerIndex=4208
|RECORD=27|IndexInSheet=410|OwnerPartId=-1|LineWidth=1|Color=8388608|LocationCount=3|X1=1180|Y1=975|X2=1180|Y2=1040|X3=1190|Y3=1040
|RECORD=17|IndexInSheet=411|OwnerPartId=-1|ShowNetName=T|Location.X=1280|Location.Y=1045|Orientation=1|Color=128|FontID=1|Text=P5V_PVDD
|RECORD=27|IndexInSheet=412|OwnerPartId=-1|LineWidth=1|Color=8388608|LocationCount=3|X1=1250|Y1=1040|X2=1280|Y2=1040|X3=1280|Y3=1045
|RECORD=1|LibReference=1d6ec82d83fb6aee721767c19dac4b9|ComponentDescription=DIODE SCHOTTKY 40V 350MA SOD323|PartCount=2|DisplayModeCount=1|IndexInSheet=413|OwnerPartId=-1|Location.X=985|Location.Y=520|Orientation=2|CurrentPartId=1|LibraryPath=*|SourceLibraryName=Altium Content Vault|TargetFileName=*|AreaColor=11599871|Color=128|PartIDLocked=T|DesignItemId=CMP-12790-000048-1|AllPinCount=2
|RECORD=2|OwnerIndex=4214|OwnerPartId=1|Electrical=4|PinConglomerate=48|PinLength=20|Location.X=965|Location.Y=520|Name=A|Designator=2|PinPropagationDelay=0.000000E+000
|RECORD=2|OwnerIndex=4214|OwnerPartId=1|Electrical=4|PinConglomerate=50|PinLength=20|Location.X=945|Location.Y=520|Name=C|Designator=1|PinPropagationDelay=0.000000E+000
|RECORD=13|OwnerIndex=4214|IsNotAccesible=T|IndexInSheet=2|OwnerPartId=1|Location.X=965|Location.Y=510|Corner.X=965|Corner.Y=530|LineWidth=1|Color=16711680
|RECORD=13|OwnerIndex=4214|IsNotAccesible=T|IndexInSheet=3|OwnerPartId=1|Location.X=945|Location.Y=510|Corner.X=945|Corner.Y=530|LineWidth=1|Color=16711680
|RECORD=13|OwnerIndex=4214|IsNotAccesible=T|IndexInSheet=4|OwnerPartId=1|Location.X=965|Location.Y=510|Corner.X=945|Corner.Y=520|LineWidth=1|Color=16711680
|RECORD=13|OwnerIndex=4214|IsNotAccesible=T|IndexInSheet=5|OwnerPartId=1|Location.X=965|Location.Y=530|Corner.X=945|Corner.Y=520|LineWidth=1|Color=16711680
|RECORD=13|OwnerIndex=4214|IsNotAccesible=T|IndexInSheet=6|OwnerPartId=1|Location.X=945|Location.Y=510|Corner.X=948|Corner.Y=510|LineWidth=1|Color=16711680
|RECORD=13|OwnerIndex=4214|IsNotAccesible=T|IndexInSheet=7|OwnerPartId=1|Location.X=942|Location.Y=530|Corner.X=942|Corner.Y=527|LineWidth=1|Color=16711680
|RECORD=13|OwnerIndex=4214|IsNotAccesible=T|IndexInSheet=8|OwnerPartId=1|Location.X=948|Location.Y=510|Corner.X=948|Corner.Y=513|LineWidth=1|Color=16711680
|RECORD=13|OwnerIndex=4214|IsNotAccesible=T|IndexInSheet=9|OwnerPartId=1|Location.X=945|Location.Y=530|Corner.X=942|Corner.Y=530|LineWidth=1|Color=16711680
|RECORD=13|OwnerIndex=4214|IsNotAccesible=T|IndexInSheet=10|OwnerPartId=1|Location.X=965|Location.Y=520|Corner.X=968|Corner.Y=520|LineWidth=1|Color=16711680
|RECORD=13|OwnerIndex=4214|IsNotAccesible=T|IndexInSheet=11|OwnerPartId=1|Location.X=945|Location.Y=520|Corner.X=942|Corner.Y=520|LineWidth=1|Color=16711680
|RECORD=41|OwnerIndex=4214|IndexInSheet=12|OwnerPartId=-1|Location.X=923|Location.Y=531|Color=8388608|FontID=7|IsHidden=T|Text=https://www.diodes.com/assets/Datasheets/ds30101.pdf|Name=ComponentLink2URL
|RECORD=41|OwnerIndex=4214|IndexInSheet=13|OwnerPartId=-1|Location.X=923|Location.Y=531|Color=8388608|FontID=1|IsHidden=T|Text=SOD250130X110-2|Name=Ipc Land Pattern Name
|RECORD=41|OwnerIndex=4214|IndexInSheet=14|OwnerPartId=-1|Location.X=923|Location.Y=531|Color=8388608|FontID=7|IsHidden=T|Text=https://octopart.com/sd103aws-7-f-diodes+inc.-55389602|Name=Octopart
|RECORD=41|OwnerIndex=4214|IndexInSheet=15|OwnerPartId=-1|Location.X=923|Location.Y=531|Color=8388608|FontID=1|IsHidden=T|Text=1.5A|Name=Max Surge Forward Current
|RECORD=41|OwnerIndex=4214|IndexInSheet=16|OwnerPartId=-1|Location.X=923|Location.Y=531|Color=8388608|FontID=1|IsHidden=T|Text=350mA|Name=Forward Current
|RECORD=41|OwnerIndex=4214|IndexInSheet=17|OwnerPartId=-1|Location.X=923|Location.Y=531|Color=8388608|FontID=1|IsHidden=T|Text=Discrete Semiconductors|Name=Device Class L1
|RECORD=41|OwnerIndex=4214|IndexInSheet=18|OwnerPartId=-1|Location.X=923|Location.Y=531|Color=8388608|FontID=1|IsHidden=T|Text=Yes|Name=Lead Free
|RECORD=41|OwnerIndex=4214|IndexInSheet=19|OwnerPartId=-1|Location.X=923|Location.Y=531|Color=8388608|FontID=1|IsHidden=T|Text=35pF|Name=Capacitance
|RECORD=41|OwnerIndex=4214|IndexInSheet=20|OwnerPartId=-1|Location.X=923|Location.Y=531|Color=8388608|FontID=1|IsHidden=T|Text=5uA|Name=Peak Reverse Current
|RECORD=41|OwnerIndex=4214|IndexInSheet=21|OwnerPartId=-1|Location.X=923|Location.Y=531|Color=8388608|FontID=1|IsHidden=T|Text=Diodes Inc.|Name=Manufacturer
|RECORD=41|OwnerIndex=4214|IndexInSheet=22|OwnerPartId=-1|Location.X=923|Location.Y=531|Color=8388608|FontID=1|IsHidden=T|Text=0.05mm|Name=Standoff Height
|RECORD=41|OwnerIndex=4214|IndexInSheet=23|OwnerPartId=-1|Location.X=923|Location.Y=531|Color=8388608|FontID=1|IsHidden=T|Text=Datasheet|Name=ComponentLink2Description
|RECORD=41|OwnerIndex=4214|IndexInSheet=24|OwnerPartId=-1|Location.X=923|Location.Y=531|Color=8388608|FontID=1|IsHidden=T|Text=+125°C|Name=Max Junction Temp
|RECORD=41|OwnerIndex=4214|IndexInSheet=25|OwnerPartId=-1|Location.X=923|Location.Y=531|Color=8388608|FontID=1|IsHidden=T|Text=TRUE|Name=RoHS
|RECORD=41|OwnerIndex=4214|IndexInSheet=26|OwnerPartId=-1|Location.X=923|Location.Y=531|Color=8388608|FontID=1|IsHidden=T|Text=-65°C to +125°C|Name=Temperature
|RECORD=41|OwnerIndex=4214|IndexInSheet=27|OwnerPartId=-1|Location.X=923|Location.Y=531|Color=8388608|FontID=1|IsHidden=T|Text=-65°C|Name=Temperature Range Low
|RECORD=41|OwnerIndex=4214|IndexInSheet=28|OwnerPartId=-1|Location.X=923|Location.Y=531|Color=8388608|FontID=1|IsHidden=T|Text=Diode|Name=Category
|RECORD=41|OwnerIndex=4214|IndexInSheet=29|OwnerPartId=-1|Location.X=923|Location.Y=531|Color=8388608|FontID=1|IsHidden=T|Text=SOD323|Name=Package
|RECORD=41|OwnerIndex=4214|IndexInSheet=30|OwnerPartId=-1|Location.X=923|Location.Y=531|Color=8388608|FontID=1|IsHidden=T|Text=35pF|Name=Value
|RECORD=41|OwnerIndex=4214|IndexInSheet=31|OwnerPartId=-1|Location.X=923|Location.Y=531|Color=8388608|FontID=1|IsHidden=T|Text=Grade 1|Name=Automotive Grade
|RECORD=41|OwnerIndex=4214|IndexInSheet=32|OwnerPartId=-1|Location.X=923|Location.Y=531|Color=8388608|FontID=1|IsHidden=T|Text=DIODE SCHOTTKY 40V 350MA SOD323|Name=Digikey Description
|RECORD=41|OwnerIndex=4214|IndexInSheet=33|OwnerPartId=-1|Location.X=923|Location.Y=531|Color=8388608|FontID=1|IsHidden=T|Text=Yes|Name=Automotive
|RECORD=41|OwnerIndex=4214|IndexInSheet=34|OwnerPartId=-1|Location.X=923|Location.Y=531|Color=8388608|FontID=1|IsHidden=T|Text=Diodes|Name=Device Class L2
|RECORD=41|OwnerIndex=4214|IndexInSheet=35|OwnerPartId=-1|Location.X=923|Location.Y=531|Color=8388608|FontID=1|IsHidden=T|Text=Schottky Diodes & Rectifiers 40V 200mW|Name=Mouser Description
|RECORD=41|OwnerIndex=4214|IndexInSheet=36|OwnerPartId=-1|Location.X=923|Location.Y=531|Color=8388608|FontID=1|IsHidden=T|Text=SD103AWS-7-F|Name=Manufacturer Part Number
|RECORD=41|OwnerIndex=4214|IndexInSheet=37|OwnerPartId=-1|Location.X=923|Location.Y=531|Color=8388608|FontID=1|IsHidden=T|Text=Schottky Diodes|Name=Device Class L3
|RECORD=41|OwnerIndex=4214|IndexInSheet=38|OwnerPartId=-1|Location.X=923|Location.Y=531|Color=8388608|FontID=1|IsHidden=T|Text=40V|Name=Max Repetitive Reverse Voltage
|RECORD=41|OwnerIndex=4214|IndexInSheet=39|OwnerPartId=-1|Location.X=923|Location.Y=531|Color=8388608|FontID=7|IsHidden=T|Text=https://www.diodes.com/assets/Package-Files/SOD323.pdf|Name=Footprint Url
|RECORD=41|OwnerIndex=4214|IndexInSheet=40|OwnerPartId=-1|Location.X=923|Location.Y=531|Color=8388608|FontID=1|IsHidden=T|Text=40V|Name=Reverse Voltage
|RECORD=41|OwnerIndex=4214|IndexInSheet=41|OwnerPartId=-1|Location.X=923|Location.Y=531|Color=8388608|FontID=1|IsHidden=T|Text=+125°C|Name=Temperature Range High
|RECORD=41|OwnerIndex=4214|IndexInSheet=42|OwnerPartId=-1|Location.X=923|Location.Y=531|Color=8388608|FontID=1|IsHidden=T|Text=1.2mm|Name=Height
|RECORD=34|OwnerIndex=4214|IndexInSheet=-1|OwnerPartId=-1|Location.X=941|Location.Y=531|Color=8388608|FontID=1|Text=D22|Name=Designator|ReadOnlyState=1
|RECORD=41|OwnerIndex=4214|IndexInSheet=-1|OwnerPartId=1|Location.X=941|Location.Y=499|Color=8388608|FontID=1|Text=SD103AWS-7-F|Name=Comment
|RECORD=44|OwnerIndex=4214
|RECORD=45|OwnerIndex=4262|IndexInSheet=-1|UseComponentLibrary=T|ModelName=FP-SOD323-MFG|ModelType=PCBLIB|DatafileCount=1|ModelDatafileEntity0=FP-SOD323-MFG|ModelDatafileKind0=PCBLib|IsCurrent=T|DatalinksLocked=T|DatabaseDatalinksLocked=T
|RECORD=46|OwnerIndex=4263
|RECORD=48|OwnerIndex=4263
|RECORD=45|OwnerIndex=4262|IndexInSheet=-1|UseComponentLibrary=T|ModelName=FP-SOD323-IPC_C|ModelType=PCBLIB|DatafileCount=1|ModelDatafileEntity0=FP-SOD323-IPC_C|ModelDatafileKind0=PCBLib|DatalinksLocked=T|DatabaseDatalinksLocked=T
|RECORD=46|OwnerIndex=4266
|RECORD=48|OwnerIndex=4266
|RECORD=45|OwnerIndex=4262|IndexInSheet=-1|UseComponentLibrary=T|ModelName=FP-SOD323-IPC_B|ModelType=PCBLIB|DatafileCount=1|ModelDatafileEntity0=FP-SOD323-IPC_B|ModelDatafileKind0=PCBLib|DatalinksLocked=T|DatabaseDatalinksLocked=T
|RECORD=46|OwnerIndex=4269
|RECORD=48|OwnerIndex=4269
|RECORD=45|OwnerIndex=4262|IndexInSheet=-1|UseComponentLibrary=T|ModelName=FP-SOD323-IPC_A|ModelType=PCBLIB|DatafileCount=1|ModelDatafileEntity0=FP-SOD323-IPC_A|ModelDatafileKind0=PCBLib|DatalinksLocked=T|DatabaseDatalinksLocked=T
|RECORD=46|OwnerIndex=4272
|RECORD=48|OwnerIndex=4272
|RECORD=27|IndexInSheet=414|OwnerPartId=-1|LineWidth=1|Color=8388608|LocationCount=3|X1=915|Y1=455|X2=915|Y2=520|X3=925|Y3=520
|RECORD=17|IndexInSheet=415|OwnerPartId=-1|ShowNetName=T|Location.X=1015|Location.Y=525|Orientation=1|Color=128|FontID=1|Text=P3V3_PVDD
|RECORD=27|IndexInSheet=416|OwnerPartId=-1|LineWidth=1|Color=8388608|LocationCount=3|X1=985|Y1=520|X2=1015|Y2=520|X3=1015|Y3=525
|RECORD=1|LibReference=8706943c75ba83719d021d2fdc84c58|ComponentDescription=LED RED DIFFUSED SMD|PartCount=2|DisplayModeCount=1|IndexInSheet=417|OwnerPartId=-1|Location.X=1425|Location.Y=420|Orientation=3|CurrentPartId=1|LibraryPath=*|SourceLibraryName=Altium Content Vault|TargetFileName=*|AreaColor=11599871|Color=128|PartIDLocked=T|DesignItemId=CMP-57192-000012-1|AllPinCount=2
|RECORD=2|OwnerIndex=4278|OwnerPartId=1|Electrical=4|PinConglomerate=49|PinLength=20|Location.X=1425|Location.Y=400|Name=A|Designator=2|PinPropagationDelay=0.000000E+000
|RECORD=2|OwnerIndex=4278|OwnerPartId=1|Electrical=4|PinConglomerate=51|PinLength=20|Location.X=1425|Location.Y=380|Name=C|Designator=1|PinPropagationDelay=0.000000E+000
|RECORD=13|OwnerIndex=4278|IsNotAccesible=T|IndexInSheet=2|OwnerPartId=1|Location.X=1435|Location.Y=400|Corner.X=1415|Corner.Y=400|LineWidth=1|Color=16711680
|RECORD=13|OwnerIndex=4278|IsNotAccesible=T|IndexInSheet=3|OwnerPartId=1|Location.X=1435|Location.Y=380|Corner.X=1415|Corner.Y=380|LineWidth=1|Color=16711680
|RECORD=13|OwnerIndex=4278|IsNotAccesible=T|IndexInSheet=4|OwnerPartId=1|Location.X=1435|Location.Y=400|Corner.X=1425|Corner.Y=380|LineWidth=1|Color=16711680
|RECORD=13|OwnerIndex=4278|IsNotAccesible=T|IndexInSheet=5|OwnerPartId=1|Location.X=1415|Location.Y=400|Corner.X=1425|Corner.Y=380|LineWidth=1|Color=16711680
|RECORD=13|OwnerIndex=4278|IsNotAccesible=T|IndexInSheet=6|OwnerPartId=1|Location.X=1437|Location.Y=395|Corner.X=1447|Corner.Y=385|LineWidth=1|Color=16711680
|RECORD=13|OwnerIndex=4278|IsNotAccesible=T|IndexInSheet=7|OwnerPartId=1|Location.X=1447|Location.Y=385|Corner.X=1447|Corner.Y=390|LineWidth=1|Color=16711680
|RECORD=13|OwnerIndex=4278|IsNotAccesible=T|IndexInSheet=8|OwnerPartId=1|Location.X=1447|Location.Y=385|Corner.X=1442|Corner.Y=385|LineWidth=1|Color=16711680
|RECORD=13|OwnerIndex=4278|IsNotAccesible=T|IndexInSheet=9|OwnerPartId=1|Location.X=1433|Location.Y=388|Corner.X=1443|Corner.Y=378|LineWidth=1|Color=16711680
|RECORD=13|OwnerIndex=4278|IsNotAccesible=T|IndexInSheet=10|OwnerPartId=1|Location.X=1443|Location.Y=378|Corner.X=1443|Corner.Y=383|LineWidth=1|Color=16711680
|RECORD=13|OwnerIndex=4278|IsNotAccesible=T|IndexInSheet=11|OwnerPartId=1|Location.X=1443|Location.Y=378|Corner.X=1438|Corner.Y=378|LineWidth=1|Color=16711680
|RECORD=13|OwnerIndex=4278|IsNotAccesible=T|IndexInSheet=12|OwnerPartId=1|Location.X=1425|Location.Y=400|Corner.X=1425|Corner.Y=403|LineWidth=1|Color=16711680
|RECORD=13|OwnerIndex=4278|IsNotAccesible=T|IndexInSheet=13|OwnerPartId=1|Location.X=1425|Location.Y=380|Corner.X=1425|Corner.Y=377|LineWidth=1|Color=16711680
|RECORD=41|OwnerIndex=4278|IndexInSheet=14|OwnerPartId=-1|Location.X=1414|Location.Y=422|Color=8388608|FontID=1|IsHidden=T|Text=14mcd|Name=Luminous Intensity
|RECORD=41|OwnerIndex=4278|IndexInSheet=15|OwnerPartId=-1|Location.X=1414|Location.Y=422|Color=8388608|FontID=1|IsHidden=T|Text=0.6mm|Name=Height
|RECORD=41|OwnerIndex=4278|IndexInSheet=16|OwnerPartId=-1|Location.X=1414|Location.Y=422|Color=8388608|FontID=1|IsHidden=T|Text=20mA|Name=Test Current
|RECORD=41|OwnerIndex=4278|IndexInSheet=17|OwnerPartId=-1|Location.X=1414|Location.Y=422|Color=8388608|FontID=1|IsHidden=T|Text=Yes|Name=RoHS Compliant
|RECORD=41|OwnerIndex=4278|IndexInSheet=18|OwnerPartId=-1|Location.X=1414|Location.Y=422|Color=8388608|FontID=1|IsHidden=T|Text=Lead Free|Name=Lead Free
|RECORD=41|OwnerIndex=4278|IndexInSheet=19|OwnerPartId=-1|Location.X=1414|Location.Y=422|Color=8388608|FontID=1|IsHidden=T|Text=2|Name=Number of Pins
|RECORD=41|OwnerIndex=4278|IndexInSheet=20|OwnerPartId=-1|Location.X=1414|Location.Y=422|Color=8388608|FontID=1|IsHidden=T|Text=Tape and Reel|Name=Packaging
|RECORD=41|OwnerIndex=4278|IndexInSheet=21|OwnerPartId=-1|Location.X=1414|Location.Y=422|Color=8388608|FontID=1|IsHidden=T|Text=0603|Name=Case/Package
|RECORD=41|OwnerIndex=4278|IndexInSheet=22|OwnerPartId=-1|Location.X=1414|Location.Y=422|Color=8388608|FontID=1|IsHidden=T|Text=1.6mm|Name=Length
|RECORD=41|OwnerIndex=4278|IndexInSheet=23|OwnerPartId=-1|Location.X=1414|Location.Y=422|Color=8388608|FontID=1|IsHidden=T|Text=Red|Name=Color
|RECORD=41|OwnerIndex=4278|IndexInSheet=24|OwnerPartId=-1|Location.X=1414|Location.Y=422|Color=8388608|FontID=1|IsHidden=T|Text=85°C|Name=Max Operating Temperature
|RECORD=41|OwnerIndex=4278|IndexInSheet=25|OwnerPartId=-1|Location.X=1414|Location.Y=422|Color=8388608|FontID=1|IsHidden=T|Text=Red|Name=Illumination Color
|RECORD=41|OwnerIndex=4278|IndexInSheet=26|OwnerPartId=-1|Location.X=1414|Location.Y=422|Color=8388608|FontID=1|IsHidden=T|Text=160°|Name=Viewing Angle
|RECORD=41|OwnerIndex=4278|IndexInSheet=27|OwnerPartId=-1|Location.X=1414|Location.Y=422|Color=8388608|FontID=1|IsHidden=T|Text=UL|Name=Approvals
|RECORD=41|OwnerIndex=4278|IndexInSheet=28|OwnerPartId=-1|Location.X=1414|Location.Y=422|Color=8388608|FontID=1|IsHidden=T|Text=1608|Name=Case Code (Metric)
|RECORD=41|OwnerIndex=4278|IndexInSheet=29|OwnerPartId=-1|Location.X=1414|Location.Y=422|Color=8388608|FontID=1|IsHidden=T|Text=0.061inch|Name=Diameter
|RECORD=41|OwnerIndex=4278|IndexInSheet=30|OwnerPartId=-1|Location.X=1414|Location.Y=422|Color=8388608|FontID=1|IsHidden=T|Text=-25°C|Name=Min Operating Temperature
|RECORD=41|OwnerIndex=4278|IndexInSheet=31|OwnerPartId=-1|Location.X=1414|Location.Y=422|Color=8388608|FontID=1|IsHidden=T|Text=Diffused|Name=Lens Style
|RECORD=41|OwnerIndex=4278|IndexInSheet=32|OwnerPartId=-1|Location.X=1414|Location.Y=422|Color=8388608|FontID=1|IsHidden=T|Text=Surface Mount|Name=Mount
|RECORD=41|OwnerIndex=4278|IndexInSheet=33|OwnerPartId=-1|Location.X=1414|Location.Y=422|Color=8388608|FontID=1|IsHidden=T|Text=0.8mm|Name=Width
|RECORD=41|OwnerIndex=4278|IndexInSheet=34|OwnerPartId=-1|Location.X=1414|Location.Y=422|Color=8388608|FontID=1|IsHidden=T|Text=2V|Name=Forward Voltage
|RECORD=41|OwnerIndex=4278|IndexInSheet=35|OwnerPartId=-1|Location.X=1414|Location.Y=422|Color=8388608|FontID=1|IsHidden=T|Text=50mW|Name=Power Dissipation
|RECORD=41|OwnerIndex=4278|IndexInSheet=36|OwnerPartId=-1|Location.X=1414|Location.Y=422|Color=8388608|FontID=1|IsHidden=T|Text=635nm|Name=Dominant Wavelength
|RECORD=41|OwnerIndex=4278|IndexInSheet=37|OwnerPartId=-1|Location.X=1414|Location.Y=422|Color=8388608|FontID=1|IsHidden=T|Text=1|Name=Number of LEDs
|RECORD=41|OwnerIndex=4278|IndexInSheet=38|OwnerPartId=-1|Location.X=1414|Location.Y=422|Color=8388608|FontID=1|IsHidden=T|Text=0603|Name=Case Code (Imperial)
|RECORD=41|OwnerIndex=4278|IndexInSheet=39|OwnerPartId=-1|Location.X=1414|Location.Y=422|Color=8388608|FontID=1|IsHidden=T|Text=Diffused|Name=Lens Transparency
|RECORD=41|OwnerIndex=4278|IndexInSheet=40|OwnerPartId=-1|Location.X=1414|Location.Y=422|Color=8388608|FontID=1|IsHidden=T|Text=635nm|Name=Wavelength
|RECORD=41|OwnerIndex=4278|IndexInSheet=41|OwnerPartId=-1|Location.X=1414|Location.Y=422|Color=8388608|FontID=1|IsHidden=T|Text=White|Name=Lens Color
|RECORD=41|OwnerIndex=4278|IndexInSheet=42|OwnerPartId=-1|Location.X=1414|Location.Y=422|Color=8388608|FontID=1|IsHidden=T|Text=1|Name=Package Quantity
|RECORD=41|OwnerIndex=4278|IndexInSheet=43|OwnerPartId=-1|Location.X=1414|Location.Y=422|Color=8388608|FontID=1|IsHidden=T|Text=20mA|Name=Forward Current
|RECORD=34|OwnerIndex=4278|IndexInSheet=-1|OwnerPartId=-1|Location.X=1448|Location.Y=394|Color=8388608|FontID=1|Text=D20|Name=Designator|ReadOnlyState=1
|RECORD=41|OwnerIndex=4278|IndexInSheet=-1|OwnerPartId=1|Location.X=1448|Location.Y=384|Color=8388608|FontID=1|Text=SML-LX0603IW-TR|Name=Comment
|RECORD=44|OwnerIndex=4278
|RECORD=45|OwnerIndex=4327|IndexInSheet=-1|UseComponentLibrary=T|ModelName=FP-SML-LX0603IW-TR-MFG|ModelType=PCBLIB|DatafileCount=1|ModelDatafileEntity0=FP-SML-LX0603IW-TR-MFG|ModelDatafileKind0=PCBLib|IsCurrent=T|DatalinksLocked=T|DatabaseDatalinksLocked=T
|RECORD=46|OwnerIndex=4328
|RECORD=48|OwnerIndex=4328
|RECORD=1|LibReference=8706943c75ba83719d021d2fdc84c58|ComponentDescription=LED RED DIFFUSED SMD|PartCount=2|DisplayModeCount=1|IndexInSheet=418|OwnerPartId=-1|Location.X=1540|Location.Y=425|Orientation=3|CurrentPartId=1|LibraryPath=*|SourceLibraryName=Altium Content Vault|TargetFileName=*|AreaColor=11599871|Color=128|PartIDLocked=T|DesignItemId=CMP-57192-000012-1|AllPinCount=2
|RECORD=2|OwnerIndex=4331|OwnerPartId=1|Electrical=4|PinConglomerate=49|PinLength=20|Location.X=1540|Location.Y=405|Name=A|Designator=2|PinPropagationDelay=0.000000E+000
|RECORD=2|OwnerIndex=4331|OwnerPartId=1|Electrical=4|PinConglomerate=51|PinLength=20|Location.X=1540|Location.Y=385|Name=C|Designator=1|PinPropagationDelay=0.000000E+000
|RECORD=13|OwnerIndex=4331|IsNotAccesible=T|IndexInSheet=2|OwnerPartId=1|Location.X=1550|Location.Y=405|Corner.X=1530|Corner.Y=405|LineWidth=1|Color=16711680
|RECORD=13|OwnerIndex=4331|IsNotAccesible=T|IndexInSheet=3|OwnerPartId=1|Location.X=1550|Location.Y=385|Corner.X=1530|Corner.Y=385|LineWidth=1|Color=16711680
|RECORD=13|OwnerIndex=4331|IsNotAccesible=T|IndexInSheet=4|OwnerPartId=1|Location.X=1550|Location.Y=405|Corner.X=1540|Corner.Y=385|LineWidth=1|Color=16711680
|RECORD=13|OwnerIndex=4331|IsNotAccesible=T|IndexInSheet=5|OwnerPartId=1|Location.X=1530|Location.Y=405|Corner.X=1540|Corner.Y=385|LineWidth=1|Color=16711680
|RECORD=13|OwnerIndex=4331|IsNotAccesible=T|IndexInSheet=6|OwnerPartId=1|Location.X=1552|Location.Y=400|Corner.X=1562|Corner.Y=390|LineWidth=1|Color=16711680
|RECORD=13|OwnerIndex=4331|IsNotAccesible=T|IndexInSheet=7|OwnerPartId=1|Location.X=1562|Location.Y=390|Corner.X=1562|Corner.Y=395|LineWidth=1|Color=16711680
|RECORD=13|OwnerIndex=4331|IsNotAccesible=T|IndexInSheet=8|OwnerPartId=1|Location.X=1562|Location.Y=390|Corner.X=1557|Corner.Y=390|LineWidth=1|Color=16711680
|RECORD=13|OwnerIndex=4331|IsNotAccesible=T|IndexInSheet=9|OwnerPartId=1|Location.X=1548|Location.Y=393|Corner.X=1558|Corner.Y=383|LineWidth=1|Color=16711680
|RECORD=13|OwnerIndex=4331|IsNotAccesible=T|IndexInSheet=10|OwnerPartId=1|Location.X=1558|Location.Y=383|Corner.X=1558|Corner.Y=388|LineWidth=1|Color=16711680
|RECORD=13|OwnerIndex=4331|IsNotAccesible=T|IndexInSheet=11|OwnerPartId=1|Location.X=1558|Location.Y=383|Corner.X=1553|Corner.Y=383|LineWidth=1|Color=16711680
|RECORD=13|OwnerIndex=4331|IsNotAccesible=T|IndexInSheet=12|OwnerPartId=1|Location.X=1540|Location.Y=405|Corner.X=1540|Corner.Y=408|LineWidth=1|Color=16711680
|RECORD=13|OwnerIndex=4331|IsNotAccesible=T|IndexInSheet=13|OwnerPartId=1|Location.X=1540|Location.Y=385|Corner.X=1540|Corner.Y=382|LineWidth=1|Color=16711680
|RECORD=41|OwnerIndex=4331|IndexInSheet=14|OwnerPartId=-1|Location.X=1529|Location.Y=427|Color=8388608|FontID=1|IsHidden=T|Text=14mcd|Name=Luminous Intensity
|RECORD=41|OwnerIndex=4331|IndexInSheet=15|OwnerPartId=-1|Location.X=1529|Location.Y=427|Color=8388608|FontID=1|IsHidden=T|Text=0.6mm|Name=Height
|RECORD=41|OwnerIndex=4331|IndexInSheet=16|OwnerPartId=-1|Location.X=1529|Location.Y=427|Color=8388608|FontID=1|IsHidden=T|Text=20mA|Name=Test Current
|RECORD=41|OwnerIndex=4331|IndexInSheet=17|OwnerPartId=-1|Location.X=1529|Location.Y=427|Color=8388608|FontID=1|IsHidden=T|Text=Yes|Name=RoHS Compliant
|RECORD=41|OwnerIndex=4331|IndexInSheet=18|OwnerPartId=-1|Location.X=1529|Location.Y=427|Color=8388608|FontID=1|IsHidden=T|Text=Lead Free|Name=Lead Free
|RECORD=41|OwnerIndex=4331|IndexInSheet=19|OwnerPartId=-1|Location.X=1529|Location.Y=427|Color=8388608|FontID=1|IsHidden=T|Text=2|Name=Number of Pins
|RECORD=41|OwnerIndex=4331|IndexInSheet=20|OwnerPartId=-1|Location.X=1529|Location.Y=427|Color=8388608|FontID=1|IsHidden=T|Text=Tape and Reel|Name=Packaging
|RECORD=41|OwnerIndex=4331|IndexInSheet=21|OwnerPartId=-1|Location.X=1529|Location.Y=427|Color=8388608|FontID=1|IsHidden=T|Text=0603|Name=Case/Package
|RECORD=41|OwnerIndex=4331|IndexInSheet=22|OwnerPartId=-1|Location.X=1529|Location.Y=427|Color=8388608|FontID=1|IsHidden=T|Text=1.6mm|Name=Length
|RECORD=41|OwnerIndex=4331|IndexInSheet=23|OwnerPartId=-1|Location.X=1529|Location.Y=427|Color=8388608|FontID=1|IsHidden=T|Text=Red|Name=Color
|RECORD=41|OwnerIndex=4331|IndexInSheet=24|OwnerPartId=-1|Location.X=1529|Location.Y=427|Color=8388608|FontID=1|IsHidden=T|Text=85°C|Name=Max Operating Temperature
|RECORD=41|OwnerIndex=4331|IndexInSheet=25|OwnerPartId=-1|Location.X=1529|Location.Y=427|Color=8388608|FontID=1|IsHidden=T|Text=Red|Name=Illumination Color
|RECORD=41|OwnerIndex=4331|IndexInSheet=26|OwnerPartId=-1|Location.X=1529|Location.Y=427|Color=8388608|FontID=1|IsHidden=T|Text=160°|Name=Viewing Angle
|RECORD=41|OwnerIndex=4331|IndexInSheet=27|OwnerPartId=-1|Location.X=1529|Location.Y=427|Color=8388608|FontID=1|IsHidden=T|Text=UL|Name=Approvals
|RECORD=41|OwnerIndex=4331|IndexInSheet=28|OwnerPartId=-1|Location.X=1529|Location.Y=427|Color=8388608|FontID=1|IsHidden=T|Text=1608|Name=Case Code (Metric)
|RECORD=41|OwnerIndex=4331|IndexInSheet=29|OwnerPartId=-1|Location.X=1529|Location.Y=427|Color=8388608|FontID=1|IsHidden=T|Text=0.061inch|Name=Diameter
|RECORD=41|OwnerIndex=4331|IndexInSheet=30|OwnerPartId=-1|Location.X=1529|Location.Y=427|Color=8388608|FontID=1|IsHidden=T|Text=-25°C|Name=Min Operating Temperature
|RECORD=41|OwnerIndex=4331|IndexInSheet=31|OwnerPartId=-1|Location.X=1529|Location.Y=427|Color=8388608|FontID=1|IsHidden=T|Text=Diffused|Name=Lens Style
|RECORD=41|OwnerIndex=4331|IndexInSheet=32|OwnerPartId=-1|Location.X=1529|Location.Y=427|Color=8388608|FontID=1|IsHidden=T|Text=Surface Mount|Name=Mount
|RECORD=41|OwnerIndex=4331|IndexInSheet=33|OwnerPartId=-1|Location.X=1529|Location.Y=427|Color=8388608|FontID=1|IsHidden=T|Text=0.8mm|Name=Width
|RECORD=41|OwnerIndex=4331|IndexInSheet=34|OwnerPartId=-1|Location.X=1529|Location.Y=427|Color=8388608|FontID=1|IsHidden=T|Text=2V|Name=Forward Voltage
|RECORD=41|OwnerIndex=4331|IndexInSheet=35|OwnerPartId=-1|Location.X=1529|Location.Y=427|Color=8388608|FontID=1|IsHidden=T|Text=50mW|Name=Power Dissipation
|RECORD=41|OwnerIndex=4331|IndexInSheet=36|OwnerPartId=-1|Location.X=1529|Location.Y=427|Color=8388608|FontID=1|IsHidden=T|Text=635nm|Name=Dominant Wavelength
|RECORD=41|OwnerIndex=4331|IndexInSheet=37|OwnerPartId=-1|Location.X=1529|Location.Y=427|Color=8388608|FontID=1|IsHidden=T|Text=1|Name=Number of LEDs
|RECORD=41|OwnerIndex=4331|IndexInSheet=38|OwnerPartId=-1|Location.X=1529|Location.Y=427|Color=8388608|FontID=1|IsHidden=T|Text=0603|Name=Case Code (Imperial)
|RECORD=41|OwnerIndex=4331|IndexInSheet=39|OwnerPartId=-1|Location.X=1529|Location.Y=427|Color=8388608|FontID=1|IsHidden=T|Text=Diffused|Name=Lens Transparency
|RECORD=41|OwnerIndex=4331|IndexInSheet=40|OwnerPartId=-1|Location.X=1529|Location.Y=427|Color=8388608|FontID=1|IsHidden=T|Text=635nm|Name=Wavelength
|RECORD=41|OwnerIndex=4331|IndexInSheet=41|OwnerPartId=-1|Location.X=1529|Location.Y=427|Color=8388608|FontID=1|IsHidden=T|Text=White|Name=Lens Color
|RECORD=41|OwnerIndex=4331|IndexInSheet=42|OwnerPartId=-1|Location.X=1529|Location.Y=427|Color=8388608|FontID=1|IsHidden=T|Text=1|Name=Package Quantity
|RECORD=41|OwnerIndex=4331|IndexInSheet=43|OwnerPartId=-1|Location.X=1529|Location.Y=427|Color=8388608|FontID=1|IsHidden=T|Text=20mA|Name=Forward Current
|RECORD=34|OwnerIndex=4331|IndexInSheet=-1|OwnerPartId=-1|Location.X=1563|Location.Y=399|Color=8388608|FontID=1|Text=D4|Name=Designator|ReadOnlyState=1
|RECORD=41|OwnerIndex=4331|IndexInSheet=-1|OwnerPartId=1|Location.X=1563|Location.Y=389|Color=8388608|FontID=1|Text=SML-LX0603IW-TR|Name=Comment
|RECORD=44|OwnerIndex=4331
|RECORD=45|OwnerIndex=4380|IndexInSheet=-1|UseComponentLibrary=T|ModelName=FP-SML-LX0603IW-TR-MFG|ModelType=PCBLIB|DatafileCount=1|ModelDatafileEntity0=FP-SML-LX0603IW-TR-MFG|ModelDatafileKind0=PCBLib|IsCurrent=T|DatalinksLocked=T|DatabaseDatalinksLocked=T
|RECORD=46|OwnerIndex=4381
|RECORD=48|OwnerIndex=4381
|RECORD=1|LibReference=1029c3af85768c4190bb7ad29bc67b5|ComponentDescription=RES SMD 200 OHM 1% 1/10W 0402|PartCount=2|DisplayModeCount=1|IndexInSheet=419|OwnerPartId=-1|Location.X=1425|Location.Y=270|Orientation=1|CurrentPartId=1|LibraryPath=*|SourceLibraryName=Altium Content Vault|TargetFileName=*|AreaColor=11599871|Color=128|PartIDLocked=T|DesignItemId=CMP-2002-00757-2|AllPinCount=2
|RECORD=2|OwnerIndex=4384|OwnerPartId=1|Electrical=4|PinConglomerate=51|PinLength=20|Location.X=1425|Location.Y=290|Name=1|Designator=1|PinPropagationDelay=0.000000E+000
|RECORD=2|OwnerIndex=4384|OwnerPartId=1|Electrical=4|PinConglomerate=49|PinLength=20|Location.X=1425|Location.Y=320|Name=2|Designator=2|PinPropagationDelay=0.000000E+000
|RECORD=13|OwnerIndex=4384|IsNotAccesible=T|IndexInSheet=2|OwnerPartId=1|Location.X=1425|Location.Y=290|Corner.X=1420|Corner.Y=293|LineWidth=1|Color=16711680
|RECORD=13|OwnerIndex=4384|IsNotAccesible=T|IndexInSheet=3|OwnerPartId=1|Location.X=1420|Location.Y=293|Corner.X=1430|Corner.Y=298|LineWidth=1|Color=16711680
|RECORD=13|OwnerIndex=4384|IsNotAccesible=T|IndexInSheet=4|OwnerPartId=1|Location.X=1430|Location.Y=298|Corner.X=1420|Corner.Y=303|LineWidth=1|Color=16711680
|RECORD=13|OwnerIndex=4384|IsNotAccesible=T|IndexInSheet=5|OwnerPartId=1|Location.X=1420|Location.Y=303|Corner.X=1430|Corner.Y=308|LineWidth=1|Color=16711680
|RECORD=13|OwnerIndex=4384|IsNotAccesible=T|IndexInSheet=6|OwnerPartId=1|Location.X=1430|Location.Y=308|Corner.X=1420|Corner.Y=313|LineWidth=1|Color=16711680
|RECORD=13|OwnerIndex=4384|IsNotAccesible=T|IndexInSheet=7|OwnerPartId=1|Location.X=1420|Location.Y=313|Corner.X=1430|Corner.Y=318|LineWidth=1|Color=16711680
|RECORD=13|OwnerIndex=4384|IsNotAccesible=T|IndexInSheet=8|OwnerPartId=1|Location.X=1430|Location.Y=318|Corner.X=1425|Corner.Y=320|LineWidth=1|Color=16711680
|RECORD=13|OwnerIndex=4384|IsNotAccesible=T|IndexInSheet=9|OwnerPartId=1|Location.X=1425|Location.Y=290|Corner.X=1425|Corner.Y=287|LineWidth=1|Color=16711680
|RECORD=13|OwnerIndex=4384|IsNotAccesible=T|IndexInSheet=10|OwnerPartId=1|Location.X=1425|Location.Y=320|Corner.X=1425|Corner.Y=323|LineWidth=1|Color=16711680
|RECORD=41|OwnerIndex=4384|IndexInSheet=11|OwnerPartId=-1|Location.X=1419|Location.Y=342|Color=8388608|FontID=1|IsHidden=T|Text=Yes|Name=RoHS Compliant
|RECORD=41|OwnerIndex=4384|IndexInSheet=12|OwnerPartId=-1|Location.X=1419|Location.Y=342|Color=8388608|FontID=1|IsHidden=T|Text=Tape and Reel|Name=Packaging
|RECORD=41|OwnerIndex=4384|IndexInSheet=13|OwnerPartId=-1|Location.X=1419|Location.Y=342|Color=8388608|FontID=1|IsHidden=T|Text=1005|Name=Case Code (Metric)
|RECORD=41|OwnerIndex=4384|IndexInSheet=14|OwnerPartId=-1|Location.X=1419|Location.Y=342|Color=8388608|FontID=1|IsHidden=T|Text=1|Name=Package Quantity
|RECORD=41|OwnerIndex=4384|IndexInSheet=15|OwnerPartId=-1|Location.X=1419|Location.Y=342|Color=8388608|FontID=1|IsHidden=T|Text=Tin|Name=Contact Plating
|RECORD=41|OwnerIndex=4384|IndexInSheet=16|OwnerPartId=-1|Location.X=1419|Location.Y=342|Color=8388608|FontID=1|IsHidden=T|Text=100mW|Name=Power Rating
|RECORD=41|OwnerIndex=4384|IndexInSheet=17|OwnerPartId=-1|Location.X=1419|Location.Y=342|Color=8388608|FontID=1|IsHidden=T|Text=ERJ|Name=Series
|RECORD=41|OwnerIndex=4384|IndexInSheet=18|OwnerPartId=-1|Location.X=1419|Location.Y=342|Color=8388608|FontID=1|IsHidden=T|Text=Surface Mount|Name=Mount
|RECORD=41|OwnerIndex=4384|IndexInSheet=19|OwnerPartId=-1|Location.X=1419|Location.Y=342|Color=8388608|FontID=1|IsHidden=T|Text=Lead Free|Name=Lead Free
|RECORD=41|OwnerIndex=4384|IndexInSheet=20|OwnerPartId=-1|Location.X=1419|Location.Y=342|Color=8388608|FontID=1|IsHidden=T|Text=-55°C|Name=Min Operating Temperature
|RECORD=41|OwnerIndex=4384|IndexInSheet=21|OwnerPartId=-1|Location.X=1419|Location.Y=342|Color=8388608|FontID=1|IsHidden=T|Text=2|Name=Number of Terminations
|RECORD=41|OwnerIndex=4384|IndexInSheet=22|OwnerPartId=-1|Location.X=1419|Location.Y=342|Color=8388608|FontID=1|IsHidden=T|Text=50V|Name=Voltage Rating (DC)
|RECORD=41|OwnerIndex=4384|IndexInSheet=23|OwnerPartId=-1|Location.X=1419|Location.Y=342|Color=8388608|FontID=1|IsHidden=T|Text=100mW|Name=Max Power Dissipation
|RECORD=41|OwnerIndex=4384|IndexInSheet=24|OwnerPartId=-1|Location.X=1419|Location.Y=342|Color=8388608|FontID=1|IsHidden=T|Text=THICK FILM|Name=Technology
|RECORD=41|OwnerIndex=4384|IndexInSheet=25|OwnerPartId=-1|Location.X=1419|Location.Y=342|Color=8388608|FontID=1|IsHidden=T|Text=200R|Name=Resistance
|RECORD=41|OwnerIndex=4384|IndexInSheet=26|OwnerPartId=-1|Location.X=1419|Location.Y=342|Color=8388608|FontID=1|IsHidden=T|Text=50V|Name=Voltage Rating
|RECORD=41|OwnerIndex=4384|IndexInSheet=27|OwnerPartId=-1|Location.X=1419|Location.Y=342|Color=8388608|FontID=1|IsHidden=T|Text=0402|Name=Case/Package
|RECORD=41|OwnerIndex=4384|IndexInSheet=28|OwnerPartId=-1|Location.X=1419|Location.Y=342|Color=8388608|FontID=1|IsHidden=T|Text=0.02inch|Name=Width
|RECORD=41|OwnerIndex=4384|IndexInSheet=29|OwnerPartId=-1|Location.X=1419|Location.Y=342|Color=8388608|FontID=1|IsHidden=T|Text=SMD/SMT|Name=Termination
|RECORD=41|OwnerIndex=4384|IndexInSheet=30|OwnerPartId=-1|Location.X=1419|Location.Y=342|Color=8388608|FontID=1|IsHidden=T|Text=Not|Name=Military Standard
|RECORD=41|OwnerIndex=4384|IndexInSheet=31|OwnerPartId=-1|Location.X=1419|Location.Y=342|Color=8388608|FontID=1|IsHidden=T|Text=100ppm/°C|Name=Temperature Coefficient
|RECORD=41|OwnerIndex=4384|IndexInSheet=32|OwnerPartId=-1|Location.X=1419|Location.Y=342|Color=8388608|FontID=1|IsHidden=T|Text=0.35mm|Name=Height
|RECORD=41|OwnerIndex=4384|IndexInSheet=33|OwnerPartId=-1|Location.X=1419|Location.Y=342|Color=8388608|FontID=1|IsHidden=T|Text=No|Name=Radiation Hardening
|RECORD=41|OwnerIndex=4384|IndexInSheet=34|OwnerPartId=-1|Location.X=1419|Location.Y=342|Color=8388608|FontID=1|IsHidden=T|Text=1%|Name=Resistance Tolerance
|RECORD=41|OwnerIndex=4384|IndexInSheet=35|OwnerPartId=-1|Location.X=1419|Location.Y=342|Color=8388608|FontID=1|IsHidden=T|Text=1mm|Name=Length
|RECORD=41|OwnerIndex=4384|IndexInSheet=36|OwnerPartId=-1|Location.X=1419|Location.Y=342|Color=8388608|FontID=1|IsHidden=T|Text=No SVHC|Name=REACH SVHC
|RECORD=41|OwnerIndex=4384|IndexInSheet=37|OwnerPartId=-1|Location.X=1419|Location.Y=342|Color=8388608|FontID=1|IsHidden=T|Text=Rectangular|Name=Construction
|RECORD=41|OwnerIndex=4384|IndexInSheet=38|OwnerPartId=-1|Location.X=1419|Location.Y=342|Color=8388608|FontID=1|IsHidden=T|Text=0.5mm|Name=Depth
|RECORD=41|OwnerIndex=4384|IndexInSheet=39|OwnerPartId=-1|Location.X=1419|Location.Y=342|Color=8388608|FontID=1|IsHidden=T|Text=Automotive AEC-Q200|Name=Features
|RECORD=41|OwnerIndex=4384|IndexInSheet=40|OwnerPartId=-1|Location.X=1419|Location.Y=342|Color=8388608|FontID=1|IsHidden=T|Text=Thick Film|Name=Resistor Type
|RECORD=41|OwnerIndex=4384|IndexInSheet=41|OwnerPartId=-1|Location.X=1419|Location.Y=342|Color=8388608|FontID=1|IsHidden=T|Text=0402|Name=Case Code (Imperial)
|RECORD=41|OwnerIndex=4384|IndexInSheet=42|OwnerPartId=-1|Location.X=1419|Location.Y=342|Color=8388608|FontID=1|IsHidden=T|Text=1%|Name=Tolerance
|RECORD=41|OwnerIndex=4384|IndexInSheet=43|OwnerPartId=-1|Location.X=1419|Location.Y=342|Color=8388608|FontID=1|IsHidden=T|Text=0402|Name=Size Code
|RECORD=41|OwnerIndex=4384|IndexInSheet=44|OwnerPartId=-1|Location.X=1419|Location.Y=342|Color=8388608|FontID=1|IsHidden=T|Text=155°C|Name=Max Operating Temperature
|RECORD=34|OwnerIndex=4384|IndexInSheet=-1|OwnerPartId=-1|Location.X=1431|Location.Y=314|Color=8388608|FontID=1|Text=R77|Name=Designator|ReadOnlyState=1
|RECORD=41|OwnerIndex=4384|IndexInSheet=-1|OwnerPartId=1|Location.X=1431|Location.Y=304|Color=8388608|FontID=1|Text=200_1%_0402|Name=Comment
|RECORD=44|OwnerIndex=4384
|RECORD=45|OwnerIndex=4434|IndexInSheet=-1|UseComponentLibrary=T|ModelName=FP-ERJ2RK-IPC_A|ModelType=PCBLIB|DatafileCount=1|ModelDatafileEntity0=FP-ERJ2RK-IPC_A|ModelDatafileKind0=PCBLib|IsCurrent=T|DatalinksLocked=T|DatabaseDatalinksLocked=T
|RECORD=46|OwnerIndex=4435
|RECORD=48|OwnerIndex=4435
|RECORD=45|OwnerIndex=4434|IndexInSheet=-1|UseComponentLibrary=T|ModelName=FP-ERJ2RK-IPC_C|ModelType=PCBLIB|DatafileCount=1|ModelDatafileEntity0=FP-ERJ2RK-IPC_C|ModelDatafileKind0=PCBLib|DatalinksLocked=T|DatabaseDatalinksLocked=T
|RECORD=46|OwnerIndex=4438
|RECORD=48|OwnerIndex=4438
|RECORD=45|OwnerIndex=4434|IndexInSheet=-1|UseComponentLibrary=T|ModelName=FP-ERJ2RK-MFG|ModelType=PCBLIB|DatafileCount=1|ModelDatafileEntity0=FP-ERJ2RK-MFG|ModelDatafileKind0=PCBLib|DatalinksLocked=T|DatabaseDatalinksLocked=T
|RECORD=46|OwnerIndex=4441
|RECORD=48|OwnerIndex=4441
|RECORD=45|OwnerIndex=4434|IndexInSheet=-1|UseComponentLibrary=T|ModelName=FP-ERJ2RK-IPC_B|ModelType=PCBLIB|DatafileCount=1|ModelDatafileEntity0=FP-ERJ2RK-IPC_B|ModelDatafileKind0=PCBLib|DatalinksLocked=T|DatabaseDatalinksLocked=T
|RECORD=46|OwnerIndex=4444
|RECORD=48|OwnerIndex=4444
|RECORD=1|LibReference=1029c3af85768c4190bb7ad29bc67b5|ComponentDescription=RES SMD 200 OHM 1% 1/10W 0402|PartCount=2|DisplayModeCount=1|IndexInSheet=420|OwnerPartId=-1|Location.X=1540|Location.Y=275|Orientation=1|CurrentPartId=1|LibraryPath=*|SourceLibraryName=Altium Content Vault|TargetFileName=*|AreaColor=11599871|Color=128|PartIDLocked=T|DesignItemId=CMP-2002-00757-2|AllPinCount=2
|RECORD=2|OwnerIndex=4447|OwnerPartId=1|Electrical=4|PinConglomerate=51|PinLength=20|Location.X=1540|Location.Y=295|Name=1|Designator=1|PinPropagationDelay=0.000000E+000
|RECORD=2|OwnerIndex=4447|OwnerPartId=1|Electrical=4|PinConglomerate=49|PinLength=20|Location.X=1540|Location.Y=325|Name=2|Designator=2|PinPropagationDelay=0.000000E+000
|RECORD=13|OwnerIndex=4447|IsNotAccesible=T|IndexInSheet=2|OwnerPartId=1|Location.X=1540|Location.Y=295|Corner.X=1535|Corner.Y=298|LineWidth=1|Color=16711680
|RECORD=13|OwnerIndex=4447|IsNotAccesible=T|IndexInSheet=3|OwnerPartId=1|Location.X=1535|Location.Y=298|Corner.X=1545|Corner.Y=303|LineWidth=1|Color=16711680
|RECORD=13|OwnerIndex=4447|IsNotAccesible=T|IndexInSheet=4|OwnerPartId=1|Location.X=1545|Location.Y=303|Corner.X=1535|Corner.Y=308|LineWidth=1|Color=16711680
|RECORD=13|OwnerIndex=4447|IsNotAccesible=T|IndexInSheet=5|OwnerPartId=1|Location.X=1535|Location.Y=308|Corner.X=1545|Corner.Y=313|LineWidth=1|Color=16711680
|RECORD=13|OwnerIndex=4447|IsNotAccesible=T|IndexInSheet=6|OwnerPartId=1|Location.X=1545|Location.Y=313|Corner.X=1535|Corner.Y=318|LineWidth=1|Color=16711680
|RECORD=13|OwnerIndex=4447|IsNotAccesible=T|IndexInSheet=7|OwnerPartId=1|Location.X=1535|Location.Y=318|Corner.X=1545|Corner.Y=323|LineWidth=1|Color=16711680
|RECORD=13|OwnerIndex=4447|IsNotAccesible=T|IndexInSheet=8|OwnerPartId=1|Location.X=1545|Location.Y=323|Corner.X=1540|Corner.Y=325|LineWidth=1|Color=16711680
|RECORD=13|OwnerIndex=4447|IsNotAccesible=T|IndexInSheet=9|OwnerPartId=1|Location.X=1540|Location.Y=295|Corner.X=1540|Corner.Y=292|LineWidth=1|Color=16711680
|RECORD=13|OwnerIndex=4447|IsNotAccesible=T|IndexInSheet=10|OwnerPartId=1|Location.X=1540|Location.Y=325|Corner.X=1540|Corner.Y=328|LineWidth=1|Color=16711680
|RECORD=41|OwnerIndex=4447|IndexInSheet=11|OwnerPartId=-1|Location.X=1534|Location.Y=347|Color=8388608|FontID=1|IsHidden=T|Text=Yes|Name=RoHS Compliant
|RECORD=41|OwnerIndex=4447|IndexInSheet=12|OwnerPartId=-1|Location.X=1534|Location.Y=347|Color=8388608|FontID=1|IsHidden=T|Text=Tape and Reel|Name=Packaging
|RECORD=41|OwnerIndex=4447|IndexInSheet=13|OwnerPartId=-1|Location.X=1534|Location.Y=347|Color=8388608|FontID=1|IsHidden=T|Text=1005|Name=Case Code (Metric)
|RECORD=41|OwnerIndex=4447|IndexInSheet=14|OwnerPartId=-1|Location.X=1534|Location.Y=347|Color=8388608|FontID=1|IsHidden=T|Text=1|Name=Package Quantity
|RECORD=41|OwnerIndex=4447|IndexInSheet=15|OwnerPartId=-1|Location.X=1534|Location.Y=347|Color=8388608|FontID=1|IsHidden=T|Text=Tin|Name=Contact Plating
|RECORD=41|OwnerIndex=4447|IndexInSheet=16|OwnerPartId=-1|Location.X=1534|Location.Y=347|Color=8388608|FontID=1|IsHidden=T|Text=100mW|Name=Power Rating
|RECORD=41|OwnerIndex=4447|IndexInSheet=17|OwnerPartId=-1|Location.X=1534|Location.Y=347|Color=8388608|FontID=1|IsHidden=T|Text=ERJ|Name=Series
|RECORD=41|OwnerIndex=4447|IndexInSheet=18|OwnerPartId=-1|Location.X=1534|Location.Y=347|Color=8388608|FontID=1|IsHidden=T|Text=Surface Mount|Name=Mount
|RECORD=41|OwnerIndex=4447|IndexInSheet=19|OwnerPartId=-1|Location.X=1534|Location.Y=347|Color=8388608|FontID=1|IsHidden=T|Text=Lead Free|Name=Lead Free
|RECORD=41|OwnerIndex=4447|IndexInSheet=20|OwnerPartId=-1|Location.X=1534|Location.Y=347|Color=8388608|FontID=1|IsHidden=T|Text=-55°C|Name=Min Operating Temperature
|RECORD=41|OwnerIndex=4447|IndexInSheet=21|OwnerPartId=-1|Location.X=1534|Location.Y=347|Color=8388608|FontID=1|IsHidden=T|Text=2|Name=Number of Terminations
|RECORD=41|OwnerIndex=4447|IndexInSheet=22|OwnerPartId=-1|Location.X=1534|Location.Y=347|Color=8388608|FontID=1|IsHidden=T|Text=50V|Name=Voltage Rating (DC)
|RECORD=41|OwnerIndex=4447|IndexInSheet=23|OwnerPartId=-1|Location.X=1534|Location.Y=347|Color=8388608|FontID=1|IsHidden=T|Text=100mW|Name=Max Power Dissipation
|RECORD=41|OwnerIndex=4447|IndexInSheet=24|OwnerPartId=-1|Location.X=1534|Location.Y=347|Color=8388608|FontID=1|IsHidden=T|Text=THICK FILM|Name=Technology
|RECORD=41|OwnerIndex=4447|IndexInSheet=25|OwnerPartId=-1|Location.X=1534|Location.Y=347|Color=8388608|FontID=1|IsHidden=T|Text=200R|Name=Resistance
|RECORD=41|OwnerIndex=4447|IndexInSheet=26|OwnerPartId=-1|Location.X=1534|Location.Y=347|Color=8388608|FontID=1|IsHidden=T|Text=50V|Name=Voltage Rating
|RECORD=41|OwnerIndex=4447|IndexInSheet=27|OwnerPartId=-1|Location.X=1534|Location.Y=347|Color=8388608|FontID=1|IsHidden=T|Text=0402|Name=Case/Package
|RECORD=41|OwnerIndex=4447|IndexInSheet=28|OwnerPartId=-1|Location.X=1534|Location.Y=347|Color=8388608|FontID=1|IsHidden=T|Text=0.02inch|Name=Width
|RECORD=41|OwnerIndex=4447|IndexInSheet=29|OwnerPartId=-1|Location.X=1534|Location.Y=347|Color=8388608|FontID=1|IsHidden=T|Text=SMD/SMT|Name=Termination
|RECORD=41|OwnerIndex=4447|IndexInSheet=30|OwnerPartId=-1|Location.X=1534|Location.Y=347|Color=8388608|FontID=1|IsHidden=T|Text=Not|Name=Military Standard
|RECORD=41|OwnerIndex=4447|IndexInSheet=31|OwnerPartId=-1|Location.X=1534|Location.Y=347|Color=8388608|FontID=1|IsHidden=T|Text=100ppm/°C|Name=Temperature Coefficient
|RECORD=41|OwnerIndex=4447|IndexInSheet=32|OwnerPartId=-1|Location.X=1534|Location.Y=347|Color=8388608|FontID=1|IsHidden=T|Text=0.35mm|Name=Height
|RECORD=41|OwnerIndex=4447|IndexInSheet=33|OwnerPartId=-1|Location.X=1534|Location.Y=347|Color=8388608|FontID=1|IsHidden=T|Text=No|Name=Radiation Hardening
|RECORD=41|OwnerIndex=4447|IndexInSheet=34|OwnerPartId=-1|Location.X=1534|Location.Y=347|Color=8388608|FontID=1|IsHidden=T|Text=1%|Name=Resistance Tolerance
|RECORD=41|OwnerIndex=4447|IndexInSheet=35|OwnerPartId=-1|Location.X=1534|Location.Y=347|Color=8388608|FontID=1|IsHidden=T|Text=1mm|Name=Length
|RECORD=41|OwnerIndex=4447|IndexInSheet=36|OwnerPartId=-1|Location.X=1534|Location.Y=347|Color=8388608|FontID=1|IsHidden=T|Text=No SVHC|Name=REACH SVHC
|RECORD=41|OwnerIndex=4447|IndexInSheet=37|OwnerPartId=-1|Location.X=1534|Location.Y=347|Color=8388608|FontID=1|IsHidden=T|Text=Rectangular|Name=Construction
|RECORD=41|OwnerIndex=4447|IndexInSheet=38|OwnerPartId=-1|Location.X=1534|Location.Y=347|Color=8388608|FontID=1|IsHidden=T|Text=0.5mm|Name=Depth
|RECORD=41|OwnerIndex=4447|IndexInSheet=39|OwnerPartId=-1|Location.X=1534|Location.Y=347|Color=8388608|FontID=1|IsHidden=T|Text=Automotive AEC-Q200|Name=Features
|RECORD=41|OwnerIndex=4447|IndexInSheet=40|OwnerPartId=-1|Location.X=1534|Location.Y=347|Color=8388608|FontID=1|IsHidden=T|Text=Thick Film|Name=Resistor Type
|RECORD=41|OwnerIndex=4447|IndexInSheet=41|OwnerPartId=-1|Location.X=1534|Location.Y=347|Color=8388608|FontID=1|IsHidden=T|Text=0402|Name=Case Code (Imperial)
|RECORD=41|OwnerIndex=4447|IndexInSheet=42|OwnerPartId=-1|Location.X=1534|Location.Y=347|Color=8388608|FontID=1|IsHidden=T|Text=1%|Name=Tolerance
|RECORD=41|OwnerIndex=4447|IndexInSheet=43|OwnerPartId=-1|Location.X=1534|Location.Y=347|Color=8388608|FontID=1|IsHidden=T|Text=0402|Name=Size Code
|RECORD=41|OwnerIndex=4447|IndexInSheet=44|OwnerPartId=-1|Location.X=1534|Location.Y=347|Color=8388608|FontID=1|IsHidden=T|Text=155°C|Name=Max Operating Temperature
|RECORD=34|OwnerIndex=4447|IndexInSheet=-1|OwnerPartId=-1|Location.X=1546|Location.Y=319|Color=8388608|FontID=1|Text=R1|Name=Designator|ReadOnlyState=1
|RECORD=41|OwnerIndex=4447|IndexInSheet=-1|OwnerPartId=1|Location.X=1546|Location.Y=309|Color=8388608|FontID=1|Text=200_1%_0402|Name=Comment
|RECORD=44|OwnerIndex=4447
|RECORD=45|OwnerIndex=4497|IndexInSheet=-1|UseComponentLibrary=T|ModelName=FP-ERJ2RK-IPC_A|ModelType=PCBLIB|DatafileCount=1|ModelDatafileEntity0=FP-ERJ2RK-IPC_A|ModelDatafileKind0=PCBLib|IsCurrent=T|DatalinksLocked=T|DatabaseDatalinksLocked=T
|RECORD=46|OwnerIndex=4498
|RECORD=48|OwnerIndex=4498
|RECORD=45|OwnerIndex=4497|IndexInSheet=-1|UseComponentLibrary=T|ModelName=FP-ERJ2RK-IPC_C|ModelType=PCBLIB|DatafileCount=1|ModelDatafileEntity0=FP-ERJ2RK-IPC_C|ModelDatafileKind0=PCBLib|DatalinksLocked=T|DatabaseDatalinksLocked=T
|RECORD=46|OwnerIndex=4501
|RECORD=48|OwnerIndex=4501
|RECORD=45|OwnerIndex=4497|IndexInSheet=-1|UseComponentLibrary=T|ModelName=FP-ERJ2RK-MFG|ModelType=PCBLIB|DatafileCount=1|ModelDatafileEntity0=FP-ERJ2RK-MFG|ModelDatafileKind0=PCBLib|DatalinksLocked=T|DatabaseDatalinksLocked=T
|RECORD=46|OwnerIndex=4504
|RECORD=48|OwnerIndex=4504
|RECORD=45|OwnerIndex=4497|IndexInSheet=-1|UseComponentLibrary=T|ModelName=FP-ERJ2RK-IPC_B|ModelType=PCBLIB|DatafileCount=1|ModelDatafileEntity0=FP-ERJ2RK-IPC_B|ModelDatafileKind0=PCBLib|DatalinksLocked=T|DatabaseDatalinksLocked=T
|RECORD=46|OwnerIndex=4507
|RECORD=48|OwnerIndex=4507
|RECORD=1|LibReference=673ecd2ea4d7fb87b4005b0cb348b7d|ComponentDescription=TVS DIODE 12V 19.9V DO214AB|PartCount=2|DisplayModeCount=1|IndexInSheet=421|OwnerPartId=-1|Location.X=425|Location.Y=840|Orientation=1|CurrentPartId=1|LibraryPath=*|SourceLibraryName=Altium Content Vault|TargetFileName=*|AreaColor=11599871|Color=128|PartIDLocked=T|DesignItemId=CMP-08607-000111-1|AllPinCount=2
|RECORD=13|OwnerIndex=4510|IsNotAccesible=T|OwnerPartId=1|Location.X=415|Location.Y=860|Corner.X=435|Corner.Y=860|LineWidth=1|Color=16711680
|RECORD=13|OwnerIndex=4510|IsNotAccesible=T|IndexInSheet=1|OwnerPartId=1|Location.X=420|Location.Y=880|Corner.X=430|Corner.Y=880|LineWidth=1|Color=16711680
|RECORD=13|OwnerIndex=4510|IsNotAccesible=T|IndexInSheet=2|OwnerPartId=1|Location.X=415|Location.Y=860|Corner.X=425|Corner.Y=880|LineWidth=1|Color=16711680
|RECORD=13|OwnerIndex=4510|IsNotAccesible=T|IndexInSheet=3|OwnerPartId=1|Location.X=435|Location.Y=860|Corner.X=425|Corner.Y=880|LineWidth=1|Color=16711680
|RECORD=13|OwnerIndex=4510|IsNotAccesible=T|IndexInSheet=4|OwnerPartId=1|Location.X=420|Location.Y=880|Corner.X=415|Corner.Y=875|LineWidth=1|Color=16711680
|RECORD=13|OwnerIndex=4510|IsNotAccesible=T|IndexInSheet=5|OwnerPartId=1|Location.X=430|Location.Y=880|Corner.X=435|Corner.Y=885|LineWidth=1|Color=16711680
|RECORD=2|OwnerIndex=4510|OwnerPartId=1|Electrical=4|PinConglomerate=51|PinLength=20|Location.X=425|Location.Y=860|Name=A|Designator=2|PinPropagationDelay=0.000000E+000
|RECORD=2|OwnerIndex=4510|OwnerPartId=1|Electrical=4|PinConglomerate=49|PinLength=20|Location.X=425|Location.Y=880|Name=C|Designator=1|PinPropagationDelay=0.000000E+000
|RECORD=41|OwnerIndex=4510|IndexInSheet=8|OwnerPartId=-1|Location.X=414|Location.Y=902|Color=8388608|FontID=1|IsHidden=T|Text=Lead Free|Name=Lead Free
|RECORD=41|OwnerIndex=4510|IndexInSheet=9|OwnerPartId=-1|Location.X=414|Location.Y=902|Color=8388608|FontID=1|IsHidden=T|Text=Tape and Reel|Name=Packaging
|RECORD=41|OwnerIndex=4510|IndexInSheet=10|OwnerPartId=-1|Location.X=414|Location.Y=902|Color=8388608|FontID=1|IsHidden=T|Text=SMDJ|Name=Series
|RECORD=41|OwnerIndex=4510|IndexInSheet=11|OwnerPartId=-1|Location.X=414|Location.Y=902|Color=8388608|FontID=1|IsHidden=T|Text=2|Name=Number of Pins
|RECORD=41|OwnerIndex=4510|IndexInSheet=12|OwnerPartId=-1|Location.X=414|Location.Y=902|Color=8388608|FontID=1|IsHidden=T|Text=1|Name=Number of Channels
|RECORD=41|OwnerIndex=4510|IndexInSheet=13|OwnerPartId=-1|Location.X=414|Location.Y=902|Color=8388608|FontID=1|IsHidden=T|Text=Zener|Name=Resistor Type
|RECORD=41|OwnerIndex=4510|IndexInSheet=14|OwnerPartId=-1|Location.X=414|Location.Y=902|Color=8388608|FontID=1|IsHidden=T|Text=SMD/SMT|Name=Termination
|RECORD=41|OwnerIndex=4510|IndexInSheet=15|OwnerPartId=-1|Location.X=414|Location.Y=902|Color=8388608|FontID=1|IsHidden=T|Text=No|Name=Power Line Protection
|RECORD=41|OwnerIndex=4510|IndexInSheet=16|OwnerPartId=-1|Location.X=414|Location.Y=902|Color=8388608|FontID=1|IsHidden=T|Text=13.3V|Name=Reverse Breakdown Voltage
|RECORD=41|OwnerIndex=4510|IndexInSheet=17|OwnerPartId=-1|Location.X=414|Location.Y=902|Color=8388608|FontID=1|IsHidden=T|Text=6.5W|Name=Max Power Dissipation
|RECORD=41|OwnerIndex=4510|IndexInSheet=18|OwnerPartId=-1|Location.X=414|Location.Y=902|Color=8388608|FontID=1|IsHidden=T|Text=150.8A|Name=Peak Pulse Current
|RECORD=41|OwnerIndex=4510|IndexInSheet=19|OwnerPartId=-1|Location.X=414|Location.Y=902|Color=8388608|FontID=1|IsHidden=T|Text=Yes|Name=RoHS Compliant
|RECORD=41|OwnerIndex=4510|IndexInSheet=20|OwnerPartId=-1|Location.X=414|Location.Y=902|Color=8388608|FontID=1|IsHidden=T|Text=2uA|Name=Leakage Current
|RECORD=41|OwnerIndex=4510|IndexInSheet=21|OwnerPartId=-1|Location.X=414|Location.Y=902|Color=8388608|FontID=1|IsHidden=T|Text=ZENER|Name=Diode Type
|RECORD=41|OwnerIndex=4510|IndexInSheet=22|OwnerPartId=-1|Location.X=414|Location.Y=902|Color=8388608|FontID=1|IsHidden=T|Text=3kW|Name=Power Dissipation
|RECORD=41|OwnerIndex=4510|IndexInSheet=23|OwnerPartId=-1|Location.X=414|Location.Y=902|Color=8388608|FontID=1|IsHidden=T|Text=1|Name=Number of Elements
|RECORD=41|OwnerIndex=4510|IndexInSheet=24|OwnerPartId=-1|Location.X=414|Location.Y=902|Color=8388608|FontID=1|IsHidden=T|Text=1mA|Name=Test Current
|RECORD=41|OwnerIndex=4510|IndexInSheet=25|OwnerPartId=-1|Location.X=414|Location.Y=902|Color=8388608|FontID=1|IsHidden=T|Text=No SVHC|Name=REACH SVHC
|RECORD=41|OwnerIndex=4510|IndexInSheet=26|OwnerPartId=-1|Location.X=414|Location.Y=902|Color=8388608|FontID=1|IsHidden=T|Text=13.3V|Name=Min Breakdown Voltage
|RECORD=41|OwnerIndex=4510|IndexInSheet=27|OwnerPartId=-1|Location.X=414|Location.Y=902|Color=8388608|FontID=1|IsHidden=T|Text=Unidirectional|Name=Direction
|RECORD=41|OwnerIndex=4510|IndexInSheet=28|OwnerPartId=-1|Location.X=414|Location.Y=902|Color=8388608|FontID=1|IsHidden=T|Text=14.7V|Name=Max Breakdown Voltage
|RECORD=41|OwnerIndex=4510|IndexInSheet=29|OwnerPartId=-1|Location.X=414|Location.Y=902|Color=8388608|FontID=1|IsHidden=T|Text=Surface Mount|Name=Mount
|RECORD=41|OwnerIndex=4510|IndexInSheet=30|OwnerPartId=-1|Location.X=414|Location.Y=902|Color=8388608|FontID=1|IsHidden=T|Text=12V|Name=Operating Supply Voltage
|RECORD=41|OwnerIndex=4510|IndexInSheet=31|OwnerPartId=-1|Location.X=414|Location.Y=902|Color=8388608|FontID=1|IsHidden=T|Text=Unidirectional|Name=Polarity
|RECORD=41|OwnerIndex=4510|IndexInSheet=32|OwnerPartId=-1|Location.X=414|Location.Y=902|Color=8388608|FontID=1|IsHidden=T|Text=13.3V|Name=Breakdown Voltage
|RECORD=41|OwnerIndex=4510|IndexInSheet=33|OwnerPartId=-1|Location.X=414|Location.Y=902|Color=8388608|FontID=1|IsHidden=T|Text=150.8A|Name=Max Surge Current
|RECORD=41|OwnerIndex=4510|IndexInSheet=34|OwnerPartId=-1|Location.X=414|Location.Y=902|Color=8388608|FontID=1|IsHidden=T|Text=19.9V|Name=Clamping Voltage-Max
|RECORD=41|OwnerIndex=4510|IndexInSheet=35|OwnerPartId=-1|Location.X=414|Location.Y=902|Color=8388608|FontID=1|IsHidden=T|Text=19.9V|Name=Clamping Voltage
|RECORD=41|OwnerIndex=4510|IndexInSheet=36|OwnerPartId=-1|Location.X=414|Location.Y=902|Color=8388608|FontID=1|IsHidden=T|Text=12V|Name=Reverse Standoff Voltage
|RECORD=41|OwnerIndex=4510|IndexInSheet=37|OwnerPartId=-1|Location.X=414|Location.Y=902|Color=8388608|FontID=1|IsHidden=T|Text=150°C|Name=Max Operating Temperature
|RECORD=41|OwnerIndex=4510|IndexInSheet=38|OwnerPartId=-1|Location.X=414|Location.Y=902|Color=8388608|FontID=1|IsHidden=T|Text=DO-214AB|Name=Case/Package
|RECORD=41|OwnerIndex=4510|IndexInSheet=39|OwnerPartId=-1|Location.X=414|Location.Y=902|Color=8388608|FontID=1|IsHidden=T|Text=3000|Name=Package Quantity
|RECORD=41|OwnerIndex=4510|IndexInSheet=40|OwnerPartId=-1|Location.X=414|Location.Y=902|Color=8388608|FontID=1|IsHidden=T|Text=3kW|Name=Peak Pulse Power
|RECORD=41|OwnerIndex=4510|IndexInSheet=41|OwnerPartId=-1|Location.X=414|Location.Y=902|Color=8388608|FontID=1|IsHidden=T|Text=-55°C|Name=Min Operating Temperature
|RECORD=41|OwnerIndex=4510|IndexInSheet=42|OwnerPartId=-1|Location.X=414|Location.Y=902|Color=8388608|FontID=1|IsHidden=T|Text=1|Name=Number of Unidirectional Channels
|RECORD=34|OwnerIndex=4510|IndexInSheet=-1|OwnerPartId=-1|Location.X=436|Location.Y=876|Color=8388608|FontID=1|Text=D23|Name=Designator|ReadOnlyState=1
|RECORD=41|OwnerIndex=4510|IndexInSheet=-1|OwnerPartId=1|Location.X=436|Location.Y=866|Color=8388608|FontID=1|Text=SMDJ12A|Name=Comment
|RECORD=44|OwnerIndex=4510
|RECORD=45|OwnerIndex=4558|IndexInSheet=-1|UseComponentLibrary=T|ModelName=FP-DO-214AB_SMC_J-Bend-MFG|ModelType=PCBLIB|DatafileCount=1|ModelDatafileEntity0=FP-DO-214AB_SMC_J-Bend-MFG|ModelDatafileKind0=PCBLib|IsCurrent=T|DatalinksLocked=T|DatabaseDatalinksLocked=T
|RECORD=46|OwnerIndex=4559
|RECORD=48|OwnerIndex=4559
|RECORD=27|IndexInSheet=422|OwnerPartId=-1|LineWidth=1|Color=8388608|LocationCount=2|X1=600|Y1=837|X2=600|Y2=805
|RECORD=27|IndexInSheet=423|OwnerPartId=-1|LineWidth=1|Color=8388608|LocationCount=5|X1=552|Y1=847|X2=552|Y2=837|X3=600|Y3=837|X4=602|Y4=837|X5=602|Y5=847
|RECORD=27|IndexInSheet=424|OwnerPartId=-1|LineWidth=1|Color=8388608|LocationCount=2|X1=425|Y1=900|X2=425|Y2=915
|RECORD=17|IndexInSheet=425|OwnerPartId=-1|Style=4|ShowNetName=T|Location.X=425|Location.Y=830|Orientation=3|Color=128|FontID=1|Text=GND
|RECORD=27|IndexInSheet=426|OwnerPartId=-1|LineWidth=1|Color=8388608|LocationCount=2|X1=425|Y1=830|X2=425|Y2=840
|RECORD=1|LibReference=RES|PartCount=2|DisplayModeCount=2|IndexInSheet=427|OwnerPartId=-1|Location.X=1005|Location.Y=185|Orientation=1|CurrentPartId=1|SourceLibraryName=Altium Content Vault|TargetFileName=*|AreaColor=11599871|Color=128|PartIDLocked=F|DesignItemId=CMP-2002-05402-1|AllPinCount=2
|RECORD=2|OwnerIndex=4567|OwnerPartId=1|OwnerPartDisplayMode=1|FormalType=1|Electrical=4|PinConglomerate=33|PinLength=10|Location.X=1015|Location.Y=205|Name=2|Designator=2|PinPropagationDelay=0.000000E+000
|RECORD=2|OwnerIndex=4567|OwnerPartId=1|OwnerPartDisplayMode=1|FormalType=1|Electrical=4|PinConglomerate=35|PinLength=10|Location.X=1015|Location.Y=185|Name=1|Designator=1|PinPropagationDelay=0.000000E+000
|RECORD=14|OwnerIndex=4567|IsNotAccesible=T|IndexInSheet=2|OwnerPartId=1|OwnerPartDisplayMode=1|Location.X=1011|Location.Y=185|Corner.X=1019|Corner.Y=205|LineWidth=1|Color=16711680|AreaColor=11599871
|RECORD=2|OwnerIndex=4567|OwnerPartId=1|FormalType=1|Electrical=4|PinConglomerate=33|PinLength=10|Location.X=1015|Location.Y=205|Name=2|Designator=2|PinPropagationDelay=0.000000E+000
|RECORD=2|OwnerIndex=4567|OwnerPartId=1|FormalType=1|Electrical=4|PinConglomerate=35|PinLength=10|Location.X=1015|Location.Y=185|Name=1|Designator=1|PinPropagationDelay=0.000000E+000
|RECORD=6|OwnerIndex=4567|IsNotAccesible=T|IndexInSheet=5|OwnerPartId=1|LineWidth=1|Color=16711680|LocationCount=10|X1=1015|Y1=205|X2=1015|Y2=201|X3=1017|Y3=200|X4=1013|Y4=198|X5=1017|Y5=196|X6=1013|Y6=194|X7=1017|Y7=192|X8=1013|Y8=190|X9=1015|Y9=189|X10=1015|Y10=185
|RECORD=41|OwnerIndex=4567|IndexInSheet=6|OwnerPartId=-1|Location.X=1012|Location.Y=217|Color=8388608|FontID=1|IsHidden=T|Text=CR0402-FX-7870GLF|Name=Part Number
|RECORD=41|OwnerIndex=4567|IndexInSheet=7|OwnerPartId=-1|Location.X=1012|Location.Y=217|Color=8388608|FontID=1|IsHidden=T|Text=Bourns|Name=Manufacturer
|RECORD=34|OwnerIndex=4567|IndexInSheet=-1|OwnerPartId=-1|Location.X=1018|Location.Y=196|Color=8388608|FontID=1|Text=R78|Name=Designator|ReadOnlyState=1
|RECORD=41|OwnerIndex=4567|IndexInSheet=-1|OwnerPartId=-1|Location.X=1018|Location.Y=186|Color=8388608|FontID=1|Text=787_1%_0402|Name=Comment
|RECORD=44|OwnerIndex=4567
|RECORD=45|OwnerIndex=4582|IndexInSheet=-1|Description=Chip Resistor, 2-Leads, Body 1.00x0.50mm, IPC Medium Density|UseComponentLibrary=T|ModelName=RESC1005X40X25NL10T10|ModelType=PCBLIB|IsCurrent=T|DatalinksLocked=T|DatabaseDatalinksLocked=T
|RECORD=46|OwnerIndex=4583
|RECORD=48|OwnerIndex=4583
|RECORD=41|OwnerIndex=4585|IndexInSheet=-1|OwnerPartId=-1|Color=8388608|FontID=1|IsHidden=T|Text=2D|Name=Available Preview Images
|RECORD=45|OwnerIndex=4582|IndexInSheet=-1|Description=Chip Resistor, 2-Leads, Body 1.00x0.50mm, IPC Low Density|UseComponentLibrary=T|ModelName=RESC1005X40X25ML10T10|ModelType=PCBLIB|DatalinksLocked=T|DatabaseDatalinksLocked=T
|RECORD=46|OwnerIndex=4587
|RECORD=48|OwnerIndex=4587
|RECORD=41|OwnerIndex=4589|IndexInSheet=-1|OwnerPartId=-1|Color=8388608|FontID=1|IsHidden=T|Text=2D|Name=Available Preview Images
|RECORD=45|OwnerIndex=4582|IndexInSheet=-1|Description=Chip Resistor, 2-Leads, Body 1.00x0.50mm, IPC High Density|UseComponentLibrary=T|ModelName=RESC1005X40X25LL10T10|ModelType=PCBLIB|DatalinksLocked=T|DatabaseDatalinksLocked=T
|RECORD=46|OwnerIndex=4591
|RECORD=48|OwnerIndex=4591
|RECORD=41|OwnerIndex=4593|IndexInSheet=-1|OwnerPartId=-1|Color=8388608|FontID=1|IsHidden=T|Text=2D|Name=Available Preview Images
|RECORD=29|IndexInSheet=-1|OwnerPartId=-1|Location.X=170|Location.Y=910|Color=128
|RECORD=29|IndexInSheet=-1|OwnerPartId=-1|Location.X=200|Location.Y=755|Color=128
|RECORD=29|IndexInSheet=-1|OwnerPartId=-1|Location.X=210|Location.Y=1000|Color=128
|RECORD=29|IndexInSheet=-1|OwnerPartId=-1|Location.X=240|Location.Y=755|Color=128
|RECORD=29|IndexInSheet=-1|OwnerPartId=-1|Location.X=285|Location.Y=915|Color=128
|RECORD=29|IndexInSheet=-1|OwnerPartId=-1|Location.X=285|Location.Y=955|Color=128
|RECORD=29|IndexInSheet=-1|OwnerPartId=-1|Location.X=405|Location.Y=915|Color=128
|RECORD=29|IndexInSheet=-1|OwnerPartId=-1|Location.X=405|Location.Y=955|Color=128
|RECORD=29|IndexInSheet=-1|OwnerPartId=-1|Location.X=425|Location.Y=915|Color=128
|RECORD=29|IndexInSheet=-1|OwnerPartId=-1|Location.X=475|Location.Y=250|Color=128
|RECORD=29|IndexInSheet=-1|OwnerPartId=-1|Location.X=475|Location.Y=335|Color=128
|RECORD=29|IndexInSheet=-1|OwnerPartId=-1|Location.X=480|Location.Y=685|Color=128
|RECORD=29|IndexInSheet=-1|OwnerPartId=-1|Location.X=485|Location.Y=335|Color=128
|RECORD=29|IndexInSheet=-1|OwnerPartId=-1|Location.X=485|Location.Y=415|Color=128
|RECORD=29|IndexInSheet=-1|OwnerPartId=-1|Location.X=485|Location.Y=525|Color=128
|RECORD=29|IndexInSheet=-1|OwnerPartId=-1|Location.X=505|Location.Y=335|Color=128
|RECORD=29|IndexInSheet=-1|OwnerPartId=-1|Location.X=515|Location.Y=250|Color=128
|RECORD=29|IndexInSheet=-1|OwnerPartId=-1|Location.X=550|Location.Y=165|Color=128
|RECORD=29|IndexInSheet=-1|OwnerPartId=-1|Location.X=552|Location.Y=915|Color=128
|RECORD=29|IndexInSheet=-1|OwnerPartId=-1|Location.X=565|Location.Y=335|Color=128
|RECORD=29|IndexInSheet=-1|OwnerPartId=-1|Location.X=575|Location.Y=705|Color=128
|RECORD=29|IndexInSheet=-1|OwnerPartId=-1|Location.X=590|Location.Y=165|Color=128
|RECORD=29|IndexInSheet=-1|OwnerPartId=-1|Location.X=600|Location.Y=837|Color=128
|RECORD=29|IndexInSheet=-1|OwnerPartId=-1|Location.X=602|Location.Y=917|Color=128
|RECORD=29|IndexInSheet=-1|OwnerPartId=-1|Location.X=605|Location.Y=250|Color=128
|RECORD=29|IndexInSheet=-1|OwnerPartId=-1|Location.X=605|Location.Y=270|Color=128
|RECORD=29|IndexInSheet=-1|OwnerPartId=-1|Location.X=610|Location.Y=365|Color=128
|RECORD=29|IndexInSheet=-1|OwnerPartId=-1|Location.X=610|Location.Y=375|Color=128
|RECORD=29|IndexInSheet=-1|OwnerPartId=-1|Location.X=610|Location.Y=385|Color=128
|RECORD=29|IndexInSheet=-1|OwnerPartId=-1|Location.X=610|Location.Y=395|Color=128
|RECORD=29|IndexInSheet=-1|OwnerPartId=-1|Location.X=610|Location.Y=405|Color=128
|RECORD=29|IndexInSheet=-1|OwnerPartId=-1|Location.X=610|Location.Y=415|Color=128
|RECORD=29|IndexInSheet=-1|OwnerPartId=-1|Location.X=740|Location.Y=770|Color=128
|RECORD=29|IndexInSheet=-1|OwnerPartId=-1|Location.X=740|Location.Y=855|Color=128
|RECORD=29|IndexInSheet=-1|OwnerPartId=-1|Location.X=750|Location.Y=855|Color=128
|RECORD=29|IndexInSheet=-1|OwnerPartId=-1|Location.X=750|Location.Y=935|Color=128
|RECORD=29|IndexInSheet=-1|OwnerPartId=-1|Location.X=750|Location.Y=1045|Color=128
|RECORD=29|IndexInSheet=-1|OwnerPartId=-1|Location.X=770|Location.Y=855|Color=128
|RECORD=29|IndexInSheet=-1|OwnerPartId=-1|Location.X=780|Location.Y=770|Color=128
|RECORD=29|IndexInSheet=-1|OwnerPartId=-1|Location.X=790|Location.Y=375|Color=128
|RECORD=29|IndexInSheet=-1|OwnerPartId=-1|Location.X=790|Location.Y=385|Color=128
|RECORD=29|IndexInSheet=-1|OwnerPartId=-1|Location.X=790|Location.Y=395|Color=128
|RECORD=29|IndexInSheet=-1|OwnerPartId=-1|Location.X=790|Location.Y=405|Color=128
|RECORD=29|IndexInSheet=-1|OwnerPartId=-1|Location.X=790|Location.Y=415|Color=128
|RECORD=29|IndexInSheet=-1|OwnerPartId=-1|Location.X=815|Location.Y=685|Color=128
|RECORD=29|IndexInSheet=-1|OwnerPartId=-1|Location.X=820|Location.Y=375|Color=128
|RECORD=29|IndexInSheet=-1|OwnerPartId=-1|Location.X=830|Location.Y=95|Color=128
|RECORD=29|IndexInSheet=-1|OwnerPartId=-1|Location.X=830|Location.Y=375|Color=128
|RECORD=29|IndexInSheet=-1|OwnerPartId=-1|Location.X=830|Location.Y=855|Color=128
|RECORD=29|IndexInSheet=-1|OwnerPartId=-1|Location.X=855|Location.Y=685|Color=128
|RECORD=29|IndexInSheet=-1|OwnerPartId=-1|Location.X=870|Location.Y=770|Color=128
|RECORD=29|IndexInSheet=-1|OwnerPartId=-1|Location.X=870|Location.Y=790|Color=128
|RECORD=29|IndexInSheet=-1|OwnerPartId=-1|Location.X=875|Location.Y=885|Color=128
|RECORD=29|IndexInSheet=-1|OwnerPartId=-1|Location.X=875|Location.Y=895|Color=128
|RECORD=29|IndexInSheet=-1|OwnerPartId=-1|Location.X=875|Location.Y=905|Color=128
|RECORD=29|IndexInSheet=-1|OwnerPartId=-1|Location.X=875|Location.Y=915|Color=128
|RECORD=29|IndexInSheet=-1|OwnerPartId=-1|Location.X=875|Location.Y=925|Color=128
|RECORD=29|IndexInSheet=-1|OwnerPartId=-1|Location.X=875|Location.Y=935|Color=128
|RECORD=29|IndexInSheet=-1|OwnerPartId=-1|Location.X=895|Location.Y=405|Color=128
|RECORD=29|IndexInSheet=-1|OwnerPartId=-1|Location.X=915|Location.Y=455|Color=128
|RECORD=29|IndexInSheet=-1|OwnerPartId=-1|Location.X=925|Location.Y=225|Color=128
|RECORD=29|IndexInSheet=-1|OwnerPartId=-1|Location.X=925|Location.Y=375|Color=128
|RECORD=29|IndexInSheet=-1|OwnerPartId=-1|Location.X=1015|Location.Y=225|Color=128
|RECORD=29|IndexInSheet=-1|OwnerPartId=-1|Location.X=1015|Location.Y=260|Color=128
|RECORD=29|IndexInSheet=-1|OwnerPartId=-1|Location.X=1015|Location.Y=345|Color=128
|RECORD=29|IndexInSheet=-1|OwnerPartId=-1|Location.X=1015|Location.Y=375|Color=128
|RECORD=29|IndexInSheet=-1|OwnerPartId=-1|Location.X=1055|Location.Y=895|Color=128
|RECORD=29|IndexInSheet=-1|OwnerPartId=-1|Location.X=1055|Location.Y=905|Color=128
|RECORD=29|IndexInSheet=-1|OwnerPartId=-1|Location.X=1055|Location.Y=915|Color=128
|RECORD=29|IndexInSheet=-1|OwnerPartId=-1|Location.X=1055|Location.Y=925|Color=128
|RECORD=29|IndexInSheet=-1|OwnerPartId=-1|Location.X=1055|Location.Y=935|Color=128
|RECORD=29|IndexInSheet=-1|OwnerPartId=-1|Location.X=1080|Location.Y=185|Color=128
|RECORD=29|IndexInSheet=-1|OwnerPartId=-1|Location.X=1080|Location.Y=265|Color=128
|RECORD=29|IndexInSheet=-1|OwnerPartId=-1|Location.X=1080|Location.Y=375|Color=128
|RECORD=29|IndexInSheet=-1|OwnerPartId=-1|Location.X=1085|Location.Y=895|Color=128
|RECORD=29|IndexInSheet=-1|OwnerPartId=-1|Location.X=1095|Location.Y=615|Color=128
|RECORD=29|IndexInSheet=-1|OwnerPartId=-1|Location.X=1095|Location.Y=895|Color=128
|RECORD=29|IndexInSheet=-1|OwnerPartId=-1|Location.X=1125|Location.Y=185|Color=128
|RECORD=29|IndexInSheet=-1|OwnerPartId=-1|Location.X=1125|Location.Y=265|Color=128
|RECORD=29|IndexInSheet=-1|OwnerPartId=-1|Location.X=1160|Location.Y=925|Color=128
|RECORD=29|IndexInSheet=-1|OwnerPartId=-1|Location.X=1165|Location.Y=185|Color=128
|RECORD=29|IndexInSheet=-1|OwnerPartId=-1|Location.X=1165|Location.Y=265|Color=128
|RECORD=29|IndexInSheet=-1|OwnerPartId=-1|Location.X=1180|Location.Y=975|Color=128
|RECORD=29|IndexInSheet=-1|OwnerPartId=-1|Location.X=1190|Location.Y=745|Color=128
|RECORD=29|IndexInSheet=-1|OwnerPartId=-1|Location.X=1190|Location.Y=895|Color=128
|RECORD=29|IndexInSheet=-1|OwnerPartId=-1|Location.X=1200|Location.Y=335|Color=128
|RECORD=29|IndexInSheet=-1|OwnerPartId=-1|Location.X=1200|Location.Y=355|Color=128
|RECORD=29|IndexInSheet=-1|OwnerPartId=-1|Location.X=1200|Location.Y=365|Color=128
|RECORD=29|IndexInSheet=-1|OwnerPartId=-1|Location.X=1200|Location.Y=375|Color=128
|RECORD=29|IndexInSheet=-1|OwnerPartId=-1|Location.X=1200|Location.Y=385|Color=128
|RECORD=29|IndexInSheet=-1|OwnerPartId=-1|Location.X=1200|Location.Y=395|Color=128
|RECORD=29|IndexInSheet=-1|OwnerPartId=-1|Location.X=1210|Location.Y=185|Color=128
|RECORD=29|IndexInSheet=-1|OwnerPartId=-1|Location.X=1210|Location.Y=265|Color=128
|RECORD=29|IndexInSheet=-1|OwnerPartId=-1|Location.X=1255|Location.Y=185|Color=128
|RECORD=29|IndexInSheet=-1|OwnerPartId=-1|Location.X=1255|Location.Y=265|Color=128
|RECORD=29|IndexInSheet=-1|OwnerPartId=-1|Location.X=1280|Location.Y=745|Color=128
|RECORD=29|IndexInSheet=-1|OwnerPartId=-1|Location.X=1280|Location.Y=780|Color=128
|RECORD=29|IndexInSheet=-1|OwnerPartId=-1|Location.X=1280|Location.Y=865|Color=128
|RECORD=29|IndexInSheet=-1|OwnerPartId=-1|Location.X=1280|Location.Y=895|Color=128
|RECORD=29|IndexInSheet=-1|OwnerPartId=-1|Location.X=1345|Location.Y=705|Color=128
|RECORD=29|IndexInSheet=-1|OwnerPartId=-1|Location.X=1345|Location.Y=785|Color=128
|RECORD=29|IndexInSheet=-1|OwnerPartId=-1|Location.X=1345|Location.Y=895|Color=128
|RECORD=29|IndexInSheet=-1|OwnerPartId=-1|Location.X=1390|Location.Y=705|Color=128
|RECORD=29|IndexInSheet=-1|OwnerPartId=-1|Location.X=1390|Location.Y=785|Color=128
|RECORD=29|IndexInSheet=-1|OwnerPartId=-1|Location.X=1430|Location.Y=705|Color=128
|RECORD=29|IndexInSheet=-1|OwnerPartId=-1|Location.X=1430|Location.Y=785|Color=128
|RECORD=29|IndexInSheet=-1|OwnerPartId=-1|Location.X=1475|Location.Y=705|Color=128
|RECORD=29|IndexInSheet=-1|OwnerPartId=-1|Location.X=1475|Location.Y=785|Color=128
|RECORD=29|IndexInSheet=-1|OwnerPartId=-1|Location.X=1520|Location.Y=705|Color=128
|RECORD=29|IndexInSheet=-1|OwnerPartId=-1|Location.X=1520|Location.Y=785|Color=128
|RECORD=29|IndexInSheet=-1|OwnerPartId=-1|Location.X=1530|Location.Y=855|Color=128
|RECORD=29|IndexInSheet=-1|OwnerPartId=-1|Location.X=1530|Location.Y=875|Color=128
|RECORD=29|IndexInSheet=-1|OwnerPartId=-1|Location.X=1530|Location.Y=885|Color=128
|RECORD=29|IndexInSheet=-1|OwnerPartId=-1|Location.X=1530|Location.Y=895|Color=128
|RECORD=29|IndexInSheet=-1|OwnerPartId=-1|Location.X=1530|Location.Y=905|Color=128
|RECORD=29|IndexInSheet=-1|OwnerPartId=-1|Location.X=1530|Location.Y=915|Color=128